(kicad_pcb
	(version 20241229)
	(generator "pcbnew")
	(generator_version "9.0")
	(general
		(thickness 1.6)
		(legacy_teardrops no)
	)
	(paper "A4")
	(title_block
		(title "OCuLink to PCIe adapter")
		(date "2025-06-18")
		(rev "1.0.0")
		(company "Antmicro Ltd")
		(comment 1 "www.antmicro.com")
	)
	(layers
		(0 "F.Cu" signal)
		(4 "In1.Cu" signal)
		(6 "In2.Cu" signal)
		(2 "B.Cu" signal)
		(9 "F.Adhes" user "F.Adhesive")
		(11 "B.Adhes" user "B.Adhesive")
		(13 "F.Paste" user)
		(15 "B.Paste" user)
		(5 "F.SilkS" user "F.Silkscreen")
		(7 "B.SilkS" user "B.Silkscreen")
		(1 "F.Mask" user)
		(3 "B.Mask" user)
		(17 "Dwgs.User" user "User.Drawings")
		(19 "Cmts.User" user "User.Comments")
		(21 "Eco1.User" user "User.Eco1")
		(23 "Eco2.User" user "User.Eco2")
		(25 "Edge.Cuts" user)
		(27 "Margin" user)
		(31 "F.CrtYd" user "F.Courtyard")
		(29 "B.CrtYd" user "B.Courtyard")
		(35 "F.Fab" user)
		(33 "B.Fab" user)
	)
	(setup
		(stackup
			(layer "F.SilkS"
				(type "Top Silk Screen")
				(color "White")
			)
			(layer "F.Paste"
				(type "Top Solder Paste")
			)
			(layer "F.Mask"
				(type "Top Solder Mask")
				(color "Black")
				(thickness 0.01)
			)
			(layer "F.Cu"
				(type "copper")
				(thickness 0.035)
			)
			(layer "dielectric 1"
				(type "prepreg")
				(thickness 0.12)
				(material "FR4")
				(epsilon_r 4.5)
				(loss_tangent 0.02)
			)
			(layer "In1.Cu"
				(type "copper")
				(thickness 0.035)
			)
			(layer "dielectric 2"
				(type "core")
				(thickness 1.2)
				(material "FR4")
				(epsilon_r 4.5)
				(loss_tangent 0.02)
			)
			(layer "In2.Cu"
				(type "copper")
				(thickness 0.035)
			)
			(layer "dielectric 3"
				(type "prepreg")
				(thickness 0.12)
				(material "FR4")
				(epsilon_r 4.5)
				(loss_tangent 0.02)
			)
			(layer "B.Cu"
				(type "copper")
				(thickness 0.035)
			)
			(layer "B.Mask"
				(type "Bottom Solder Mask")
				(color "Black")
				(thickness 0.01)
			)
			(layer "B.Paste"
				(type "Bottom Solder Paste")
			)
			(layer "B.SilkS"
				(type "Bottom Silk Screen")
				(color "White")
			)
			(copper_finish "None")
			(dielectric_constraints yes)
		)
		(pad_to_mask_clearance 0)
		(allow_soldermask_bridges_in_footprints no)
		(tenting front back)
		(grid_origin 101.6 166)
		(pcbplotparams
			(layerselection 0x00000000_00000000_55555555_5755f5ff)
			(plot_on_all_layers_selection 0x00000000_00000000_00000000_00000000)
			(disableapertmacros no)
			(usegerberextensions no)
			(usegerberattributes yes)
			(usegerberadvancedattributes yes)
			(creategerberjobfile yes)
			(dashed_line_dash_ratio 12.000000)
			(dashed_line_gap_ratio 3.000000)
			(svgprecision 4)
			(plotframeref no)
			(mode 1)
			(useauxorigin no)
			(hpglpennumber 1)
			(hpglpenspeed 20)
			(hpglpendiameter 15.000000)
			(pdf_front_fp_property_popups yes)
			(pdf_back_fp_property_popups yes)
			(pdf_metadata yes)
			(pdf_single_document no)
			(dxfpolygonmode yes)
			(dxfimperialunits yes)
			(dxfusepcbnewfont yes)
			(psnegative no)
			(psa4output no)
			(plot_black_and_white yes)
			(sketchpadsonfab no)
			(plotpadnumbers no)
			(hidednponfab no)
			(sketchdnponfab yes)
			(crossoutdnponfab yes)
			(subtractmaskfromsilk no)
			(outputformat 1)
			(mirror no)
			(drillshape 1)
			(scaleselection 1)
			(outputdirectory "")
		)
	)
	(net 0 "")
	(net 1 "unconnected-(J2-PadA36)")
	(net 2 "unconnected-(J2-PadA50)")
	(net 3 "unconnected-(J2-PadA64)")
	(net 4 "unconnected-(J2-PadB70)")
	(net 5 "unconnected-(J2-PadB33)")
	(net 6 "unconnected-(J2-PadA65)")
	(net 7 "unconnected-(J2-PadB17)")
	(net 8 "unconnected-(J2-PadA72)")
	(net 9 "unconnected-(J2-PadB55)")
	(net 10 "unconnected-(J2-PadB31)")
	(net 11 "unconnected-(J2-PadB38)")
	(net 12 "unconnected-(J2-PadA48)")
	(net 13 "unconnected-(J2-PadA76)")
	(net 14 "unconnected-(J2-PadA39)")
	(net 15 "unconnected-(J2-PadB46)")
	(net 16 "unconnected-(J2-PadA47)")
	(net 17 "unconnected-(J2-PadB62)")
	(net 18 "unconnected-(J2-PadA60)")
	(net 19 "unconnected-(J2-PadA6)")
	(net 20 "unconnected-(J2-PadA69)")
	(net 21 "unconnected-(J2-PadA8)")
	(net 22 "unconnected-(J2-PadB74)")
	(net 23 "unconnected-(J2-PadA68)")
	(net 24 "unconnected-(J2-PadA5)")
	(net 25 "unconnected-(J2-PadB81)")
	(net 26 "unconnected-(J2-PadA52)")
	(net 27 "unconnected-(J2-PadA32)")
	(net 28 "unconnected-(J2-PadB82)")
	(net 29 "unconnected-(J2-PadA53)")
	(net 30 "unconnected-(J2-PadA61)")
	(net 31 "unconnected-(J2-PadB51)")
	(net 32 "unconnected-(J2-PadA80)")
	(net 33 "unconnected-(J2-PadB54)")
	(net 34 "unconnected-(J2-PadB66)")
	(net 35 "unconnected-(J2-PadB50)")
	(net 36 "unconnected-(J2-PadA19)")
	(net 37 "unconnected-(J2-PadA57)")
	(net 38 "unconnected-(J2-PadB12)")
	(net 39 "unconnected-(J2-PadA43)")
	(net 40 "unconnected-(J2-PadA56)")
	(net 41 "unconnected-(J2-PadB34)")
	(net 42 "unconnected-(J2-PadB71)")
	(net 43 "unconnected-(J2-PadB48)")
	(net 44 "unconnected-(J2-PadB37)")
	(net 45 "unconnected-(J2-PadA77)")
	(net 46 "unconnected-(J2-PadB41)")
	(net 47 "unconnected-(J2-PadA81)")
	(net 48 "unconnected-(J2-PadB78)")
	(net 49 "unconnected-(J2-PadA33)")
	(net 50 "unconnected-(J2-PadB9)")
	(net 51 "unconnected-(J2-PadB63)")
	(net 52 "unconnected-(J2-PadB67)")
	(net 53 "unconnected-(J2-PadA44)")
	(net 54 "unconnected-(J2-PadB30)")
	(net 55 "unconnected-(J2-PadA1)")
	(net 56 "unconnected-(J2-PadB58)")
	(net 57 "unconnected-(J2-PadA7)")
	(net 58 "unconnected-(J2-PadB42)")
	(net 59 "unconnected-(J2-PadA73)")
	(net 60 "unconnected-(J2-PadB75)")
	(net 61 "unconnected-(J2-PadB79)")
	(net 62 "unconnected-(J2-PadA35)")
	(net 63 "unconnected-(J2-PadB59)")
	(net 64 "unconnected-(J2-PadA40)")
	(net 65 "unconnected-(J2-PadB45)")
	(net 66 "GND")
	(net 67 "/OCuLink/PCIe_{x4}.RX3-")
	(net 68 "/OCuLink/PCIe_{x4}.RX3+")
	(net 69 "/OCuLink/PCIe_{x4}.TX1-")
	(net 70 "/OCuLink/PCIe_{x4}.TX2+")
	(net 71 "/OCuLink/PCIe_{x4}.RX1-")
	(net 72 "/OCuLink/PCIe_{x4}.TX0+")
	(net 73 "/OCuLink/PCIe_{x4}.RX0-")
	(net 74 "/OCuLink/PCIe_{x4}.TX0-")
	(net 75 "/OCuLink/PCIe_{x4}.RX1+")
	(net 76 "/OCuLink/PCIe_{x4}.TX2-")
	(net 77 "/OCuLink/PCIe_{x4}.TX1+")
	(net 78 "/OCuLink/PCIe_{x4}.RX0+")
	(net 79 "/OCuLink/PCIe_{x4}.RX2-")
	(net 80 "/OCuLink/PCIe_{x4}.TX3-")
	(net 81 "/OCuLink/PCIe_{x4}.RX2+")
	(net 82 "/OCuLink/PCIe_{x4}.TX3+")
	(net 83 "/PCIe-connector/3V3_PCIe_AUX")
	(net 84 "Net-(Q6-G)")
	(net 85 "/Power/3V3_BST")
	(net 86 "/Power/3V3_SW")
	(net 87 "+12V")
	(net 88 "/Power/3V3_VCC")
	(net 89 "Net-(D1-C)")
	(net 90 "Net-(D2-C)")
	(net 91 "Net-(D3-C)")
	(net 92 "unconnected-(J1-V_{ACT}_RX_3V3-PadA1)")
	(net 93 "/OCuLink/~{WAKE}")
	(net 94 "unconnected-(J1-V_{ACT}_TX_3V3-PadB21)")
	(net 95 "/OCuLink/I2C0C_SDA")
	(net 96 "/OCuLink/PCIe_{REF0}.CK+")
	(net 97 "/OCuLink/PCIe_{REF0}.CK-")
	(net 98 "unconnected-(J1-5V-PadA21)")
	(net 99 "/OCuLink/~{CPRSNT}")
	(net 100 "unconnected-(J1-5V-PadA21)_1")
	(net 101 "/OCuLink/I2C0C_SCL")
	(net 102 "/OCuLink/I2C0.SCL")
	(net 103 "/OCuLink/I2C0.SDA")
	(net 104 "Net-(Q1-G)")
	(net 105 "/Power/3V3_PG")
	(net 106 "/Power/3V3_EN")
	(net 107 "/Power/3V3_MODE")
	(net 108 "/Power/3V3_FB")
	(net 109 "unconnected-(U1-NC-Pad16)")
	(net 110 "unconnected-(U1-NC-Pad10)")
	(net 111 "unconnected-(U1-SS-Pad11)")
	(net 112 "unconnected-(J1-NC-PadB9)")
	(net 113 "VBUS")
	(net 114 "/USB-PD/VCCD_1V8")
	(net 115 "/USB-PD/VCC")
	(net 116 "/Power/Ideal-diode-2/VIN")
	(net 117 "/USB-PD/VDDD_3V3")
	(net 118 "/Power/Ideal-diode-1/VIN")
	(net 119 "/Power/VCC_PD")
	(net 120 "Net-(C27-Pad2)")
	(net 121 "/USB-PD/12V_VDD")
	(net 122 "/USB-PD/12V_BOOT")
	(net 123 "/USB-PD/12V_VDRV")
	(net 124 "/USB-PD/FAULT")
	(net 125 "/USB-PD/12V_SS")
	(net 126 "unconnected-(J3-D_{A}--PadA7)")
	(net 127 "unconnected-(J3-D_{B}+-PadB6)")
	(net 128 "unconnected-(J3-D_{A}+-PadA6)")
	(net 129 "unconnected-(J3-D_{B}--PadB7)")
	(net 130 "unconnected-(J3-SBU_{1}-PadA8)")
	(net 131 "unconnected-(J3-SBU_{2}-PadB8)")
	(net 132 "unconnected-(D14-Pad1)")
	(net 133 "/USB-PD/VBUS_MIN")
	(net 134 "+3V3")
	(net 135 "/USB-PD/FLIP")
	(net 136 "/USB-PD/VBUS_MAX")
	(net 137 "/USB-PD/ISNK_FINE")
	(net 138 "/USB-PD/ISNK_COARSE")
	(net 139 "/USB-PD/CC2")
	(net 140 "/USB-PD/CC1")
	(net 141 "/USB-PD/SDA")
	(net 142 "/USB-PD/SCL")
	(net 143 "/USB-PD/12V_SW")
	(net 144 "/USB-PD/~{HPI_INT}")
	(net 145 "/USB-PD/GPIO_1")
	(net 146 "unconnected-(U5-DNU2-Pad21)")
	(net 147 "unconnected-(U5-DNU1-Pad20)")
	(net 148 "unconnected-(U5-D--Pad16)")
	(net 149 "unconnected-(U9-NC-Pad18)")
	(net 150 "unconnected-(U9-GL-Pad15)")
	(net 151 "Net-(Q5-G)")
	(net 152 "unconnected-(U5-SAFE_PWR_EN-Pad4)")
	(net 153 "/USB-PD/12V_MODE")
	(net 154 "/USB-PD/VBUS_EN")
	(net 155 "/USB-PD/12V_ILIM")
	(net 156 "/USB-PD/12V_EN")
	(net 157 "/USB-PD/12V_FSW")
	(net 158 "/USB-PD/12V_PG")
	(net 159 "/USB-PD/12V_FB")
	(net 160 "unconnected-(U9-NC-Pad21)")
	(net 161 "Net-(Q3-D)")
	(net 162 "unconnected-(U3-STAT-Pad4)")
	(net 163 "unconnected-(U4-STAT-Pad4)")
	(net 164 "unconnected-(U5-D+-Pad17)")
	(net 165 "Net-(D4-C_{G})")
	(net 166 "unconnected-(D4-C_{B}-Pad3)")
	(net 167 "Net-(D4-C_{R})")
	(net 168 "/Power/VCC_DC_CONN_1")
	(net 169 "/Power/VCC_DC_CONN_2")
	(net 170 "/OCuLink/PCIe_{REF0}_R.CK+")
	(net 171 "/OCuLink/PCIe_{REF0}_R.CK-")
	(net 172 "/Power/~{PERST}")
	(net 173 "/USB-PD/~{FAULT}")
	(net 174 "Net-(Q4-D)")
	(net 175 "Net-(Q7-G)")
	(net 176 "Net-(Q8-D)")
	(net 177 "Net-(U6-2Y)")
	(net 178 "/PCIe-clock-generator/PCIe_{REF1}_R.CK+")
	(net 179 "/PCIe-clock-generator/PCIe_{REF1}_R.CK-")
	(net 180 "unconnected-(U2-STAT-Pad4)")
	(net 181 "/Power/PERST")
	(net 182 "/OCuLink/~{CPRSNTC}")
	(net 183 "/OCuLink/~{PERSTC}")
	(net 184 "/OCuLink/~{WAKEC}")
	(net 185 "/Power/~{PERST_CONN}")
	(net 186 "/Power/3V3_CONV")
	(net 187 "/USB-PD/12V_CONV")
	(net 188 "unconnected-(D14-Pad1)_1")
	(net 189 "unconnected-(U7-NC-Pad3)")
	(net 190 "unconnected-(U7-NC-Pad5)")
	(net 191 "unconnected-(U7-CLK0+-Pad11)")
	(net 192 "unconnected-(U7-NC-Pad6)")
	(net 193 "unconnected-(U7-NC-Pad14)")
	(net 194 "unconnected-(U7-CLK0--Pad10)")
	(net 195 "unconnected-(U7-NC-Pad2)")
	(net 196 "unconnected-(U7-NC-Pad7)")
	(net 197 "/PCIe-clock-generator/PCIe_{REF1}_R2.CK+")
	(net 198 "/PCIe-clock-generator/PCIe_{REF1}_R2.CK-")
	(footprint "antmicro-footprints:MOLEX_39288080"
		(layer "F.Cu")
		(at 150.85 141.4 90)
		(property "Reference" "J5"
			(at -3.35 -2.777 90)
			(layer "F.SilkS")
			(effects
				(font
					(size 0.7 0.7)
					(thickness 0.15)
				)
				(justify left bottom)
			)
		)
		(property "Value" "Molex_Mini-Fit-Jr_2x4_39-28-8080"
			(at 4.49 11.365 90)
			(layer "F.Fab")
			(effects
				(font
					(size 0.7 0.7)
					(thickness 0.15)
				)
				(justify left bottom)
			)
		)
		(property "Datasheet" "https://www.molex.com/pdm_docs/sd/039288080_sd.pdf"
			(at 0 0 90)
			(layer "F.Fab")
			(hide yes)
			(effects
				(font
					(size 1.27 1.27)
					(thickness 0.15)
				)
			)
		)
		(property "Description" "Pin Header, THT, Vertical, UL94V-2, Power, Wire-to-Board, 4.2 mm, 2 Rows, 8 Contacts, Mini-fit Jr, 5566 series"
			(at 0 0 90)
			(layer "F.Fab")
			(hide yes)
			(effects
				(font
					(size 1.27 1.27)
					(thickness 0.15)
				)
			)
		)
		(property "MPN" "39-28-8080"
			(at 0 0 90)
			(unlocked yes)
			(layer "F.Fab")
			(hide yes)
			(effects
				(font
					(size 1 1)
					(thickness 0.15)
				)
			)
		)
		(property "Manufacturer" "Molex"
			(at 0 0 90)
			(unlocked yes)
			(layer "F.Fab")
			(hide yes)
			(effects
				(font
					(size 1 1)
					(thickness 0.15)
				)
			)
		)
		(property "Author" "Antmicro"
			(at 0 0 90)
			(unlocked yes)
			(layer "F.Fab")
			(hide yes)
			(effects
				(font
					(size 1 1)
					(thickness 0.15)
				)
			)
		)
		(property "License" "Apache-2.0"
			(at 0 0 90)
			(unlocked yes)
			(layer "F.Fab")
			(hide yes)
			(effects
				(font
					(size 1 1)
					(thickness 0.15)
				)
			)
		)
		(sheetname "/")
		(sheetfile "oculink-to-pcie-adapter.kicad_sch")
		(attr through_hole)
		(fp_circle
			(center 12.6 0)
			(end 13.113 0)
			(stroke
				(width 1.0262)
				(type solid)
			)
			(fill no)
			(layer "F.Mask")
		)
		(fp_circle
			(center 8.4 0)
			(end 8.913 0)
			(stroke
				(width 1.0262)
				(type solid)
			)
			(fill no)
			(layer "F.Mask")
		)
		(fp_circle
			(center 4.2 0)
			(end 4.713 0)
			(stroke
				(width 1.0262)
				(type solid)
			)
			(fill no)
			(layer "F.Mask")
		)
		(fp_circle
			(center 12.6 5.5)
			(end 13.113 5.5)
			(stroke
				(width 1.0262)
				(type solid)
			)
			(fill no)
			(layer "F.Mask")
		)
		(fp_circle
			(center 8.4 5.5)
			(end 8.913 5.5)
			(stroke
				(width 1.0262)
				(type solid)
			)
			(fill no)
			(layer "F.Mask")
		)
		(fp_circle
			(center 4.2 5.5)
			(end 4.713 5.5)
			(stroke
				(width 1.0262)
				(type solid)
			)
			(fill no)
			(layer "F.Mask")
		)
		(fp_circle
			(center 0 5.5)
			(end 0.513 5.5)
			(stroke
				(width 1.0262)
				(type solid)
			)
			(fill no)
			(layer "F.Mask")
		)
		(fp_poly
			(pts
				(xy -1.026 -1.026) (xy 1.026 -1.026) (xy 1.026 1.026) (xy -1.026 1.026)
			)
			(stroke
				(width 0.01)
				(type solid)
			)
			(fill yes)
			(layer "F.Mask")
		)
		(fp_circle
			(center 12.6 0)
			(end 13.113 0)
			(stroke
				(width 1.0262)
				(type solid)
			)
			(fill no)
			(layer "B.Mask")
		)
		(fp_circle
			(center 8.4 0)
			(end 8.913 0)
			(stroke
				(width 1.0262)
				(type solid)
			)
			(fill no)
			(layer "B.Mask")
		)
		(fp_circle
			(center 4.2 0)
			(end 4.713 0)
			(stroke
				(width 1.0262)
				(type solid)
			)
			(fill no)
			(layer "B.Mask")
		)
		(fp_circle
			(center 12.6 5.5)
			(end 13.113 5.5)
			(stroke
				(width 1.0262)
				(type solid)
			)
			(fill no)
			(layer "B.Mask")
		)
		(fp_circle
			(center 8.4 5.5)
			(end 8.913 5.5)
			(stroke
				(width 1.0262)
				(type solid)
			)
			(fill no)
			(layer "B.Mask")
		)
		(fp_circle
			(center 4.2 5.5)
			(end 4.713 5.5)
			(stroke
				(width 1.0262)
				(type solid)
			)
			(fill no)
			(layer "B.Mask")
		)
		(fp_circle
			(center 0 5.5)
			(end 0.513 5.5)
			(stroke
				(width 1.0262)
				(type solid)
			)
			(fill no)
			(layer "B.Mask")
		)
		(fp_poly
			(pts
				(xy -1.026 -1.026) (xy 1.026 -1.026) (xy 1.026 1.026) (xy -1.026 1.026)
			)
			(stroke
				(width 0.01)
				(type solid)
			)
			(fill yes)
			(layer "B.Mask")
		)
		(fp_line
			(start 0.4 -3.327)
			(end -0.4 -3.327)
			(stroke
				(width 0.15)
				(type solid)
			)
			(layer "F.SilkS")
		)
		(fp_line
			(start -0.4 -3.327)
			(end 0 -2.627)
			(stroke
				(width 0.15)
				(type solid)
			)
			(layer "F.SilkS")
		)
		(fp_line
			(start 0 -2.627)
			(end 0.4 -3.327)
			(stroke
				(width 0.15)
				(type solid)
			)
			(layer "F.SilkS")
		)
		(fp_line
			(start 15.7 -2.25)
			(end 15.7 8.75)
			(stroke
				(width 0.15)
				(type solid)
			)
			(layer "F.SilkS")
		)
		(fp_line
			(start -1.83 -2.25)
			(end 15.7 -2.25)
			(stroke
				(width 0.15)
				(type solid)
			)
			(layer "F.SilkS")
		)
		(fp_line
			(start -1.83 -2.25)
			(end -3.1 -0.98)
			(stroke
				(width 0.15)
				(type solid)
			)
			(layer "F.SilkS")
		)
		(fp_line
			(start 15.7 8.75)
			(end -3.1 8.75)
			(stroke
				(width 0.15)
				(type solid)
			)
			(layer "F.SilkS")
		)
		(fp_line
			(start -3.1 8.75)
			(end -3.1 -0.98)
			(stroke
				(width 0.15)
				(type solid)
			)
			(layer "F.SilkS")
		)
		(fp_circle
			(center 0 -3)
			(end 0.05 -3)
			(stroke
				(width 0.15)
				(type solid)
			)
			(fill yes)
			(layer "F.SilkS")
		)
		(fp_rect
			(start -3.5 -2.7)
			(end 16.1 9.1)
			(stroke
				(width 0.05)
				(type solid)
			)
			(fill no)
			(layer "F.CrtYd")
		)
		(fp_line
			(start 0.4 -3.327)
			(end -0.4 -3.327)
			(stroke
				(width 0.15)
				(type solid)
			)
			(layer "F.Fab")
		)
		(fp_line
			(start -0.4 -3.327)
			(end 0 -2.627)
			(stroke
				(width 0.15)
				(type solid)
			)
			(layer "F.Fab")
		)
		(fp_line
			(start 0 -2.627)
			(end 0.4 -3.327)
			(stroke
				(width 0.15)
				(type solid)
			)
			(layer "F.Fab")
		)
		(fp_line
			(start 15.7 -2.25)
			(end 15.7 8.75)
			(stroke
				(width 0.15)
				(type solid)
			)
			(layer "F.Fab")
		)
		(fp_line
			(start -1.83 -2.25)
			(end 15.7 -2.25)
			(stroke
				(width 0.15)
				(type solid)
			)
			(layer "F.Fab")
		)
		(fp_line
			(start -1.83 -2.25)
			(end -3.1 -0.98)
			(stroke
				(width 0.15)
				(type solid)
			)
			(layer "F.Fab")
		)
		(fp_line
			(start 15.7 8.75)
			(end -3.1 8.75)
			(stroke
				(width 0.15)
				(type solid)
			)
			(layer "F.Fab")
		)
		(fp_line
			(start -3.1 8.75)
			(end -3.1 -0.98)
			(stroke
				(width 0.15)
				(type solid)
			)
			(layer "F.Fab")
		)
		(fp_text user "License: Apache-2.0"
			(at -3.5 14.565 90)
			(layer "F.Fab")
			(effects
				(font
					(size 0.7 0.7)
					(thickness 0.15)
				)
				(justify left bottom)
			)
		)
		(fp_text user "Author: Antmicro"
			(at -3.5 16.965 90)
			(layer "F.Fab")
			(effects
				(font
					(size 0.7 0.7)
					(thickness 0.15)
				)
				(justify left bottom)
			)
		)
		(fp_text user "${REFERENCE}"
			(at -3.5 15.765 90)
			(layer "F.Fab")
			(effects
				(font
					(size 0.7 0.7)
					(thickness 0.15)
				)
				(justify left bottom)
			)
		)
		(fp_text user "PTH D1.40 +/- 0.05"
			(at -3.5 13.365 90)
			(layer "F.Fab")
			(effects
				(font
					(size 0.7 0.7)
					(thickness 0.15)
				)
				(justify left bottom)
			)
		)
		(pad "1" thru_hole rect
			(at 0 0 90)
			(size 1.9 1.9)
			(drill 1.4)
			(layers "*.Cu")
			(remove_unused_layers no)
			(net 66 "GND")
			(pinfunction "1")
			(pintype "passive")
		)
		(pad "2" thru_hole circle
			(at 4.2 0 90)
			(size 1.9 1.9)
			(drill 1.4)
			(layers "*.Cu")
			(remove_unused_layers no)
			(net 66 "GND")
			(pinfunction "2")
			(pintype "passive")
		)
		(pad "3" thru_hole circle
			(at 8.4 0 90)
			(size 1.9 1.9)
			(drill 1.4)
			(layers "*.Cu")
			(remove_unused_layers no)
			(net 66 "GND")
			(pinfunction "3")
			(pintype "passive")
		)
		(pad "4" thru_hole circle
			(at 12.6 0 90)
			(size 1.9 1.9)
			(drill 1.4)
			(layers "*.Cu")
			(remove_unused_layers no)
			(net 66 "GND")
			(pinfunction "4")
			(pintype "passive")
		)
		(pad "5" thru_hole circle
			(at 0 5.5 90)
			(size 1.9 1.9)
			(drill 1.4)
			(layers "*.Cu")
			(remove_unused_layers no)
			(net 169 "/Power/VCC_DC_CONN_2")
			(pinfunction "5")
			(pintype "passive")
		)
		(pad "6" thru_hole circle
			(at 4.2 5.5 90)
			(size 1.9 1.9)
			(drill 1.4)
			(layers "*.Cu")
			(remove_unused_layers no)
			(net 169 "/Power/VCC_DC_CONN_2")
			(pinfunction "6")
			(pintype "passive")
		)
		(pad "7" thru_hole circle
			(at 8.4 5.5 90)
			(size 1.9 1.9)
			(drill 1.4)
			(layers "*.Cu")
			(remove_unused_layers no)
			(net 169 "/Power/VCC_DC_CONN_2")
			(pinfunction "7")
			(pintype "passive")
		)
		(pad "8" thru_hole circle
			(at 12.6 5.5 90)
			(size 1.9 1.9)
			(drill 1.4)
			(layers "*.Cu")
			(remove_unused_layers no)
			(net 169 "/Power/VCC_DC_CONN_2")
			(pinfunction "8")
			(pintype "passive")
		)
	)
	(footprint "antmicro-footprints:R_0402_1005Metric"
		(layer "F.Cu")
		(at 131.719999 153.999999)
		(descr "Resistor SMD 0402")
		(tags "resistor SMD 0402")
		(property "Reference" "R12"
			(at 1.08 0.500001 180)
			(layer "F.SilkS")
			(effects
				(font
					(size 0.7 0.7)
					(thickness 0.15)
				)
				(justify left bottom)
			)
		)
		(property "Value" "R_10k_0402"
			(at -1.011843 1.772046 0)
			(layer "F.Fab")
			(effects
				(font
					(size 0.7 0.7)
					(thickness 0.15)
				)
				(justify left bottom)
			)
		)
		(property "Datasheet" "https://www.bourns.com/docs/product-datasheets/cr.pdf"
			(at 0 0 0)
			(layer "F.Fab")
			(hide yes)
			(effects
				(font
					(size 1.27 1.27)
					(thickness 0.15)
				)
			)
		)
		(property "Description" "SMD Chip Resistor, 10 kohm, ± 1%, 62.5 mW, 0402 [1005 Metric], Thick Film, General Purpose"
			(at 0 0 0)
			(layer "F.Fab")
			(hide yes)
			(effects
				(font
					(size 1.27 1.27)
					(thickness 0.15)
				)
			)
		)
		(property "MPN" "CR0402-FX-1002GLF"
			(at 0 0 0)
			(unlocked yes)
			(layer "F.Fab")
			(hide yes)
			(effects
				(font
					(size 1 1)
					(thickness 0.15)
				)
			)
		)
		(property "Manufacturer" "Bourns"
			(at 0 0 0)
			(unlocked yes)
			(layer "F.Fab")
			(hide yes)
			(effects
				(font
					(size 1 1)
					(thickness 0.15)
				)
			)
		)
		(property "License" "Apache-2.0"
			(at 0 0 0)
			(unlocked yes)
			(layer "F.Fab")
			(hide yes)
			(effects
				(font
					(size 1 1)
					(thickness 0.15)
				)
			)
		)
		(property "Author" "Antmicro"
			(at 0 0 0)
			(unlocked yes)
			(layer "F.Fab")
			(hide yes)
			(effects
				(font
					(size 1 1)
					(thickness 0.15)
				)
			)
		)
		(property "Val" "10k"
			(at 0 0 0)
			(unlocked yes)
			(layer "F.Fab")
			(hide yes)
			(effects
				(font
					(size 1 1)
					(thickness 0.15)
				)
			)
		)
		(property "Tolerance" "1%"
			(at 0 0 0)
			(unlocked yes)
			(layer "F.Fab")
			(hide yes)
			(effects
				(font
					(size 1 1)
					(thickness 0.15)
				)
			)
		)
		(sheetname "/Power/")
		(sheetfile "power.kicad_sch")
		(attr smd)
		(fp_rect
			(start -0.925 -0.47)
			(end 0.925 0.47)
			(stroke
				(width 0.05)
				(type default)
			)
			(fill no)
			(layer "F.CrtYd")
		)
		(fp_rect
			(start -0.5 -0.25)
			(end 0.5 0.25)
			(stroke
				(width 0.15)
				(type solid)
			)
			(fill no)
			(layer "F.Fab")
		)
		(fp_text user "License: Apache-2.0"
			(at -0.949999 5.169 0)
			(layer "F.Fab")
			(effects
				(font
					(size 0.7 0.7)
					(thickness 0.15)
				)
				(justify left bottom)
			)
		)
		(fp_text user "Author: Antmicro"
			(at -0.95 4.169 0)
			(layer "F.Fab")
			(effects
				(font
					(size 0.7 0.7)
					(thickness 0.15)
				)
				(justify left bottom)
			)
		)
		(fp_text user "${REFERENCE}"
			(at 0 0 0)
			(layer "F.Fab")
			(effects
				(font
					(size 0.7 0.7)
					(thickness 0.15)
				)
				(justify left bottom)
			)
		)
		(pad "1" smd roundrect
			(at -0.48 0)
			(size 0.59 0.64)
			(layers "F.Cu" "F.Mask" "F.Paste")
			(roundrect_rratio 0.25)
			(net 66 "GND")
			(pintype "passive")
		)
		(pad "2" smd roundrect
			(at 0.48 0)
			(size 0.59 0.64)
			(layers "F.Cu" "F.Mask" "F.Paste")
			(roundrect_rratio 0.25)
			(net 89 "Net-(D1-C)")
			(pintype "passive")
		)
	)
	(footprint "antmicro-footprints:C_0805_2012Metric"
		(layer "F.Cu")
		(at 103.8 115.2 -90)
		(descr "Capacitor SMD 0805")
		(tags "capacitor SMD 0805")
		(property "Reference" "C37"
			(at -1.1 1.8 90)
			(layer "F.SilkS")
			(effects
				(font
					(size 0.7 0.7)
					(thickness 0.15)
				)
				(justify right top)
			)
		)
		(property "Value" "C_10u_0805_35V"
			(at -2.055717 1.963153 90)
			(layer "F.Fab")
			(effects
				(font
					(size 0.7 0.7)
					(thickness 0.15)
				)
				(justify right top)
			)
		)
		(property "Datasheet" "https://www.murata.com/products/productdetail?partno=GRM21BR6YA106KE43%23"
			(at 0 0 90)
			(layer "F.Fab")
			(hide yes)
			(effects
				(font
					(size 1.27 1.27)
					(thickness 0.15)
				)
			)
		)
		(property "Description" "SMD Multilayer Ceramic Capacitor, 10 µF, 35 V, 0805 [2012 Metric], ± 10%, X5R, GRM Series"
			(at 0 0 90)
			(layer "F.Fab")
			(hide yes)
			(effects
				(font
					(size 1.27 1.27)
					(thickness 0.15)
				)
			)
		)
		(property "MPN" "GRM21BR6YA106KE43L"
			(at 0 0 270)
			(unlocked yes)
			(layer "F.Fab")
			(hide yes)
			(effects
				(font
					(size 1 1)
					(thickness 0.15)
				)
			)
		)
		(property "Manufacturer" "Murata"
			(at 0 0 270)
			(unlocked yes)
			(layer "F.Fab")
			(hide yes)
			(effects
				(font
					(size 1 1)
					(thickness 0.15)
				)
			)
		)
		(property "License" "Apache-2.0"
			(at 0 0 270)
			(unlocked yes)
			(layer "F.Fab")
			(hide yes)
			(effects
				(font
					(size 1 1)
					(thickness 0.15)
				)
			)
		)
		(property "Author" "Antmicro"
			(at 0 0 270)
			(unlocked yes)
			(layer "F.Fab")
			(hide yes)
			(effects
				(font
					(size 1 1)
					(thickness 0.15)
				)
			)
		)
		(property "Val" "10u"
			(at 0 0 270)
			(unlocked yes)
			(layer "F.Fab")
			(hide yes)
			(effects
				(font
					(size 1 1)
					(thickness 0.15)
				)
			)
		)
		(property "Voltage" "35V"
			(at 0 0 270)
			(unlocked yes)
			(layer "F.Fab")
			(hide yes)
			(effects
				(font
					(size 1 1)
					(thickness 0.15)
				)
			)
		)
		(property "Dielectric" ""
			(at 0 0 270)
			(unlocked yes)
			(layer "F.Fab")
			(hide yes)
			(effects
				(font
					(size 1 1)
					(thickness 0.15)
				)
			)
		)
		(property "Public" "False"
			(at 0 0 270)
			(unlocked yes)
			(layer "F.Fab")
			(hide yes)
			(effects
				(font
					(size 1 1)
					(thickness 0.15)
				)
			)
		)
		(sheetname "/PCIe-connector/")
		(sheetfile "pcie-connector.kicad_sch")
		(attr smd)
		(fp_line
			(start -0.3 0.7)
			(end 0.3 0.7)
			(stroke
				(width 0.15)
				(type solid)
			)
			(layer "F.SilkS")
		)
		(fp_line
			(start -0.3 -0.7)
			(end 0.3 -0.7)
			(stroke
				(width 0.15)
				(type solid)
			)
			(layer "F.SilkS")
		)
		(fp_rect
			(start 1.95 -0.9)
			(end -1.95 0.9)
			(stroke
				(width 0.05)
				(type default)
			)
			(fill no)
			(layer "F.CrtYd")
		)
		(fp_rect
			(start -0.95 -0.675)
			(end 0.95 0.675)
			(stroke
				(width 0.15)
				(type solid)
			)
			(fill no)
			(layer "F.Fab")
		)
		(fp_text user "Author: Antmicro"
			(at -1.9 5.947 90)
			(layer "F.Fab")
			(effects
				(font
					(size 0.7 0.7)
					(thickness 0.15)
				)
				(justify right top)
			)
		)
		(fp_text user "License: Apache-2.0"
			(at -1.9 4.947 90)
			(layer "F.Fab")
			(effects
				(font
					(size 0.7 0.7)
					(thickness 0.15)
				)
				(justify right top)
			)
		)
		(fp_text user "${REFERENCE}"
			(at 0 0 90)
			(layer "F.Fab")
			(effects
				(font
					(size 0.7 0.7)
					(thickness 0.15)
				)
				(justify right top)
			)
		)
		(pad "1" smd roundrect
			(at -1.1 0 270)
			(size 1.2 1.3)
			(layers "F.Cu" "F.Mask" "F.Paste")
			(roundrect_rratio 0.25)
			(net 134 "+3V3")
			(pintype "passive")
		)
		(pad "2" smd roundrect
			(at 1.1 0 270)
			(size 1.2 1.3)
			(layers "F.Cu" "F.Mask" "F.Paste")
			(roundrect_rratio 0.25)
			(net 66 "GND")
			(pintype "passive")
		)
	)
	(footprint "antmicro-footprints:R_0402_1005Metric"
		(layer "F.Cu")
		(at 125.5 51.98 -90)
		(descr "Resistor SMD 0402")
		(tags "resistor SMD 0402")
		(property "Reference" "R52"
			(at -1.122484 -0.772697 90)
			(layer "F.SilkS")
			(effects
				(font
					(size 0.7 0.7)
					(thickness 0.15)
				)
				(justify right top)
			)
		)
		(property "Value" "R_0R_0402"
			(at -1.011843 1.772046 90)
			(layer "F.Fab")
			(effects
				(font
					(size 0.7 0.7)
					(thickness 0.15)
				)
				(justify right top)
			)
		)
		(property "Datasheet" "https://industrial.panasonic.com/cdbs/www-data/pdf/RDA0000/AOA0000C301.pdf"
			(at 0 0 90)
			(layer "F.Fab")
			(hide yes)
			(effects
				(font
					(size 1.27 1.27)
					(thickness 0.15)
				)
			)
		)
		(property "Description" "SMD Chip Resistor, Jumper, 0 ohm, 100 mW, 0402 [1005 Metric], Thick Film, General Purpose"
			(at 0 0 90)
			(layer "F.Fab")
			(hide yes)
			(effects
				(font
					(size 1.27 1.27)
					(thickness 0.15)
				)
			)
		)
		(property "MPN" "ERJ2GE0R00X"
			(at 0 0 270)
			(unlocked yes)
			(layer "F.Fab")
			(hide yes)
			(effects
				(font
					(size 1 1)
					(thickness 0.15)
				)
			)
		)
		(property "Manufacturer" "Panasonic"
			(at 0 0 270)
			(unlocked yes)
			(layer "F.Fab")
			(hide yes)
			(effects
				(font
					(size 1 1)
					(thickness 0.15)
				)
			)
		)
		(property "License" "Apache-2.0"
			(at 0 0 270)
			(unlocked yes)
			(layer "F.Fab")
			(hide yes)
			(effects
				(font
					(size 1 1)
					(thickness 0.15)
				)
			)
		)
		(property "Author" "Antmicro"
			(at 0 0 270)
			(unlocked yes)
			(layer "F.Fab")
			(hide yes)
			(effects
				(font
					(size 1 1)
					(thickness 0.15)
				)
			)
		)
		(property "Val" "0R"
			(at 0 0 270)
			(unlocked yes)
			(layer "F.Fab")
			(hide yes)
			(effects
				(font
					(size 1 1)
					(thickness 0.15)
				)
			)
		)
		(property "Tolerance" ""
			(at 0 0 270)
			(unlocked yes)
			(layer "F.Fab")
			(hide yes)
			(effects
				(font
					(size 1 1)
					(thickness 0.15)
				)
			)
		)
		(property "Current" "1A"
			(at 0 0 270)
			(unlocked yes)
			(layer "F.Fab")
			(hide yes)
			(effects
				(font
					(size 1 1)
					(thickness 0.15)
				)
			)
		)
		(sheetname "/OCuLink/")
		(sheetfile "oculink.kicad_sch")
		(attr smd)
		(fp_rect
			(start -0.925 -0.47)
			(end 0.925 0.47)
			(stroke
				(width 0.05)
				(type default)
			)
			(fill no)
			(layer "F.CrtYd")
		)
		(fp_rect
			(start -0.5 -0.25)
			(end 0.5 0.25)
			(stroke
				(width 0.15)
				(type solid)
			)
			(fill no)
			(layer "F.Fab")
		)
		(fp_text user "Author: Antmicro"
			(at -0.95 4.169 90)
			(layer "F.Fab")
			(effects
				(font
					(size 0.7 0.7)
					(thickness 0.15)
				)
				(justify right top)
			)
		)
		(fp_text user "License: Apache-2.0"
			(at -0.949999 5.169 90)
			(layer "F.Fab")
			(effects
				(font
					(size 0.7 0.7)
					(thickness 0.15)
				)
				(justify right top)
			)
		)
		(fp_text user "${REFERENCE}"
			(at -0.95 3.168 90)
			(layer "F.Fab")
			(effects
				(font
					(size 0.7 0.7)
					(thickness 0.15)
				)
				(justify right top)
			)
		)
		(pad "1" smd roundrect
			(at -0.48 0 270)
			(size 0.59 0.64)
			(layers "F.Cu" "F.Mask" "F.Paste")
			(roundrect_rratio 0.25)
			(net 184 "/OCuLink/~{WAKEC}")
			(pintype "passive")
		)
		(pad "2" smd roundrect
			(at 0.48 0 270)
			(size 0.59 0.64)
			(layers "F.Cu" "F.Mask" "F.Paste")
			(roundrect_rratio 0.25)
			(net 93 "/OCuLink/~{WAKE}")
			(pintype "passive")
		)
	)
	(footprint "antmicro-footprints:C_0402_1005Metric"
		(layer "F.Cu")
		(at 124.882999 149.054999 90)
		(descr "Capacitor SMD 0402")
		(tags "capacitor SMD 0402")
		(property "Reference" "C12"
			(at 1.054999 0.317001 270)
			(layer "F.SilkS")
			(effects
				(font
					(size 0.7 0.7)
					(thickness 0.15)
				)
				(justify left bottom)
			)
		)
		(property "Value" "C_100n_0402"
			(at -1.022927 2.155213 90)
			(layer "F.Fab")
			(effects
				(font
					(size 0.7 0.7)
					(thickness 0.15)
				)
				(justify left bottom)
			)
		)
		(property "Datasheet" "https://www.murata.com/products/productdetail?partno=GRM155R61H104KE14%23"
			(at 0 0 90)
			(layer "F.Fab")
			(hide yes)
			(effects
				(font
					(size 1.27 1.27)
					(thickness 0.15)
				)
			)
		)
		(property "Description" "SMD Multilayer Ceramic Capacitor, 0.1 µF, 50 V, 0402 [1005 Metric], ± 10%, X5R, GRM Series"
			(at 0 0 90)
			(layer "F.Fab")
			(hide yes)
			(effects
				(font
					(size 1.27 1.27)
					(thickness 0.15)
				)
			)
		)
		(property "MPN" "GRM155R61H104KE14D"
			(at 0 0 90)
			(unlocked yes)
			(layer "F.Fab")
			(hide yes)
			(effects
				(font
					(size 1 1)
					(thickness 0.15)
				)
			)
		)
		(property "Manufacturer" "Murata"
			(at 0 0 90)
			(unlocked yes)
			(layer "F.Fab")
			(hide yes)
			(effects
				(font
					(size 1 1)
					(thickness 0.15)
				)
			)
		)
		(property "License" "Apache-2.0"
			(at 0 0 90)
			(unlocked yes)
			(layer "F.Fab")
			(hide yes)
			(effects
				(font
					(size 1 1)
					(thickness 0.15)
				)
			)
		)
		(property "Author" "Antmicro"
			(at 0 0 90)
			(unlocked yes)
			(layer "F.Fab")
			(hide yes)
			(effects
				(font
					(size 1 1)
					(thickness 0.15)
				)
			)
		)
		(property "Val" "100n"
			(at 0 0 90)
			(unlocked yes)
			(layer "F.Fab")
			(hide yes)
			(effects
				(font
					(size 1 1)
					(thickness 0.15)
				)
			)
		)
		(property "Voltage" "50V"
			(at 0 0 90)
			(unlocked yes)
			(layer "F.Fab")
			(hide yes)
			(effects
				(font
					(size 1 1)
					(thickness 0.15)
				)
			)
		)
		(property "Dielectric" "X5R"
			(at 0 0 90)
			(unlocked yes)
			(layer "F.Fab")
			(hide yes)
			(effects
				(font
					(size 1 1)
					(thickness 0.15)
				)
			)
		)
		(sheetname "/Power/")
		(sheetfile "power.kicad_sch")
		(attr smd)
		(fp_rect
			(start -0.925 -0.47)
			(end 0.925 0.47)
			(stroke
				(width 0.05)
				(type default)
			)
			(fill no)
			(layer "F.CrtYd")
		)
		(fp_line
			(start 0.504 -0.25)
			(end 0.504 0.248)
			(stroke
				(width 0.15)
				(type solid)
			)
			(layer "F.Fab")
		)
		(fp_line
			(start -0.494 -0.25)
			(end 0.504 -0.25)
			(stroke
				(width 0.15)
				(type solid)
			)
			(layer "F.Fab")
		)
		(fp_line
			(start 0.504 0.248)
			(end -0.494 0.248)
			(stroke
				(width 0.15)
				(type solid)
			)
			(layer "F.Fab")
		)
		(fp_line
			(start -0.494 0.248)
			(end -0.494 -0.25)
			(stroke
				(width 0.15)
				(type solid)
			)
			(layer "F.Fab")
		)
		(fp_text user "${REFERENCE}"
			(at 0 0 90)
			(layer "F.Fab")
			(effects
				(font
					(size 0.7 0.7)
					(thickness 0.15)
				)
				(justify left bottom)
			)
		)
		(fp_text user "License: Apache-2.0"
			(at -0.939 5.799 90)
			(layer "F.Fab")
			(effects
				(font
					(size 0.7 0.7)
					(thickness 0.15)
				)
				(justify left bottom)
			)
		)
		(fp_text user "Author: Antmicro"
			(at -0.939 3.399 90)
			(layer "F.Fab")
			(effects
				(font
					(size 0.7 0.7)
					(thickness 0.15)
				)
				(justify left bottom)
			)
		)
		(pad "1" smd roundrect
			(at -0.48 0 90)
			(size 0.59 0.64)
			(layers "F.Cu" "F.Mask" "F.Paste")
			(roundrect_rratio 0.25)
			(net 66 "GND")
			(pintype "passive")
		)
		(pad "2" smd roundrect
			(at 0.48 0 90)
			(size 0.59 0.64)
			(layers "F.Cu" "F.Mask" "F.Paste")
			(roundrect_rratio 0.25)
			(net 134 "+3V3")
			(pintype "passive")
		)
	)
	(footprint "antmicro-footprints:TP_Pad0.75mm_Drill0.2mm"
		(layer "F.Cu")
		(at 150.8 42.7 180)
		(property "Reference" "TP4"
			(at 2.7 -0.3 180)
			(layer "F.SilkS")
			(effects
				(font
					(size 0.7 0.7)
					(thickness 0.15)
				)
				(justify left bottom)
			)
		)
		(property "Value" "TP_Pad0.75mm_Drill0.2mm"
			(at 0 1.2 180)
			(layer "F.Fab")
			(effects
				(font
					(size 0.7 0.7)
					(thickness 0.15)
				)
				(justify left bottom)
			)
		)
		(property "Description" "SMT test point"
			(at 0 0 180)
			(layer "F.Fab")
			(hide yes)
			(effects
				(font
					(size 1.27 1.27)
					(thickness 0.15)
				)
			)
		)
		(property "MPN" ""
			(at 0 0 180)
			(unlocked yes)
			(layer "F.Fab")
			(hide yes)
			(effects
				(font
					(size 1 1)
					(thickness 0.15)
				)
			)
		)
		(property "Manufacturer" ""
			(at 0 0 180)
			(unlocked yes)
			(layer "F.Fab")
			(hide yes)
			(effects
				(font
					(size 1 1)
					(thickness 0.15)
				)
			)
		)
		(property "Author" "Antmicro"
			(at 0 0 180)
			(unlocked yes)
			(layer "F.Fab")
			(hide yes)
			(effects
				(font
					(size 1 1)
					(thickness 0.15)
				)
			)
		)
		(property "License" "Apache-2.0"
			(at 0 0 180)
			(unlocked yes)
			(layer "F.Fab")
			(hide yes)
			(effects
				(font
					(size 1 1)
					(thickness 0.15)
				)
			)
		)
		(sheetname "/USB-PD/")
		(sheetfile "usb-pd.kicad_sch")
		(attr exclude_from_pos_files exclude_from_bom)
		(fp_circle
			(center 0 0)
			(end 0.475 0)
			(stroke
				(width 0.05)
				(type default)
			)
			(fill no)
			(layer "F.CrtYd")
		)
		(fp_text user "License: Apache-2.0"
			(at -0.4 5.101 180)
			(layer "F.Fab")
			(effects
				(font
					(size 0.7 0.7)
					(thickness 0.15)
				)
				(justify left bottom)
			)
		)
		(fp_text user "${REFERENCE}"
			(at -0.4 2.7 180)
			(layer "F.Fab")
			(effects
				(font
					(size 0.7 0.7)
					(thickness 0.15)
				)
				(justify left bottom)
			)
		)
		(fp_text user "Author: Antmicro"
			(at -0.4 3.901 180)
			(layer "F.Fab")
			(effects
				(font
					(size 0.7 0.7)
					(thickness 0.15)
				)
				(justify left bottom)
			)
		)
		(pad "1" thru_hole circle
			(at 0 0 180)
			(size 0.75 0.75)
			(drill 0.2)
			(layers "*.Cu" "*.Mask")
			(remove_unused_layers no)
			(net 113 "VBUS")
			(pinfunction "1")
			(pintype "passive")
		)
	)
	(footprint "antmicro-footprints:TP_Pad0.75mm_Drill0.2mm"
		(layer "F.Cu")
		(at 155.75 148 -90)
		(property "Reference" "TP1"
			(at 0.5 -0.6 0)
			(layer "F.SilkS")
			(effects
				(font
					(size 0.7 0.7)
					(thickness 0.15)
				)
				(justify left bottom)
			)
		)
		(property "Value" "TP_Pad0.75mm_Drill0.2mm"
			(at 0 1.2 270)
			(layer "F.Fab")
			(effects
				(font
					(size 0.7 0.7)
					(thickness 0.15)
				)
				(justify left bottom)
			)
		)
		(property "Description" "SMT test point"
			(at 0 0 270)
			(layer "F.Fab")
			(hide yes)
			(effects
				(font
					(size 1.27 1.27)
					(thickness 0.15)
				)
			)
		)
		(property "MPN" ""
			(at 0 0 270)
			(unlocked yes)
			(layer "F.Fab")
			(hide yes)
			(effects
				(font
					(size 1 1)
					(thickness 0.15)
				)
			)
		)
		(property "Manufacturer" ""
			(at 0 0 270)
			(unlocked yes)
			(layer "F.Fab")
			(hide yes)
			(effects
				(font
					(size 1 1)
					(thickness 0.15)
				)
			)
		)
		(property "Author" "Antmicro"
			(at 0 0 270)
			(unlocked yes)
			(layer "F.Fab")
			(hide yes)
			(effects
				(font
					(size 1 1)
					(thickness 0.15)
				)
			)
		)
		(property "License" "Apache-2.0"
			(at 0 0 270)
			(unlocked yes)
			(layer "F.Fab")
			(hide yes)
			(effects
				(font
					(size 1 1)
					(thickness 0.15)
				)
			)
		)
		(sheetname "/Power/")
		(sheetfile "power.kicad_sch")
		(attr exclude_from_pos_files exclude_from_bom)
		(fp_circle
			(center 0 0)
			(end 0.475 0)
			(stroke
				(width 0.05)
				(type default)
			)
			(fill no)
			(layer "F.CrtYd")
		)
		(fp_text user "Author: Antmicro"
			(at -0.4 3.901 270)
			(layer "F.Fab")
			(effects
				(font
					(size 0.7 0.7)
					(thickness 0.15)
				)
				(justify left bottom)
			)
		)
		(fp_text user "License: Apache-2.0"
			(at -0.4 5.101 270)
			(layer "F.Fab")
			(effects
				(font
					(size 0.7 0.7)
					(thickness 0.15)
				)
				(justify left bottom)
			)
		)
		(fp_text user "${REFERENCE}"
			(at -0.4 2.7 270)
			(layer "F.Fab")
			(effects
				(font
					(size 0.7 0.7)
					(thickness 0.15)
				)
				(justify left bottom)
			)
		)
		(pad "1" thru_hole circle
			(at 0 0 270)
			(size 0.75 0.75)
			(drill 0.2)
			(layers "*.Cu" "*.Mask")
			(remove_unused_layers no)
			(net 172 "/Power/~{PERST}")
			(pinfunction "1")
			(pintype "passive")
		)
	)
	(footprint "antmicro-footprints:TP_Pad0.75mm_Drill0.2mm"
		(layer "F.Cu")
		(at 155.75 154)
		(property "Reference" "TP8"
			(at 0.6 0.5 0)
			(layer "F.SilkS")
			(effects
				(font
					(size 0.7 0.7)
					(thickness 0.15)
				)
				(justify left bottom)
			)
		)
		(property "Value" "TP_Pad0.75mm_Drill0.2mm"
			(at 0 1.2 0)
			(layer "F.Fab")
			(effects
				(font
					(size 0.7 0.7)
					(thickness 0.15)
				)
				(justify left bottom)
			)
		)
		(property "Description" "SMT test point"
			(at 0 0 0)
			(layer "F.Fab")
			(hide yes)
			(effects
				(font
					(size 1.27 1.27)
					(thickness 0.15)
				)
			)
		)
		(property "MPN" ""
			(at 0 0 0)
			(unlocked yes)
			(layer "F.Fab")
			(hide yes)
			(effects
				(font
					(size 1 1)
					(thickness 0.15)
				)
			)
		)
		(property "Manufacturer" ""
			(at 0 0 0)
			(unlocked yes)
			(layer "F.Fab")
			(hide yes)
			(effects
				(font
					(size 1 1)
					(thickness 0.15)
				)
			)
		)
		(property "Author" "Antmicro"
			(at 0 0 0)
			(unlocked yes)
			(layer "F.Fab")
			(hide yes)
			(effects
				(font
					(size 1 1)
					(thickness 0.15)
				)
			)
		)
		(property "License" "Apache-2.0"
			(at 0 0 0)
			(unlocked yes)
			(layer "F.Fab")
			(hide yes)
			(effects
				(font
					(size 1 1)
					(thickness 0.15)
				)
			)
		)
		(sheetname "/Power/")
		(sheetfile "power.kicad_sch")
		(attr exclude_from_pos_files exclude_from_bom)
		(fp_circle
			(center 0 0)
			(end 0.475 0)
			(stroke
				(width 0.05)
				(type default)
			)
			(fill no)
			(layer "F.CrtYd")
		)
		(fp_text user "${REFERENCE}"
			(at -0.4 2.7 0)
			(layer "F.Fab")
			(effects
				(font
					(size 0.7 0.7)
					(thickness 0.15)
				)
				(justify left bottom)
			)
		)
		(fp_text user "License: Apache-2.0"
			(at -0.4 5.101 0)
			(layer "F.Fab")
			(effects
				(font
					(size 0.7 0.7)
					(thickness 0.15)
				)
				(justify left bottom)
			)
		)
		(fp_text user "Author: Antmicro"
			(at -0.4 3.901 0)
			(layer "F.Fab")
			(effects
				(font
					(size 0.7 0.7)
					(thickness 0.15)
				)
				(justify left bottom)
			)
		)
		(pad "1" thru_hole circle
			(at 0 0)
			(size 0.75 0.75)
			(drill 0.2)
			(layers "*.Cu" "*.Mask")
			(remove_unused_layers no)
			(net 66 "GND")
			(pinfunction "1")
			(pintype "passive")
		)
	)
	(footprint "antmicro-footprints:Vishay_PowerPAK_1212-8_Single"
		(layer "F.Cu")
		(at 140.943001 116.399999)
		(descr "PowerPAK 1212-8 Single")
		(tags "Vishay PowerPAK 1212-8 Single")
		(property "Reference" "Q1"
			(at -3.543001 -0.799999 180)
			(layer "F.SilkS")
			(effects
				(font
					(size 0.7 0.7)
					(thickness 0.15)
				)
				(justify left bottom)
			)
		)
		(property "Value" "SQS401EN-T1_BE3"
			(at 0 2.7 0)
			(layer "F.Fab")
			(effects
				(font
					(size 0.7 0.7)
					(thickness 0.15)
				)
				(justify left bottom)
			)
		)
		(property "Datasheet" "https://www.vishay.com/docs/65529/sqs401en.pdf"
			(at 0 0 0)
			(layer "F.Fab")
			(hide yes)
			(effects
				(font
					(size 1.27 1.27)
					(thickness 0.15)
				)
			)
		)
		(property "Description" "MOSFET, P Channel, 40 V, 16A, 0.047 ohm, PowerPAK 1212-8, Surface Mount"
			(at 0 0 0)
			(layer "F.Fab")
			(hide yes)
			(effects
				(font
					(size 1.27 1.27)
					(thickness 0.15)
				)
			)
		)
		(property "MPN" "SQS401EN-T1_BE3"
			(at 0 0 0)
			(unlocked yes)
			(layer "F.Fab")
			(hide yes)
			(effects
				(font
					(size 1 1)
					(thickness 0.15)
				)
			)
		)
		(property "Manufacturer" "Vishay"
			(at 0 0 0)
			(unlocked yes)
			(layer "F.Fab")
			(hide yes)
			(effects
				(font
					(size 1 1)
					(thickness 0.15)
				)
			)
		)
		(property "Author" "Antmicro"
			(at 0 0 0)
			(unlocked yes)
			(layer "F.Fab")
			(hide yes)
			(effects
				(font
					(size 1 1)
					(thickness 0.15)
				)
			)
		)
		(property "License" "Apache-2.0"
			(at 0 0 0)
			(unlocked yes)
			(layer "F.Fab")
			(hide yes)
			(effects
				(font
					(size 1 1)
					(thickness 0.15)
				)
			)
		)
		(sheetname "/Power/Ideal-diode-1/")
		(sheetfile "ideal-diode.kicad_sch")
		(attr smd)
		(fp_line
			(start -1.651 -1.651)
			(end -1.651 -1.317)
			(stroke
				(width 0.15)
				(type solid)
			)
			(layer "F.SilkS")
		)
		(fp_line
			(start -1.651 -1.651)
			(end 1.648 -1.651)
			(stroke
				(width 0.15)
				(type solid)
			)
			(layer "F.SilkS")
		)
		(fp_line
			(start -1.635 1.3)
			(end -1.635 1.634)
			(stroke
				(width 0.15)
				(type solid)
			)
			(layer "F.SilkS")
		)
		(fp_line
			(start -1.635 1.634)
			(end 1.634 1.634)
			(stroke
				(width 0.15)
				(type solid)
			)
			(layer "F.SilkS")
		)
		(fp_line
			(start 1.634 1.3)
			(end 1.634 1.634)
			(stroke
				(width 0.15)
				(type solid)
			)
			(layer "F.SilkS")
		)
		(fp_line
			(start 1.648 -1.651)
			(end 1.648 -1.317)
			(stroke
				(width 0.15)
				(type solid)
			)
			(layer "F.SilkS")
		)
		(fp_circle
			(center -1.9 -1.4)
			(end -1.85 -1.4)
			(stroke
				(width 0.15)
				(type solid)
			)
			(fill yes)
			(layer "F.SilkS")
		)
		(fp_rect
			(start -2 -1.8)
			(end 2 1.798)
			(stroke
				(width 0.05)
				(type solid)
			)
			(fill no)
			(layer "F.CrtYd")
		)
		(fp_line
			(start -1.6425 -1.4175)
			(end -1.4175 -1.6425)
			(stroke
				(width 0.15)
				(type solid)
			)
			(layer "F.Fab")
		)
		(fp_rect
			(start -1.651 -1.651)
			(end 1.648 1.648)
			(stroke
				(width 0.15)
				(type solid)
			)
			(fill no)
			(layer "F.Fab")
		)
		(fp_text user "${REFERENCE}"
			(at 0 -0.001 0)
			(layer "F.Fab")
			(effects
				(font
					(size 0.7 0.7)
					(thickness 0.15)
				)
				(justify left bottom)
			)
		)
		(fp_text user "License: Apache-2.0"
			(at -8 7.1 0)
			(layer "F.Fab")
			(effects
				(font
					(size 0.7 0.7)
					(thickness 0.15)
				)
				(justify left bottom)
			)
		)
		(fp_text user "Author: Antmicro"
			(at -8 5.9 0)
			(layer "F.Fab")
			(effects
				(font
					(size 0.7 0.7)
					(thickness 0.15)
				)
				(justify left bottom)
			)
		)
		(pad "1" smd rect
			(at -1.436 -0.99)
			(size 0.99 0.405)
			(layers "F.Cu" "F.Mask" "F.Paste")
			(net 87 "+12V")
			(pinfunction "S")
			(pintype "passive")
		)
		(pad "2" smd rect
			(at -1.436 -0.332)
			(size 0.99 0.405)
			(layers "F.Cu" "F.Mask" "F.Paste")
			(net 87 "+12V")
			(pinfunction "S")
			(pintype "passive")
		)
		(pad "3" smd rect
			(at -1.436 0.33)
			(size 0.99 0.405)
			(layers "F.Cu" "F.Mask" "F.Paste")
			(net 87 "+12V")
			(pinfunction "S")
			(pintype "passive")
		)
		(pad "4" smd rect
			(at -1.436 0.988)
			(size 0.99 0.405)
			(layers "F.Cu" "F.Mask" "F.Paste")
			(net 104 "Net-(Q1-G)")
			(pinfunction "G")
			(pintype "input")
		)
		(pad "5" smd custom
			(at 0.557 0)
			(size 1.725 2.235)
			(layers "F.Cu" "F.Mask" "F.Paste")
			(net 118 "/Power/Ideal-diode-1/VIN")
			(pinfunction "D")
			(pintype "passive")
			(zone_connect 2)
			(options
				(clearance outline)
				(anchor rect)
			)
			(primitives
				(gr_poly
					(pts
						(xy 0.8625 0.1275) (xy 0.8625 -0.1275) (xy 1.3725 -0.1275) (xy 1.3725 -0.5325) (xy 0.8625 -0.5325)
						(xy 0.8625 -0.7875) (xy 1.3725 -0.7875) (xy 1.3725 -1.195) (xy 0.6125 -1.195) (xy 0.6125 1.195)
						(xy 1.3725 1.195) (xy 1.3725 0.7875) (xy 0.8625 0.7875) (xy 0.8625 0.5325) (xy 1.3725 0.5325)
						(xy 1.3725 0.1275)
					)
					(width 0)
					(fill yes)
				)
			)
		)
	)
	(footprint "antmicro-footprints:R_0402_1005Metric"
		(layer "F.Cu")
		(at 153.900001 47.62 90)
		(descr "Resistor SMD 0402")
		(tags "resistor SMD 0402")
		(property "Reference" "R37"
			(at 1.02 3.699998 90)
			(layer "F.SilkS")
			(effects
				(font
					(size 0.7 0.7)
					(thickness 0.15)
				)
				(justify right top)
			)
		)
		(property "Value" "R_1k_0402"
			(at -1.011843 1.772046 90)
			(layer "F.Fab")
			(effects
				(font
					(size 0.7 0.7)
					(thickness 0.15)
				)
				(justify left bottom)
			)
		)
		(property "Datasheet" "https://www.bourns.com/docs/product-datasheets/cr.pdf"
			(at 0 0 90)
			(layer "F.Fab")
			(hide yes)
			(effects
				(font
					(size 1.27 1.27)
					(thickness 0.15)
				)
			)
		)
		(property "Description" "SMD Chip Resistor, 1 kohm, ± 1%, 63 mW, 0402 [1005 Metric], Thick Film, General Purpose"
			(at 0 0 90)
			(layer "F.Fab")
			(hide yes)
			(effects
				(font
					(size 1.27 1.27)
					(thickness 0.15)
				)
			)
		)
		(property "MPN" "CR0402-FX-1001GLF"
			(at 0 0 90)
			(unlocked yes)
			(layer "F.Fab")
			(hide yes)
			(effects
				(font
					(size 1 1)
					(thickness 0.15)
				)
			)
		)
		(property "Manufacturer" "Bourns"
			(at 0 0 90)
			(unlocked yes)
			(layer "F.Fab")
			(hide yes)
			(effects
				(font
					(size 1 1)
					(thickness 0.15)
				)
			)
		)
		(property "License" "Apache-2.0"
			(at 0 0 90)
			(unlocked yes)
			(layer "F.Fab")
			(hide yes)
			(effects
				(font
					(size 1 1)
					(thickness 0.15)
				)
			)
		)
		(property "Author" "Antmicro"
			(at 0 0 90)
			(unlocked yes)
			(layer "F.Fab")
			(hide yes)
			(effects
				(font
					(size 1 1)
					(thickness 0.15)
				)
			)
		)
		(property "Val" "1k"
			(at 0 0 90)
			(unlocked yes)
			(layer "F.Fab")
			(hide yes)
			(effects
				(font
					(size 1 1)
					(thickness 0.15)
				)
			)
		)
		(property "Tolerance" "1%"
			(at 0 0 90)
			(unlocked yes)
			(layer "F.Fab")
			(hide yes)
			(effects
				(font
					(size 1 1)
					(thickness 0.15)
				)
			)
		)
		(sheetname "/USB-PD/")
		(sheetfile "usb-pd.kicad_sch")
		(attr smd)
		(fp_rect
			(start -0.925 -0.47)
			(end 0.925 0.47)
			(stroke
				(width 0.05)
				(type default)
			)
			(fill no)
			(layer "F.CrtYd")
		)
		(fp_rect
			(start -0.5 -0.25)
			(end 0.5 0.25)
			(stroke
				(width 0.15)
				(type solid)
			)
			(fill no)
			(layer "F.Fab")
		)
		(fp_text user "License: Apache-2.0"
			(at -0.949999 5.169 90)
			(layer "F.Fab")
			(effects
				(font
					(size 0.7 0.7)
					(thickness 0.15)
				)
				(justify left bottom)
			)
		)
		(fp_text user "Author: Antmicro"
			(at -0.95 4.169 90)
			(layer "F.Fab")
			(effects
				(font
					(size 0.7 0.7)
					(thickness 0.15)
				)
				(justify left bottom)
			)
		)
		(fp_text user "${REFERENCE}"
			(at 0 0 270)
			(layer "F.Fab")
			(effects
				(font
					(size 0.7 0.7)
					(thickness 0.15)
				)
				(justify right top)
			)
		)
		(pad "1" smd roundrect
			(at -0.48 0 90)
			(size 0.59 0.64)
			(layers "F.Cu" "F.Mask" "F.Paste")
			(roundrect_rratio 0.25)
			(net 154 "/USB-PD/VBUS_EN")
			(pintype "passive")
		)
		(pad "2" smd roundrect
			(at 0.48 0 90)
			(size 0.59 0.64)
			(layers "F.Cu" "F.Mask" "F.Paste")
			(roundrect_rratio 0.25)
			(net 84 "Net-(Q6-G)")
			(pintype "passive")
		)
	)
	(footprint "antmicro-footprints:C_0805_2012Metric"
		(layer "F.Cu")
		(at 138.2 89.5 90)
		(descr "Capacitor SMD 0805")
		(tags "capacitor SMD 0805")
		(property "Reference" "C25"
			(at 0.3 -4.8 90)
			(layer "F.SilkS")
			(effects
				(font
					(size 0.7 0.7)
					(thickness 0.15)
				)
				(justify left bottom)
			)
		)
		(property "Value" "C_10u_0805_35V"
			(at -2.055717 1.963153 90)
			(layer "F.Fab")
			(effects
				(font
					(size 0.7 0.7)
					(thickness 0.15)
				)
				(justify left bottom)
			)
		)
		(property "Datasheet" "https://www.murata.com/products/productdetail?partno=GRM21BR6YA106KE43%23"
			(at 0 0 90)
			(layer "F.Fab")
			(hide yes)
			(effects
				(font
					(size 1.27 1.27)
					(thickness 0.15)
				)
			)
		)
		(property "Description" "SMD Multilayer Ceramic Capacitor, 10 µF, 35 V, 0805 [2012 Metric], ± 10%, X5R, GRM Series"
			(at 0 0 90)
			(layer "F.Fab")
			(hide yes)
			(effects
				(font
					(size 1.27 1.27)
					(thickness 0.15)
				)
			)
		)
		(property "MPN" "GRM21BR6YA106KE43L"
			(at 0 0 90)
			(unlocked yes)
			(layer "F.Fab")
			(hide yes)
			(effects
				(font
					(size 1 1)
					(thickness 0.15)
				)
			)
		)
		(property "Manufacturer" "Murata"
			(at 0 0 90)
			(unlocked yes)
			(layer "F.Fab")
			(hide yes)
			(effects
				(font
					(size 1 1)
					(thickness 0.15)
				)
			)
		)
		(property "License" "Apache-2.0"
			(at 0 0 90)
			(unlocked yes)
			(layer "F.Fab")
			(hide yes)
			(effects
				(font
					(size 1 1)
					(thickness 0.15)
				)
			)
		)
		(property "Author" "Antmicro"
			(at 0 0 90)
			(unlocked yes)
			(layer "F.Fab")
			(hide yes)
			(effects
				(font
					(size 1 1)
					(thickness 0.15)
				)
			)
		)
		(property "Val" "10u"
			(at 0 0 90)
			(unlocked yes)
			(layer "F.Fab")
			(hide yes)
			(effects
				(font
					(size 1 1)
					(thickness 0.15)
				)
			)
		)
		(property "Voltage" "35V"
			(at 0 0 90)
			(unlocked yes)
			(layer "F.Fab")
			(hide yes)
			(effects
				(font
					(size 1 1)
					(thickness 0.15)
				)
			)
		)
		(property "Dielectric" ""
			(at 0 0 90)
			(unlocked yes)
			(layer "F.Fab")
			(hide yes)
			(effects
				(font
					(size 1 1)
					(thickness 0.15)
				)
			)
		)
		(property "Public" "False"
			(at 0 0 90)
			(unlocked yes)
			(layer "F.Fab")
			(hide yes)
			(effects
				(font
					(size 1 1)
					(thickness 0.15)
				)
			)
		)
		(sheetname "/USB-PD/")
		(sheetfile "usb-pd.kicad_sch")
		(attr smd)
		(fp_line
			(start -0.3 -0.7)
			(end 0.3 -0.7)
			(stroke
				(width 0.15)
				(type solid)
			)
			(layer "F.SilkS")
		)
		(fp_line
			(start -0.3 0.7)
			(end 0.3 0.7)
			(stroke
				(width 0.15)
				(type solid)
			)
			(layer "F.SilkS")
		)
		(fp_rect
			(start 1.95 -0.9)
			(end -1.95 0.9)
			(stroke
				(width 0.05)
				(type default)
			)
			(fill no)
			(layer "F.CrtYd")
		)
		(fp_rect
			(start -0.95 -0.675)
			(end 0.95 0.675)
			(stroke
				(width 0.15)
				(type solid)
			)
			(fill no)
			(layer "F.Fab")
		)
		(fp_text user "License: Apache-2.0"
			(at -1.9 4.947 90)
			(layer "F.Fab")
			(effects
				(font
					(size 0.7 0.7)
					(thickness 0.15)
				)
				(justify left bottom)
			)
		)
		(fp_text user "${REFERENCE}"
			(at 0 0 90)
			(layer "F.Fab")
			(effects
				(font
					(size 0.7 0.7)
					(thickness 0.15)
				)
				(justify left bottom)
			)
		)
		(fp_text user "Author: Antmicro"
			(at -1.9 5.947 90)
			(layer "F.Fab")
			(effects
				(font
					(size 0.7 0.7)
					(thickness 0.15)
				)
				(justify left bottom)
			)
		)
		(pad "1" smd roundrect
			(at -1.1 0 90)
			(size 1.2 1.3)
			(layers "F.Cu" "F.Mask" "F.Paste")
			(roundrect_rratio 0.25)
			(net 66 "GND")
			(pintype "passive")
		)
		(pad "2" smd roundrect
			(at 1.1 0 90)
			(size 1.2 1.3)
			(layers "F.Cu" "F.Mask" "F.Paste")
			(roundrect_rratio 0.25)
			(net 115 "/USB-PD/VCC")
			(pintype "passive")
		)
	)
	(footprint "antmicro-footprints:C_0402_1005Metric"
		(layer "F.Cu")
		(at 146.562 53.001)
		(descr "Capacitor SMD 0402")
		(tags "capacitor SMD 0402")
		(property "Reference" "C41"
			(at -3.162 2.999 180)
			(layer "F.SilkS")
			(effects
				(font
					(size 0.7 0.7)
					(thickness 0.15)
				)
				(justify left bottom)
			)
		)
		(property "Value" "C_100n_0402"
			(at -1.022927 2.155213 0)
			(layer "F.Fab")
			(effects
				(font
					(size 0.7 0.7)
					(thickness 0.15)
				)
				(justify left bottom)
			)
		)
		(property "Datasheet" "https://www.murata.com/products/productdetail?partno=GRM155R61H104KE14%23"
			(at 0 0 0)
			(layer "F.Fab")
			(hide yes)
			(effects
				(font
					(size 1.27 1.27)
					(thickness 0.15)
				)
			)
		)
		(property "Description" "SMD Multilayer Ceramic Capacitor, 0.1 µF, 50 V, 0402 [1005 Metric], ± 10%, X5R, GRM Series"
			(at 0 0 0)
			(layer "F.Fab")
			(hide yes)
			(effects
				(font
					(size 1.27 1.27)
					(thickness 0.15)
				)
			)
		)
		(property "MPN" "GRM155R61H104KE14D"
			(at 0 0 0)
			(unlocked yes)
			(layer "F.Fab")
			(hide yes)
			(effects
				(font
					(size 1 1)
					(thickness 0.15)
				)
			)
		)
		(property "Manufacturer" "Murata"
			(at 0 0 0)
			(unlocked yes)
			(layer "F.Fab")
			(hide yes)
			(effects
				(font
					(size 1 1)
					(thickness 0.15)
				)
			)
		)
		(property "License" "Apache-2.0"
			(at 0 0 0)
			(unlocked yes)
			(layer "F.Fab")
			(hide yes)
			(effects
				(font
					(size 1 1)
					(thickness 0.15)
				)
			)
		)
		(property "Author" "Antmicro"
			(at 0 0 0)
			(unlocked yes)
			(layer "F.Fab")
			(hide yes)
			(effects
				(font
					(size 1 1)
					(thickness 0.15)
				)
			)
		)
		(property "Val" "100n"
			(at 0 0 0)
			(unlocked yes)
			(layer "F.Fab")
			(hide yes)
			(effects
				(font
					(size 1 1)
					(thickness 0.15)
				)
			)
		)
		(property "Voltage" "50V"
			(at 0 0 0)
			(unlocked yes)
			(layer "F.Fab")
			(hide yes)
			(effects
				(font
					(size 1 1)
					(thickness 0.15)
				)
			)
		)
		(property "Dielectric" "X5R"
			(at 0 0 0)
			(unlocked yes)
			(layer "F.Fab")
			(hide yes)
			(effects
				(font
					(size 1 1)
					(thickness 0.15)
				)
			)
		)
		(sheetname "/USB-PD/")
		(sheetfile "usb-pd.kicad_sch")
		(attr smd)
		(fp_rect
			(start -0.925 -0.47)
			(end 0.925 0.47)
			(stroke
				(width 0.05)
				(type default)
			)
			(fill no)
			(layer "F.CrtYd")
		)
		(fp_line
			(start -0.494 -0.25)
			(end 0.504 -0.25)
			(stroke
				(width 0.15)
				(type solid)
			)
			(layer "F.Fab")
		)
		(fp_line
			(start -0.494 0.248)
			(end -0.494 -0.25)
			(stroke
				(width 0.15)
				(type solid)
			)
			(layer "F.Fab")
		)
		(fp_line
			(start 0.504 -0.25)
			(end 0.504 0.248)
			(stroke
				(width 0.15)
				(type solid)
			)
			(layer "F.Fab")
		)
		(fp_line
			(start 0.504 0.248)
			(end -0.494 0.248)
			(stroke
				(width 0.15)
				(type solid)
			)
			(layer "F.Fab")
		)
		(fp_text user "Author: Antmicro"
			(at -0.939 3.399 0)
			(layer "F.Fab")
			(effects
				(font
					(size 0.7 0.7)
					(thickness 0.15)
				)
				(justify left bottom)
			)
		)
		(fp_text user "${REFERENCE}"
			(at 0 0 0)
			(layer "F.Fab")
			(effects
				(font
					(size 0.7 0.7)
					(thickness 0.15)
				)
				(justify left bottom)
			)
		)
		(fp_text user "License: Apache-2.0"
			(at -0.939 5.799 0)
			(layer "F.Fab")
			(effects
				(font
					(size 0.7 0.7)
					(thickness 0.15)
				)
				(justify left bottom)
			)
		)
		(pad "1" smd roundrect
			(at -0.48 0)
			(size 0.59 0.64)
			(layers "F.Cu" "F.Mask" "F.Paste")
			(roundrect_rratio 0.25)
			(net 66 "GND")
			(pintype "passive")
		)
		(pad "2" smd roundrect
			(at 0.48 0)
			(size 0.59 0.64)
			(layers "F.Cu" "F.Mask" "F.Paste")
			(roundrect_rratio 0.25)
			(net 117 "/USB-PD/VDDD_3V3")
			(pintype "passive")
		)
	)
	(footprint "antmicro-footprints:R_0402_1005Metric"
		(layer "F.Cu")
		(at 148.152 88)
		(descr "Resistor SMD 0402")
		(tags "resistor SMD 0402")
		(property "Reference" "R34"
			(at 1.248 0.3 180)
			(layer "F.SilkS")
			(effects
				(font
					(size 0.7 0.7)
					(thickness 0.15)
				)
				(justify left bottom)
			)
		)
		(property "Value" "R_100k_0402"
			(at -1.011843 1.772046 0)
			(layer "F.Fab")
			(effects
				(font
					(size 0.7 0.7)
					(thickness 0.15)
				)
				(justify left bottom)
			)
		)
		(property "Datasheet" "https://www.bourns.com/docs/product-datasheets/cr.pdf"
			(at 0 0 0)
			(layer "F.Fab")
			(hide yes)
			(effects
				(font
					(size 1.27 1.27)
					(thickness 0.15)
				)
			)
		)
		(property "Description" "SMD Chip Resistor, 100 kohm, ± 1%, 62.5 mW, 0402 [1005 Metric], Thick Film, General Purpose"
			(at 0 0 0)
			(layer "F.Fab")
			(hide yes)
			(effects
				(font
					(size 1.27 1.27)
					(thickness 0.15)
				)
			)
		)
		(property "Manufacturer" "Bourns"
			(at 0 0 0)
			(unlocked yes)
			(layer "F.Fab")
			(hide yes)
			(effects
				(font
					(size 1 1)
					(thickness 0.15)
				)
			)
		)
		(property "MPN" "CR0402-FX-1003GLF"
			(at 0 0 0)
			(unlocked yes)
			(layer "F.Fab")
			(hide yes)
			(effects
				(font
					(size 1 1)
					(thickness 0.15)
				)
			)
		)
		(property "Val" "100k"
			(at 0 0 0)
			(unlocked yes)
			(layer "F.Fab")
			(hide yes)
			(effects
				(font
					(size 1 1)
					(thickness 0.15)
				)
			)
		)
		(property "License" "Apache-2.0"
			(at 0 0 0)
			(unlocked yes)
			(layer "F.Fab")
			(hide yes)
			(effects
				(font
					(size 1 1)
					(thickness 0.15)
				)
			)
		)
		(property "Author" "Antmicro"
			(at 0 0 0)
			(unlocked yes)
			(layer "F.Fab")
			(hide yes)
			(effects
				(font
					(size 1 1)
					(thickness 0.15)
				)
			)
		)
		(property "Tolerance" "1%"
			(at 0 0 0)
			(unlocked yes)
			(layer "F.Fab")
			(hide yes)
			(effects
				(font
					(size 1 1)
					(thickness 0.15)
				)
			)
		)
		(sheetname "/USB-PD/")
		(sheetfile "usb-pd.kicad_sch")
		(attr smd)
		(fp_rect
			(start -0.925 -0.47)
			(end 0.925 0.47)
			(stroke
				(width 0.05)
				(type default)
			)
			(fill no)
			(layer "F.CrtYd")
		)
		(fp_rect
			(start -0.5 -0.25)
			(end 0.5 0.25)
			(stroke
				(width 0.15)
				(type solid)
			)
			(fill no)
			(layer "F.Fab")
		)
		(fp_text user "${REFERENCE}"
			(at 0 0 0)
			(layer "F.Fab")
			(effects
				(font
					(size 0.7 0.7)
					(thickness 0.15)
				)
				(justify left bottom)
			)
		)
		(fp_text user "Author: Antmicro"
			(at -0.95 4.169 0)
			(layer "F.Fab")
			(effects
				(font
					(size 0.7 0.7)
					(thickness 0.15)
				)
				(justify left bottom)
			)
		)
		(fp_text user "License: Apache-2.0"
			(at -0.949999 5.169 0)
			(layer "F.Fab")
			(effects
				(font
					(size 0.7 0.7)
					(thickness 0.15)
				)
				(justify left bottom)
			)
		)
		(pad "1" smd roundrect
			(at -0.48 0)
			(size 0.59 0.64)
			(layers "F.Cu" "F.Mask" "F.Paste")
			(roundrect_rratio 0.25)
			(net 158 "/USB-PD/12V_PG")
			(pintype "passive")
		)
		(pad "2" smd roundrect
			(at 0.48 0)
			(size 0.59 0.64)
			(layers "F.Cu" "F.Mask" "F.Paste")
			(roundrect_rratio 0.25)
			(net 121 "/USB-PD/12V_VDD")
			(pintype "passive")
		)
	)
	(footprint "antmicro-footprints:SOT-23-6"
		(layer "F.Cu")
		(at 136.4 108.8 180)
		(property "Reference" "U3"
			(at -0.8 -2 180)
			(layer "F.SilkS")
			(effects
				(font
					(size 0.7 0.7)
					(thickness 0.15)
				)
				(justify right top)
			)
		)
		(property "Value" "LTC4412IS6"
			(at -1.749999 2.693 0)
			(layer "F.Fab")
			(effects
				(font
					(size 0.7 0.7)
					(thickness 0.15)
				)
				(justify right top)
			)
		)
		(property "Datasheet" "https://www.analog.com/media/en/technical-documentation/data-sheets/4412fb.pdf"
			(at 0 -0.057 0)
			(layer "F.Fab")
			(hide yes)
			(effects
				(font
					(size 1.27 1.27)
					(thickness 0.15)
				)
			)
		)
		(property "Description" "Ideal diode controller"
			(at 0 -0.057 0)
			(layer "F.Fab")
			(hide yes)
			(effects
				(font
					(size 1.27 1.27)
					(thickness 0.15)
				)
			)
		)
		(property "MPN" "LTC4412IS6#TRMPBF"
			(at 0 0 180)
			(unlocked yes)
			(layer "F.Fab")
			(hide yes)
			(effects
				(font
					(size 1 1)
					(thickness 0.15)
				)
			)
		)
		(property "Manufacturer" "Analog Devices"
			(at 0 0 180)
			(unlocked yes)
			(layer "F.Fab")
			(hide yes)
			(effects
				(font
					(size 1 1)
					(thickness 0.15)
				)
			)
		)
		(property "Author" "Antmicro"
			(at 0 0 180)
			(unlocked yes)
			(layer "F.Fab")
			(hide yes)
			(effects
				(font
					(size 1 1)
					(thickness 0.15)
				)
			)
		)
		(property "License" "Apache-2.0"
			(at 0 0 180)
			(unlocked yes)
			(layer "F.Fab")
			(hide yes)
			(effects
				(font
					(size 1 1)
					(thickness 0.15)
				)
			)
		)
		(sheetname "/Power/Ideal-diode-0/")
		(sheetfile "ideal-diode.kicad_sch")
		(attr smd)
		(fp_line
			(start 1.45 0.643)
			(end 1.45 0.343)
			(stroke
				(width 0.12)
				(type solid)
			)
			(layer "F.SilkS")
		)
		(fp_line
			(start 1.45 -0.757)
			(end 1.45 -0.457)
			(stroke
				(width 0.12)
				(type solid)
			)
			(layer "F.SilkS")
		)
		(fp_line
			(start 1.3 0.643)
			(end 1.45 0.643)
			(stroke
				(width 0.12)
				(type solid)
			)
			(layer "F.SilkS")
		)
		(fp_line
			(start 1.3 -0.757)
			(end 1.45 -0.757)
			(stroke
				(width 0.12)
				(type solid)
			)
			(layer "F.SilkS")
		)
		(fp_line
			(start -1.3 -0.757)
			(end -1.45 -0.757)
			(stroke
				(width 0.12)
				(type solid)
			)
			(layer "F.SilkS")
		)
		(fp_line
			(start -1.45 0.643)
			(end -1.45 0.343)
			(stroke
				(width 0.12)
				(type solid)
			)
			(layer "F.SilkS")
		)
		(fp_line
			(start -1.45 -0.757)
			(end -1.45 -0.457)
			(stroke
				(width 0.12)
				(type solid)
			)
			(layer "F.SilkS")
		)
		(fp_rect
			(start -1.55 -1.85)
			(end 1.55 1.75)
			(stroke
				(width 0.05)
				(type solid)
			)
			(fill no)
			(layer "F.CrtYd")
		)
		(fp_line
			(start 1.5 0.643)
			(end -1.5 0.643)
			(stroke
				(width 0.1)
				(type solid)
			)
			(layer "F.Fab")
		)
		(fp_line
			(start 1.5 -0.757)
			(end 1.5 0.643)
			(stroke
				(width 0.1)
				(type solid)
			)
			(layer "F.Fab")
		)
		(fp_line
			(start -1.5 0.643)
			(end -1.5 -0.757)
			(stroke
				(width 0.1)
				(type solid)
			)
			(layer "F.Fab")
		)
		(fp_line
			(start -1.5 -0.757)
			(end 1.5 -0.757)
			(stroke
				(width 0.1)
				(type solid)
			)
			(layer "F.Fab")
		)
		(fp_text user "."
			(at -1.8 1.743001 0)
			(layer "F.SilkS")
			(effects
				(font
					(size 1 1)
					(thickness 0.15)
				)
			)
		)
		(fp_text user "${REFERENCE}"
			(at 0 -0.050001 0)
			(layer "F.Fab")
			(effects
				(font
					(size 0.7 0.7)
					(thickness 0.15)
				)
				(justify right top)
			)
		)
		(fp_text user "Author: Antmicro"
			(at -1.829 5.25 0)
			(layer "F.Fab")
			(effects
				(font
					(size 0.7 0.7)
					(thickness 0.15)
				)
				(justify right top)
			)
		)
		(fp_text user "License: Apache-2.0"
			(at -1.75 6.5 0)
			(layer "F.Fab")
			(effects
				(font
					(size 0.7 0.7)
					(thickness 0.15)
				)
				(justify right top)
			)
		)
		(pad "1" smd roundrect
			(at -0.954 1.1 180)
			(size 0.55 1)
			(layers "F.Cu" "F.Mask" "F.Paste")
			(roundrect_rratio 0.15)
			(net 119 "/Power/VCC_PD")
			(pinfunction "IN")
			(pintype "power_in")
		)
		(pad "2" smd roundrect
			(at -0.003 1.1 180)
			(size 0.55 1)
			(layers "F.Cu" "F.Mask" "F.Paste")
			(roundrect_rratio 0.15)
			(net 66 "GND")
			(pinfunction "GND")
			(pintype "power_in")
		)
		(pad "3" smd roundrect
			(at 0.947 1.1 180)
			(size 0.55 1)
			(layers "F.Cu" "F.Mask" "F.Paste")
			(roundrect_rratio 0.15)
			(net 66 "GND")
			(pinfunction "CTL")
			(pintype "input")
		)
		(pad "4" smd roundrect
			(at 0.947 -1.214 180)
			(size 0.55 1)
			(layers "F.Cu" "F.Mask" "F.Paste")
			(roundrect_rratio 0.15)
			(net 162 "unconnected-(U3-STAT-Pad4)")
			(pinfunction "STAT")
			(pintype "output+no_connect")
		)
		(pad "5" smd roundrect
			(at -0.003 -1.214 180)
			(size 0.55 1)
			(layers "F.Cu" "F.Mask" "F.Paste")
			(roundrect_rratio 0.15)
			(net 151 "Net-(Q5-G)")
			(pinfunction "GATE")
			(pintype "output")
		)
		(pad "6" smd roundrect
			(at -0.954 -1.214 180)
			(size 0.55 1)
			(layers "F.Cu" "F.Mask" "F.Paste")
			(roundrect_rratio 0.15)
			(net 87 "+12V")
			(pinfunction "SENSE")
			(pintype "input")
		)
	)
	(footprint "antmicro-footprints:TP_Pad0.75mm_Drill0.2mm"
		(layer "F.Cu")
		(at 147.6 76)
		(property "Reference" "TP14"
			(at 0.5 0.5 0)
			(layer "F.SilkS")
			(effects
				(font
					(size 0.7 0.7)
					(thickness 0.15)
				)
				(justify left bottom)
			)
		)
		(property "Value" "TP_Pad0.75mm_Drill0.2mm"
			(at 0 1.2 0)
			(layer "F.Fab")
			(effects
				(font
					(size 0.7 0.7)
					(thickness 0.15)
				)
				(justify left bottom)
			)
		)
		(property "Description" "SMT test point"
			(at 0 0 0)
			(layer "F.Fab")
			(hide yes)
			(effects
				(font
					(size 1.27 1.27)
					(thickness 0.15)
				)
			)
		)
		(property "MPN" ""
			(at 0 0 0)
			(unlocked yes)
			(layer "F.Fab")
			(hide yes)
			(effects
				(font
					(size 1 1)
					(thickness 0.15)
				)
			)
		)
		(property "Manufacturer" ""
			(at 0 0 0)
			(unlocked yes)
			(layer "F.Fab")
			(hide yes)
			(effects
				(font
					(size 1 1)
					(thickness 0.15)
				)
			)
		)
		(property "Author" "Antmicro"
			(at 0 0 0)
			(unlocked yes)
			(layer "F.Fab")
			(hide yes)
			(effects
				(font
					(size 1 1)
					(thickness 0.15)
				)
			)
		)
		(property "License" "Apache-2.0"
			(at 0 0 0)
			(unlocked yes)
			(layer "F.Fab")
			(hide yes)
			(effects
				(font
					(size 1 1)
					(thickness 0.15)
				)
			)
		)
		(sheetname "/USB-PD/")
		(sheetfile "usb-pd.kicad_sch")
		(attr exclude_from_pos_files exclude_from_bom)
		(fp_circle
			(center 0 0)
			(end 0.475 0)
			(stroke
				(width 0.05)
				(type default)
			)
			(fill no)
			(layer "F.CrtYd")
		)
		(fp_text user "License: Apache-2.0"
			(at -0.4 5.101 0)
			(layer "F.Fab")
			(effects
				(font
					(size 0.7 0.7)
					(thickness 0.15)
				)
				(justify left bottom)
			)
		)
		(fp_text user "Author: Antmicro"
			(at -0.4 3.901 0)
			(layer "F.Fab")
			(effects
				(font
					(size 0.7 0.7)
					(thickness 0.15)
				)
				(justify left bottom)
			)
		)
		(fp_text user "${REFERENCE}"
			(at -0.4 2.7 0)
			(layer "F.Fab")
			(effects
				(font
					(size 0.7 0.7)
					(thickness 0.15)
				)
				(justify left bottom)
			)
		)
		(pad "1" thru_hole circle
			(at 0 0)
			(size 0.75 0.75)
			(drill 0.2)
			(layers "*.Cu" "*.Mask")
			(remove_unused_layers no)
			(net 115 "/USB-PD/VCC")
			(pinfunction "1")
			(pintype "passive")
		)
	)
	(footprint "antmicro-footprints:QFN-24-1EP_4x4mm_P0.5mm_EP2.6x2.6mm"
		(layer "F.Cu")
		(at 150.250001 53.25 90)
		(descr "QFN, 24 Pin (http://ww1.microchip.com/downloads/en/PackagingSpec/00000049BQ.pdf#page=278), generated with kicad-footprint-generator ipc_noLead_generator.py")
		(tags "QFN NoLead")
		(property "Reference" "U5"
			(at 2.75 0.999999 180)
			(layer "F.SilkS")
			(effects
				(font
					(size 0.7 0.7)
					(thickness 0.15)
				)
				(justify left bottom)
			)
		)
		(property "Value" "CYPD3177-24LQXQ"
			(at 0 3.4 90)
			(layer "F.Fab")
			(effects
				(font
					(size 0.7 0.7)
					(thickness 0.15)
				)
				(justify left bottom)
			)
		)
		(property "Datasheet" "https://www.infineon.com/dgdl/Infineon-EZ-PD_BCR_Datasheet_USB_Type-C_Port_Controller_for_Power_Sinks-DataSheet-v03_00-EN.pdf?fileId=8ac78c8c7d0d8da4017d0ee7ce9d70ad"
			(at 0 0 90)
			(layer "F.Fab")
			(hide yes)
			(effects
				(font
					(size 1.27 1.27)
					(thickness 0.15)
				)
			)
		)
		(property "Description" "USB Interface, USB Type-C and Power Delivery (PD) Controller, USB PD 3.0, 2.7 V, 5.5 V, QFN-EP"
			(at 0 0 90)
			(layer "F.Fab")
			(hide yes)
			(effects
				(font
					(size 1.27 1.27)
					(thickness 0.15)
				)
			)
		)
		(property "MPN" "CYPD3177-24LQXQ"
			(at 0 0 90)
			(unlocked yes)
			(layer "F.Fab")
			(hide yes)
			(effects
				(font
					(size 1 1)
					(thickness 0.15)
				)
			)
		)
		(property "Manufacturer" "Infineon"
			(at 0 0 90)
			(unlocked yes)
			(layer "F.Fab")
			(hide yes)
			(effects
				(font
					(size 1 1)
					(thickness 0.15)
				)
			)
		)
		(property "Author" "Antmicro"
			(at 0 0 90)
			(unlocked yes)
			(layer "F.Fab")
			(hide yes)
			(effects
				(font
					(size 1 1)
					(thickness 0.15)
				)
			)
		)
		(property "License" "Apache-2.0"
			(at 0 0 90)
			(unlocked yes)
			(layer "F.Fab")
			(hide yes)
			(effects
				(font
					(size 1 1)
					(thickness 0.15)
				)
			)
		)
		(sheetname "/USB-PD/")
		(sheetfile "usb-pd.kicad_sch")
		(attr smd)
		(fp_line
			(start 2.108 -2.11)
			(end 2.108 -1.635)
			(stroke
				(width 0.15)
				(type solid)
			)
			(layer "F.SilkS")
		)
		(fp_line
			(start 1.634 -2.11)
			(end 2.108 -2.11)
			(stroke
				(width 0.15)
				(type solid)
			)
			(layer "F.SilkS")
		)
		(fp_line
			(start -1.635 -2.11)
			(end -2.11 -2.11)
			(stroke
				(width 0.15)
				(type solid)
			)
			(layer "F.SilkS")
		)
		(fp_line
			(start -2.11 -1.636)
			(end -2.11 -2.11)
			(stroke
				(width 0.15)
				(type solid)
			)
			(layer "F.SilkS")
		)
		(fp_line
			(start 2.108 2.108)
			(end 2.108 1.634)
			(stroke
				(width 0.15)
				(type solid)
			)
			(layer "F.SilkS")
		)
		(fp_line
			(start 1.634 2.108)
			(end 2.108 2.108)
			(stroke
				(width 0.15)
				(type solid)
			)
			(layer "F.SilkS")
		)
		(fp_line
			(start -1.635 2.108)
			(end -2.11 2.108)
			(stroke
				(width 0.15)
				(type solid)
			)
			(layer "F.SilkS")
		)
		(fp_line
			(start -2.11 2.108)
			(end -2.11 1.634)
			(stroke
				(width 0.15)
				(type solid)
			)
			(layer "F.SilkS")
		)
		(fp_circle
			(center -2.3 -2.3)
			(end -2.25 -2.3)
			(stroke
				(width 0.15)
				(type solid)
			)
			(fill yes)
			(layer "F.SilkS")
		)
		(fp_rect
			(start -2.503 -2.503)
			(end 2.5 2.5)
			(stroke
				(width 0.05)
				(type solid)
			)
			(fill no)
			(layer "F.CrtYd")
		)
		(fp_line
			(start 1.999 -2)
			(end 1.999 1.999)
			(stroke
				(width 0.15)
				(type solid)
			)
			(layer "F.Fab")
		)
		(fp_line
			(start -1 -2)
			(end 1.999 -2)
			(stroke
				(width 0.15)
				(type solid)
			)
			(layer "F.Fab")
		)
		(fp_line
			(start -2 -1)
			(end -1 -2)
			(stroke
				(width 0.15)
				(type solid)
			)
			(layer "F.Fab")
		)
		(fp_line
			(start 1.999 1.999)
			(end -2 1.999)
			(stroke
				(width 0.15)
				(type solid)
			)
			(layer "F.Fab")
		)
		(fp_line
			(start -2 1.999)
			(end -2 -1)
			(stroke
				(width 0.15)
				(type solid)
			)
			(layer "F.Fab")
		)
		(fp_text user "Author: Antmicro"
			(at -2.503 7.8 90)
			(layer "F.Fab")
			(effects
				(font
					(size 0.7 0.7)
					(thickness 0.15)
				)
				(justify left bottom)
			)
		)
		(fp_text user "${REFERENCE}"
			(at -0.0015 -0.0015 90)
			(layer "F.Fab")
			(effects
				(font
					(size 0.7 0.7)
					(thickness 0.15)
				)
				(justify left bottom)
			)
		)
		(fp_text user "License: Apache-2.0"
			(at -2.503 6.6 90)
			(layer "F.Fab")
			(effects
				(font
					(size 0.7 0.7)
					(thickness 0.15)
				)
				(justify left bottom)
			)
		)
		(pad "" smd roundrect
			(at -0.652 -0.652 90)
			(size 1.05 1.05)
			(layers "F.Paste")
			(roundrect_rratio 0.238095)
		)
		(pad "" smd roundrect
			(at -0.652 0.65 90)
			(size 1.05 1.05)
			(layers "F.Paste")
			(roundrect_rratio 0.238095)
		)
		(pad "" smd roundrect
			(at 0.65 -0.652 90)
			(size 1.05 1.05)
			(layers "F.Paste")
			(roundrect_rratio 0.238095)
		)
		(pad "" smd roundrect
			(at 0.65 0.65 90)
			(size 1.05 1.05)
			(layers "F.Paste")
			(roundrect_rratio 0.238095)
		)
		(pad "1" smd roundrect
			(at -1.938 -1.25 90)
			(size 0.825 0.25)
			(layers "F.Cu" "F.Mask" "F.Paste")
			(roundrect_rratio 0.25)
			(net 133 "/USB-PD/VBUS_MIN")
			(pinfunction "VBUS_MIN")
			(pintype "input")
		)
		(pad "2" smd roundrect
			(at -1.938 -0.75 90)
			(size 0.825 0.25)
			(layers "F.Cu" "F.Mask" "F.Paste")
			(roundrect_rratio 0.25)
			(net 136 "/USB-PD/VBUS_MAX")
			(pinfunction "VBUS_MAX")
			(pintype "input")
		)
		(pad "3" smd roundrect
			(at -1.938 -0.25 90)
			(size 0.825 0.25)
			(layers "F.Cu" "F.Mask" "F.Paste")
			(roundrect_rratio 0.25)
			(net 154 "/USB-PD/VBUS_EN")
			(pinfunction "VBUS_FET_EN")
			(pintype "output")
		)
		(pad "4" smd roundrect
			(at -1.938 0.248 90)
			(size 0.825 0.25)
			(layers "F.Cu" "F.Mask" "F.Paste")
			(roundrect_rratio 0.25)
			(net 152 "unconnected-(U5-SAFE_PWR_EN-Pad4)")
			(pinfunction "SAFE_PWR_EN")
			(pintype "output+no_connect")
		)
		(pad "5" smd roundrect
			(at -1.938 0.748 90)
			(size 0.825 0.25)
			(layers "F.Cu" "F.Mask" "F.Paste")
			(roundrect_rratio 0.25)
			(net 138 "/USB-PD/ISNK_COARSE")
			(pinfunction "ISNK_COARSE")
			(pintype "input")
		)
		(pad "6" smd roundrect
			(at -1.938 1.249 90)
			(size 0.825 0.25)
			(layers "F.Cu" "F.Mask" "F.Paste")
			(roundrect_rratio 0.25)
			(net 137 "/USB-PD/ISNK_FINE")
			(pinfunction "ISNK_FINE")
			(pintype "input")
		)
		(pad "7" smd roundrect
			(at -1.25 1.937 90)
			(size 0.25 0.825)
			(layers "F.Cu" "F.Mask" "F.Paste")
			(roundrect_rratio 0.25)
			(net 144 "/USB-PD/~{HPI_INT}")
			(pinfunction "~{HPI_INT}")
			(pintype "passive")
		)
		(pad "8" smd roundrect
			(at -0.75 1.937 90)
			(size 0.25 0.825)
			(layers "F.Cu" "F.Mask" "F.Paste")
			(roundrect_rratio 0.25)
			(net 145 "/USB-PD/GPIO_1")
			(pinfunction "GPIO_1")
			(pintype "passive")
		)
		(pad "9" smd roundrect
			(at -0.25 1.937 90)
			(size 0.25 0.825)
			(layers "F.Cu" "F.Mask" "F.Paste")
			(roundrect_rratio 0.25)
			(net 124 "/USB-PD/FAULT")
			(pinfunction "FAULT")
			(pintype "output")
		)
		(pad "10" smd roundrect
			(at 0.248 1.937 90)
			(size 0.25 0.825)
			(layers "F.Cu" "F.Mask" "F.Paste")
			(roundrect_rratio 0.25)
			(net 135 "/USB-PD/FLIP")
			(pinfunction "FLIP")
			(pintype "open_collector")
		)
		(pad "11" smd roundrect
			(at 0.748 1.937 90)
			(size 0.25 0.825)
			(layers "F.Cu" "F.Mask" "F.Paste")
			(roundrect_rratio 0.25)
			(net 115 "/USB-PD/VCC")
			(pinfunction "VDC_OUT")
			(pintype "passive")
		)
		(pad "12" smd roundrect
			(at 1.249 1.937 90)
			(size 0.25 0.825)
			(layers "F.Cu" "F.Mask" "F.Paste")
			(roundrect_rratio 0.25)
			(net 141 "/USB-PD/SDA")
			(pinfunction "HPI_SDA")
			(pintype "passive")
		)
		(pad "13" smd roundrect
			(at 1.937 1.249 90)
			(size 0.825 0.25)
			(layers "F.Cu" "F.Mask" "F.Paste")
			(roundrect_rratio 0.25)
			(net 142 "/USB-PD/SCL")
			(pinfunction "HPI_SCL")
			(pintype "passive")
		)
		(pad "14" smd roundrect
			(at 1.937 0.748 90)
			(size 0.825 0.25)
			(layers "F.Cu" "F.Mask" "F.Paste")
			(roundrect_rratio 0.25)
			(net 139 "/USB-PD/CC2")
			(pinfunction "CC2")
			(pintype "passive")
		)
		(pad "15" smd roundrect
			(at 1.937 0.248 90)
			(size 0.825 0.25)
			(layers "F.Cu" "F.Mask" "F.Paste")
			(roundrect_rratio 0.25)
			(net 140 "/USB-PD/CC1")
			(pinfunction "CC1")
			(pintype "passive")
		)
		(pad "16" smd roundrect
			(at 1.937 -0.25 90)
			(size 0.825 0.25)
			(layers "F.Cu" "F.Mask" "F.Paste")
			(roundrect_rratio 0.25)
			(net 148 "unconnected-(U5-D--Pad16)")
			(pinfunction "D-")
			(pintype "passive+no_connect")
		)
		(pad "17" smd roundrect
			(at 1.937 -0.75 90)
			(size 0.825 0.25)
			(layers "F.Cu" "F.Mask" "F.Paste")
			(roundrect_rratio 0.25)
			(net 164 "unconnected-(U5-D+-Pad17)")
			(pinfunction "D+")
			(pintype "passive+no_connect")
		)
		(pad "18" smd roundrect
			(at 1.937 -1.25 90)
			(size 0.825 0.25)
			(layers "F.Cu" "F.Mask" "F.Paste")
			(roundrect_rratio 0.25)
			(net 113 "VBUS")
			(pinfunction "VBUS_IN")
			(pintype "power_in")
		)
		(pad "19" smd roundrect
			(at 1.249 -1.938 90)
			(size 0.25 0.825)
			(layers "F.Cu" "F.Mask" "F.Paste")
			(roundrect_rratio 0.25)
			(net 66 "GND")
			(pinfunction "GND")
			(pintype "power_in")
		)
		(pad "20" smd roundrect
			(at 0.748 -1.938 90)
			(size 0.25 0.825)
			(layers "F.Cu" "F.Mask" "F.Paste")
			(roundrect_rratio 0.25)
			(net 147 "unconnected-(U5-DNU1-Pad20)")
			(pinfunction "DNU1")
			(pintype "no_connect")
		)
		(pad "21" smd roundrect
			(at 0.248 -1.938 90)
			(size 0.25 0.825)
			(layers "F.Cu" "F.Mask" "F.Paste")
			(roundrect_rratio 0.25)
			(net 146 "unconnected-(U5-DNU2-Pad21)")
			(pinfunction "DNU2")
			(pintype "no_connect")
		)
		(pad "22" smd roundrect
			(at -0.25 -1.938 90)
			(size 0.25 0.825)
			(layers "F.Cu" "F.Mask" "F.Paste")
			(roundrect_rratio 0.25)
			(net 66 "GND")
			(pinfunction "GND")
			(pintype "passive")
		)
		(pad "23" smd roundrect
			(at -0.75 -1.938 90)
			(size 0.25 0.825)
			(layers "F.Cu" "F.Mask" "F.Paste")
			(roundrect_rratio 0.25)
			(net 117 "/USB-PD/VDDD_3V3")
			(pinfunction "VDDD")
			(pintype "passive")
		)
		(pad "24" smd roundrect
			(at -1.25 -1.938 90)
			(size 0.25 0.825)
			(layers "F.Cu" "F.Mask" "F.Paste")
			(roundrect_rratio 0.25)
			(net 114 "/USB-PD/VCCD_1V8")
			(pinfunction "VCCD")
			(pintype "passive")
		)
		(pad "25" smd rect
			(at 0 0 90)
			(size 2.6 2.6)
			(layers "F.Cu" "F.Mask")
			(net 66 "GND")
			(pinfunction "GND")
			(pintype "passive")
		)
	)
	(footprint "antmicro-footprints:R_0402_1005Metric"
		(layer "F.Cu")
		(at 152.900002 47.620001 90)
		(descr "Resistor SMD 0402")
		(tags "resistor SMD 0402")
		(property "Reference" "R27"
			(at 1.020001 5.699998 90)
			(layer "F.SilkS")
			(effects
				(font
					(size 0.7 0.7)
					(thickness 0.15)
				)
				(justify right top)
			)
		)
		(property "Value" "R_10k_0402"
			(at -1.011843 1.772046 90)
			(layer "F.Fab")
			(effects
				(font
					(size 0.7 0.7)
					(thickness 0.15)
				)
				(justify left bottom)
			)
		)
		(property "Datasheet" "https://www.bourns.com/docs/product-datasheets/cr.pdf"
			(at 0 0 90)
			(layer "F.Fab")
			(hide yes)
			(effects
				(font
					(size 1.27 1.27)
					(thickness 0.15)
				)
			)
		)
		(property "Description" "SMD Chip Resistor, 10 kohm, ± 1%, 62.5 mW, 0402 [1005 Metric], Thick Film, General Purpose"
			(at 0 0 90)
			(layer "F.Fab")
			(hide yes)
			(effects
				(font
					(size 1.27 1.27)
					(thickness 0.15)
				)
			)
		)
		(property "MPN" "CR0402-FX-1002GLF"
			(at 0 0 90)
			(unlocked yes)
			(layer "F.Fab")
			(hide yes)
			(effects
				(font
					(size 1 1)
					(thickness 0.15)
				)
			)
		)
		(property "Manufacturer" "Bourns"
			(at 0 0 90)
			(unlocked yes)
			(layer "F.Fab")
			(hide yes)
			(effects
				(font
					(size 1 1)
					(thickness 0.15)
				)
			)
		)
		(property "License" "Apache-2.0"
			(at 0 0 90)
			(unlocked yes)
			(layer "F.Fab")
			(hide yes)
			(effects
				(font
					(size 1 1)
					(thickness 0.15)
				)
			)
		)
		(property "Author" "Antmicro"
			(at 0 0 90)
			(unlocked yes)
			(layer "F.Fab")
			(hide yes)
			(effects
				(font
					(size 1 1)
					(thickness 0.15)
				)
			)
		)
		(property "Val" "10k"
			(at 0 0 90)
			(unlocked yes)
			(layer "F.Fab")
			(hide yes)
			(effects
				(font
					(size 1 1)
					(thickness 0.15)
				)
			)
		)
		(property "Tolerance" "1%"
			(at 0 0 90)
			(unlocked yes)
			(layer "F.Fab")
			(hide yes)
			(effects
				(font
					(size 1 1)
					(thickness 0.15)
				)
			)
		)
		(sheetname "/USB-PD/")
		(sheetfile "usb-pd.kicad_sch")
		(attr smd)
		(fp_rect
			(start -0.925 -0.47)
			(end 0.925 0.47)
			(stroke
				(width 0.05)
				(type default)
			)
			(fill no)
			(layer "F.CrtYd")
		)
		(fp_rect
			(start -0.5 -0.25)
			(end 0.5 0.25)
			(stroke
				(width 0.15)
				(type solid)
			)
			(fill no)
			(layer "F.Fab")
		)
		(fp_text user "Author: Antmicro"
			(at -0.95 4.169 90)
			(layer "F.Fab")
			(effects
				(font
					(size 0.7 0.7)
					(thickness 0.15)
				)
				(justify left bottom)
			)
		)
		(fp_text user "${REFERENCE}"
			(at 0 0 270)
			(layer "F.Fab")
			(effects
				(font
					(size 0.7 0.7)
					(thickness 0.15)
				)
				(justify right top)
			)
		)
		(fp_text user "License: Apache-2.0"
			(at -0.949999 5.169 90)
			(layer "F.Fab")
			(effects
				(font
					(size 0.7 0.7)
					(thickness 0.15)
				)
				(justify left bottom)
			)
		)
		(pad "1" smd roundrect
			(at -0.48 0 90)
			(size 0.59 0.64)
			(layers "F.Cu" "F.Mask" "F.Paste")
			(roundrect_rratio 0.25)
			(net 84 "Net-(Q6-G)")
			(pintype "passive")
		)
		(pad "2" smd roundrect
			(at 0.48 0 90)
			(size 0.59 0.64)
			(layers "F.Cu" "F.Mask" "F.Paste")
			(roundrect_rratio 0.25)
			(net 113 "VBUS")
			(pintype "passive")
		)
	)
	(footprint "antmicro-footprints:Conn_Molex_Nano-Fit_1x2_SMD_1054301202"
		(layer "F.Cu")
		(at 154.799001 35.729 180)
		(descr "Molex Nano-Fit Power Connectors, 105430-xx02, 2 Pins per row")
		(tags "connector Molex Nano-Fit")
		(property "Reference" "J4"
			(at 3.399001 -4.871 0)
			(layer "F.SilkS")
			(effects
				(font
					(size 0.7 0.7)
					(thickness 0.15)
				)
				(justify right top)
			)
		)
		(property "Value" "Molex_Nano-Fit_1x2_SMD_1054301202"
			(at 0 7.1 0)
			(layer "F.Fab")
			(effects
				(font
					(size 0.7 0.7)
					(thickness 0.15)
				)
				(justify right top)
			)
		)
		(property "Datasheet" "https://www.farnell.com/cad/3578051.pdf"
			(at 0 0 0)
			(layer "F.Fab")
			(hide yes)
			(effects
				(font
					(size 1.27 1.27)
					(thickness 0.15)
				)
			)
		)
		(property "Description" "Pin Header, Pitch 2.5 mm, 1 Row, 2 Contacts, Nano-Fit"
			(at 0 0 0)
			(layer "F.Fab")
			(hide yes)
			(effects
				(font
					(size 1.27 1.27)
					(thickness 0.15)
				)
			)
		)
		(property "Manufacturer" "Molex"
			(at 0 0 180)
			(unlocked yes)
			(layer "F.Fab")
			(hide yes)
			(effects
				(font
					(size 1 1)
					(thickness 0.15)
				)
			)
		)
		(property "MPN" "105430-1202"
			(at 0 0 180)
			(unlocked yes)
			(layer "F.Fab")
			(hide yes)
			(effects
				(font
					(size 1 1)
					(thickness 0.15)
				)
			)
		)
		(property "Author" "Antmicro"
			(at 0 0 180)
			(unlocked yes)
			(layer "F.Fab")
			(hide yes)
			(effects
				(font
					(size 1 1)
					(thickness 0.15)
				)
			)
		)
		(property "License" "Apache-2.0"
			(at 0 0 180)
			(unlocked yes)
			(layer "F.Fab")
			(hide yes)
			(effects
				(font
					(size 1 1)
					(thickness 0.15)
				)
			)
		)
		(sheetname "/")
		(sheetfile "oculink-to-pcie-adapter.kicad_sch")
		(attr smd)
		(fp_line
			(start 4.48 2.298)
			(end 4.48 -4.5)
			(stroke
				(width 0.15)
				(type solid)
			)
			(layer "F.SilkS")
		)
		(fp_line
			(start 4.48 2.298)
			(end 4.28 2.698)
			(stroke
				(width 0.15)
				(type solid)
			)
			(layer "F.SilkS")
		)
		(fp_line
			(start 4.48 -4.5)
			(end 2.68 -4.5)
			(stroke
				(width 0.15)
				(type solid)
			)
			(layer "F.SilkS")
		)
		(fp_line
			(start 4.28 2.698)
			(end 4.28 4.299)
			(stroke
				(width 0.15)
				(type solid)
			)
			(layer "F.SilkS")
		)
		(fp_line
			(start -0.22 -4.5)
			(end 0.78 -4.5)
			(stroke
				(width 0.15)
				(type solid)
			)
			(layer "F.SilkS")
		)
		(fp_line
			(start -1.72 -4.5)
			(end -4.47 -4.5)
			(stroke
				(width 0.15)
				(type solid)
			)
			(layer "F.SilkS")
		)
		(fp_line
			(start -4.321 4.299)
			(end 4.28 4.299)
			(stroke
				(width 0.15)
				(type solid)
			)
			(layer "F.SilkS")
		)
		(fp_line
			(start -4.321 2.499)
			(end -4.321 4.299)
			(stroke
				(width 0.15)
				(type solid)
			)
			(layer "F.SilkS")
		)
		(fp_line
			(start -4.47 2.099)
			(end -4.321 2.499)
			(stroke
				(width 0.15)
				(type solid)
			)
			(layer "F.SilkS")
		)
		(fp_line
			(start -4.47 -4.5)
			(end -4.47 2.099)
			(stroke
				(width 0.15)
				(type solid)
			)
			(layer "F.SilkS")
		)
		(fp_circle
			(center 2.428 -4.91)
			(end 2.478 -4.91)
			(stroke
				(width 0.15)
				(type solid)
			)
			(fill yes)
			(layer "F.SilkS")
		)
		(fp_rect
			(start -4.77 -6.21)
			(end 4.77 6.11)
			(stroke
				(width 0.05)
				(type solid)
			)
			(fill no)
			(layer "F.CrtYd")
		)
		(fp_text user "License: Apache-2.0"
			(at -4.77 10.51 0)
			(layer "F.Fab")
			(effects
				(font
					(size 0.7 0.7)
					(thickness 0.15)
				)
				(justify right top)
			)
		)
		(fp_text user "Author: Antmicro"
			(at -4.77 9.31 0)
			(layer "F.Fab")
			(effects
				(font
					(size 0.7 0.7)
					(thickness 0.15)
				)
				(justify right top)
			)
		)
		(fp_text user "${REFERENCE}"
			(at -4.77 8.11 0)
			(layer "F.Fab")
			(effects
				(font
					(size 0.7 0.7)
					(thickness 0.15)
				)
				(justify right top)
			)
		)
		(pad "1" smd roundrect
			(at 1.528 -4.901 270)
			(size 2.5 1.24)
			(layers "F.Cu" "F.Mask" "F.Paste")
			(roundrect_rratio 0.25)
			(net 168 "/Power/VCC_DC_CONN_1")
			(pintype "passive")
		)
		(pad "2" smd roundrect
			(at -0.97 -4.901 270)
			(size 2.5 1.24)
			(layers "F.Cu" "F.Mask" "F.Paste")
			(roundrect_rratio 0.25)
			(net 66 "GND")
			(pintype "passive")
		)
		(pad "MP" smd roundrect
			(at -3.54 0.029 180)
			(size 1.1 8.2)
			(layers "F.Cu" "F.Mask" "F.Paste")
			(roundrect_rratio 0.25)
			(net 66 "GND")
			(pintype "passive")
		)
		(pad "MP" smd roundrect
			(at 3.499 0.029 180)
			(size 1.1 8.2)
			(layers "F.Cu" "F.Mask" "F.Paste")
			(roundrect_rratio 0.25)
			(net 66 "GND")
			(pintype "passive")
		)
	)
	(footprint "antmicro-footprints:USON-10_2.5x1mm_P0.5mm"
		(layer "F.Cu")
		(at 130.298 43.387 -90)
		(descr "USON-10 2.5x1mm_ Pitch 0.5mm")
		(tags "USON-10 2.5x1mm Pitch 0.5mm")
		(property "Reference" "D5"
			(at 1.113 -0.702 180)
			(layer "F.SilkS")
			(effects
				(font
					(size 0.7 0.7)
					(thickness 0.15)
				)
				(justify right top)
			)
		)
		(property "Value" "ESD204DQAR"
			(at 0.018 2.499 90)
			(layer "F.Fab")
			(effects
				(font
					(size 0.7 0.7)
					(thickness 0.15)
				)
				(justify right top)
			)
		)
		(property "Datasheet" "https://www.ti.com/lit/ds/symlink/esd204.pdf?ts=1706004844383&ref_url=https%253A%252F%252Fwww.ti.com%252Finterface%252Fdiodes%252Fesd-protection-diodes%252Fproducts.html"
			(at 0 0 90)
			(layer "F.Fab")
			(hide yes)
			(effects
				(font
					(size 1.27 1.27)
					(thickness 0.15)
				)
			)
		)
		(property "Description" "TVS diode array, 30 kV, USON-10, 3.6 V, 0.55 pF"
			(at 0 0 90)
			(layer "F.Fab")
			(hide yes)
			(effects
				(font
					(size 1.27 1.27)
					(thickness 0.15)
				)
			)
		)
		(property "MPN" "ESD204DQAR"
			(at 0 0 270)
			(unlocked yes)
			(layer "F.Fab")
			(hide yes)
			(effects
				(font
					(size 1 1)
					(thickness 0.15)
				)
			)
		)
		(property "Manufacturer" "Texas Instruments"
			(at 0 0 270)
			(unlocked yes)
			(layer "F.Fab")
			(hide yes)
			(effects
				(font
					(size 1 1)
					(thickness 0.15)
				)
			)
		)
		(property "Author" "Antmicro"
			(at 0 0 270)
			(unlocked yes)
			(layer "F.Fab")
			(hide yes)
			(effects
				(font
					(size 1 1)
					(thickness 0.15)
				)
			)
		)
		(property "License" "Apache-2.0"
			(at 0 0 270)
			(unlocked yes)
			(layer "F.Fab")
			(hide yes)
			(effects
				(font
					(size 1 1)
					(thickness 0.15)
				)
			)
		)
		(sheetname "/OCuLink/")
		(sheetfile "oculink.kicad_sch")
		(attr smd)
		(fp_line
			(start 0.498 1.398)
			(end -0.5 1.398)
			(stroke
				(width 0.15)
				(type solid)
			)
			(layer "F.SilkS")
		)
		(fp_line
			(start 0.498 -1.401)
			(end -0.5 -1.401)
			(stroke
				(width 0.15)
				(type solid)
			)
			(layer "F.SilkS")
		)
		(fp_circle
			(center -0.68 -1.27)
			(end -0.63 -1.27)
			(stroke
				(width 0.15)
				(type solid)
			)
			(fill yes)
			(layer "F.SilkS")
		)
		(fp_rect
			(start -0.8 -1.5)
			(end 0.8 1.499)
			(stroke
				(width 0.05)
				(type solid)
			)
			(fill no)
			(layer "F.CrtYd")
		)
		(fp_line
			(start -0.5 1.249)
			(end 0.498 1.249)
			(stroke
				(width 0.15)
				(type solid)
			)
			(layer "F.Fab")
		)
		(fp_line
			(start -0.5 -1)
			(end -0.5 1.249)
			(stroke
				(width 0.15)
				(type solid)
			)
			(layer "F.Fab")
		)
		(fp_line
			(start -0.25 -1.25)
			(end -0.5 -1)
			(stroke
				(width 0.15)
				(type solid)
			)
			(layer "F.Fab")
		)
		(fp_line
			(start 0.498 -1.25)
			(end 0.498 1.249)
			(stroke
				(width 0.15)
				(type solid)
			)
			(layer "F.Fab")
		)
		(fp_line
			(start 0.498 -1.25)
			(end -0.25 -1.25)
			(stroke
				(width 0.15)
				(type solid)
			)
			(layer "F.Fab")
		)
		(fp_text user "License: Apache-2.0"
			(at -0.802 6.9 90)
			(layer "F.Fab")
			(effects
				(font
					(size 0.7 0.7)
					(thickness 0.15)
				)
				(justify right top)
			)
		)
		(fp_text user "${REFERENCE}"
			(at 0 -0.000501 90)
			(layer "F.Fab")
			(effects
				(font
					(size 0.7 0.7)
					(thickness 0.15)
				)
				(justify right top)
			)
		)
		(fp_text user "Author: Antmicro"
			(at -0.802 5.7 90)
			(layer "F.Fab")
			(effects
				(font
					(size 0.7 0.7)
					(thickness 0.15)
				)
				(justify right top)
			)
		)
		(pad "1" smd roundrect
			(at -0.387 -1 180)
			(size 0.25 0.55)
			(layers "F.Cu" "F.Mask" "F.Paste")
			(roundrect_rratio 0.25)
			(net 78 "/OCuLink/PCIe_{x4}.RX0+")
			(pintype "passive")
		)
		(pad "2" smd roundrect
			(at -0.387 -0.5 180)
			(size 0.25 0.55)
			(layers "F.Cu" "F.Mask" "F.Paste")
			(roundrect_rratio 0.25)
			(net 73 "/OCuLink/PCIe_{x4}.RX0-")
			(pintype "passive")
		)
		(pad "3" smd roundrect
			(at -0.387 0 180)
			(size 0.4 0.55)
			(layers "F.Cu" "F.Mask" "F.Paste")
			(roundrect_rratio 0.25)
			(net 66 "GND")
			(pintype "power_in")
		)
		(pad "4" smd roundrect
			(at -0.387 0.498 180)
			(size 0.25 0.55)
			(layers "F.Cu" "F.Mask" "F.Paste")
			(roundrect_rratio 0.25)
			(net 75 "/OCuLink/PCIe_{x4}.RX1+")
			(pintype "passive")
		)
		(pad "5" smd roundrect
			(at -0.387 0.998 180)
			(size 0.25 0.55)
			(layers "F.Cu" "F.Mask" "F.Paste")
			(roundrect_rratio 0.25)
			(net 71 "/OCuLink/PCIe_{x4}.RX1-")
			(pintype "passive")
		)
		(pad "6" smd roundrect
			(at 0.385 0.998 180)
			(size 0.25 0.55)
			(layers "F.Cu" "F.Mask" "F.Paste")
			(roundrect_rratio 0.25)
			(net 71 "/OCuLink/PCIe_{x4}.RX1-")
			(pintype "passive")
		)
		(pad "7" smd roundrect
			(at 0.385 0.498 180)
			(size 0.25 0.55)
			(layers "F.Cu" "F.Mask" "F.Paste")
			(roundrect_rratio 0.25)
			(net 75 "/OCuLink/PCIe_{x4}.RX1+")
			(pintype "passive")
		)
		(pad "8" smd roundrect
			(at 0.385 0 180)
			(size 0.4 0.55)
			(layers "F.Cu" "F.Mask" "F.Paste")
			(roundrect_rratio 0.25)
			(net 66 "GND")
			(pintype "passive")
		)
		(pad "9" smd roundrect
			(at 0.385 -0.5 180)
			(size 0.25 0.55)
			(layers "F.Cu" "F.Mask" "F.Paste")
			(roundrect_rratio 0.25)
			(net 73 "/OCuLink/PCIe_{x4}.RX0-")
			(pintype "passive")
		)
		(pad "10" smd roundrect
			(at 0.385 -1 180)
			(size 0.25 0.55)
			(layers "F.Cu" "F.Mask" "F.Paste")
			(roundrect_rratio 0.25)
			(net 78 "/OCuLink/PCIe_{x4}.RX0+")
			(pintype "passive")
		)
	)
	(footprint "antmicro-footprints:C_0402_1005Metric"
		(layer "F.Cu")
		(at 146.562001 52.001)
		(descr "Capacitor SMD 0402")
		(tags "capacitor SMD 0402")
		(property "Reference" "C39"
			(at -3.162001 2.899 180)
			(layer "F.SilkS")
			(effects
				(font
					(size 0.7 0.7)
					(thickness 0.15)
				)
				(justify left bottom)
			)
		)
		(property "Value" "C_1u_25V_0402"
			(at -1.022927 2.155213 0)
			(layer "F.Fab")
			(effects
				(font
					(size 0.7 0.7)
					(thickness 0.15)
				)
				(justify left bottom)
			)
		)
		(property "Datasheet" "https://www.murata.com/products/productdetail?partno=GRM155R61E105KE11%23"
			(at 0 0 0)
			(layer "F.Fab")
			(hide yes)
			(effects
				(font
					(size 1.27 1.27)
					(thickness 0.15)
				)
			)
		)
		(property "Description" "SMD Multilayer Ceramic Capacitor, 1 µF, 25 V, 0402 [1005 Metric], ± 10%, X5R, GRM Series"
			(at 0 0 0)
			(layer "F.Fab")
			(hide yes)
			(effects
				(font
					(size 1.27 1.27)
					(thickness 0.15)
				)
			)
		)
		(property "MPN" "GRM155R61E105KE11J"
			(at 0 0 0)
			(unlocked yes)
			(layer "F.Fab")
			(hide yes)
			(effects
				(font
					(size 1 1)
					(thickness 0.15)
				)
			)
		)
		(property "Manufacturer" "Murata"
			(at 0 0 0)
			(unlocked yes)
			(layer "F.Fab")
			(hide yes)
			(effects
				(font
					(size 1 1)
					(thickness 0.15)
				)
			)
		)
		(property "License" "Apache-2.0"
			(at 0 0 0)
			(unlocked yes)
			(layer "F.Fab")
			(hide yes)
			(effects
				(font
					(size 1 1)
					(thickness 0.15)
				)
			)
		)
		(property "Author" "Antmicro"
			(at 0 0 0)
			(unlocked yes)
			(layer "F.Fab")
			(hide yes)
			(effects
				(font
					(size 1 1)
					(thickness 0.15)
				)
			)
		)
		(property "Val" "1u"
			(at 0 0 0)
			(unlocked yes)
			(layer "F.Fab")
			(hide yes)
			(effects
				(font
					(size 1 1)
					(thickness 0.15)
				)
			)
		)
		(property "Voltage" "25V"
			(at 0 0 0)
			(unlocked yes)
			(layer "F.Fab")
			(hide yes)
			(effects
				(font
					(size 1 1)
					(thickness 0.15)
				)
			)
		)
		(property "Dielectric" "X5R"
			(at 0 0 0)
			(unlocked yes)
			(layer "F.Fab")
			(hide yes)
			(effects
				(font
					(size 1 1)
					(thickness 0.15)
				)
			)
		)
		(sheetname "/USB-PD/")
		(sheetfile "usb-pd.kicad_sch")
		(attr smd)
		(fp_rect
			(start -0.925 -0.47)
			(end 0.925 0.47)
			(stroke
				(width 0.05)
				(type default)
			)
			(fill no)
			(layer "F.CrtYd")
		)
		(fp_line
			(start -0.494 -0.25)
			(end 0.504 -0.25)
			(stroke
				(width 0.15)
				(type solid)
			)
			(layer "F.Fab")
		)
		(fp_line
			(start -0.494 0.248)
			(end -0.494 -0.25)
			(stroke
				(width 0.15)
				(type solid)
			)
			(layer "F.Fab")
		)
		(fp_line
			(start 0.504 -0.25)
			(end 0.504 0.248)
			(stroke
				(width 0.15)
				(type solid)
			)
			(layer "F.Fab")
		)
		(fp_line
			(start 0.504 0.248)
			(end -0.494 0.248)
			(stroke
				(width 0.15)
				(type solid)
			)
			(layer "F.Fab")
		)
		(fp_text user "${REFERENCE}"
			(at 0 0 0)
			(layer "F.Fab")
			(effects
				(font
					(size 0.7 0.7)
					(thickness 0.15)
				)
				(justify left bottom)
			)
		)
		(fp_text user "Author: Antmicro"
			(at -0.939 3.399 0)
			(layer "F.Fab")
			(effects
				(font
					(size 0.7 0.7)
					(thickness 0.15)
				)
				(justify left bottom)
			)
		)
		(fp_text user "License: Apache-2.0"
			(at -0.939 5.799 0)
			(layer "F.Fab")
			(effects
				(font
					(size 0.7 0.7)
					(thickness 0.15)
				)
				(justify left bottom)
			)
		)
		(pad "1" smd roundrect
			(at -0.48 0)
			(size 0.59 0.64)
			(layers "F.Cu" "F.Mask" "F.Paste")
			(roundrect_rratio 0.25)
			(net 66 "GND")
			(pintype "passive")
		)
		(pad "2" smd roundrect
			(at 0.48 0)
			(size 0.59 0.64)
			(layers "F.Cu" "F.Mask" "F.Paste")
			(roundrect_rratio 0.25)
			(net 117 "/USB-PD/VDDD_3V3")
			(pintype "passive")
		)
	)
	(footprint "antmicro-footprints:R_0402_1005Metric"
		(layer "F.Cu")
		(at 126.332999 152.076999 -90)
		(descr "Resistor SMD 0402")
		(tags "resistor SMD 0402")
		(property "Reference" "R41"
			(at 0.923 0.332999 270)
			(layer "F.SilkS")
			(effects
				(font
					(size 0.7 0.7)
					(thickness 0.15)
				)
				(justify right top)
			)
		)
		(property "Value" "R_0R_0402"
			(at -1.011843 1.772046 90)
			(layer "F.Fab")
			(effects
				(font
					(size 0.7 0.7)
					(thickness 0.15)
				)
				(justify right top)
			)
		)
		(property "Datasheet" "https://industrial.panasonic.com/cdbs/www-data/pdf/RDA0000/AOA0000C301.pdf"
			(at 0 0 90)
			(layer "F.Fab")
			(hide yes)
			(effects
				(font
					(size 1.27 1.27)
					(thickness 0.15)
				)
			)
		)
		(property "Description" "SMD Chip Resistor, Jumper, 0 ohm, 100 mW, 0402 [1005 Metric], Thick Film, General Purpose"
			(at 0 0 90)
			(layer "F.Fab")
			(hide yes)
			(effects
				(font
					(size 1.27 1.27)
					(thickness 0.15)
				)
			)
		)
		(property "MPN" "ERJ2GE0R00X"
			(at 0 0 270)
			(unlocked yes)
			(layer "F.Fab")
			(hide yes)
			(effects
				(font
					(size 1 1)
					(thickness 0.15)
				)
			)
		)
		(property "Manufacturer" "Panasonic"
			(at 0 0 270)
			(unlocked yes)
			(layer "F.Fab")
			(hide yes)
			(effects
				(font
					(size 1 1)
					(thickness 0.15)
				)
			)
		)
		(property "License" "Apache-2.0"
			(at 0 0 270)
			(unlocked yes)
			(layer "F.Fab")
			(hide yes)
			(effects
				(font
					(size 1 1)
					(thickness 0.15)
				)
			)
		)
		(property "Author" "Antmicro"
			(at 0 0 270)
			(unlocked yes)
			(layer "F.Fab")
			(hide yes)
			(effects
				(font
					(size 1 1)
					(thickness 0.15)
				)
			)
		)
		(property "Val" "0R"
			(at 0 0 270)
			(unlocked yes)
			(layer "F.Fab")
			(hide yes)
			(effects
				(font
					(size 1 1)
					(thickness 0.15)
				)
			)
		)
		(property "Tolerance" ""
			(at 0 0 270)
			(unlocked yes)
			(layer "F.Fab")
			(hide yes)
			(effects
				(font
					(size 1 1)
					(thickness 0.15)
				)
			)
		)
		(property "Current" "1A"
			(at 0 0 270)
			(unlocked yes)
			(layer "F.Fab")
			(hide yes)
			(effects
				(font
					(size 1 1)
					(thickness 0.15)
				)
			)
		)
		(sheetname "/Power/")
		(sheetfile "power.kicad_sch")
		(attr smd dnp)
		(fp_rect
			(start -0.925 -0.47)
			(end 0.925 0.47)
			(stroke
				(width 0.05)
				(type default)
			)
			(fill no)
			(layer "F.CrtYd")
		)
		(fp_rect
			(start -0.5 -0.25)
			(end 0.5 0.25)
			(stroke
				(width 0.15)
				(type solid)
			)
			(fill no)
			(layer "F.Fab")
		)
		(fp_text user "${REFERENCE}"
			(at 0 0 90)
			(layer "F.Fab")
			(effects
				(font
					(size 0.7 0.7)
					(thickness 0.15)
				)
				(justify right top)
			)
		)
		(fp_text user "Author: Antmicro"
			(at -0.95 4.169 90)
			(layer "F.Fab")
			(effects
				(font
					(size 0.7 0.7)
					(thickness 0.15)
				)
				(justify right top)
			)
		)
		(fp_text user "License: Apache-2.0"
			(at -0.949999 5.169 90)
			(layer "F.Fab")
			(effects
				(font
					(size 0.7 0.7)
					(thickness 0.15)
				)
				(justify right top)
			)
		)
		(pad "1" smd roundrect
			(at -0.48 0 270)
			(size 0.59 0.64)
			(layers "F.Cu" "F.Mask" "F.Paste")
			(roundrect_rratio 0.25)
			(net 185 "/Power/~{PERST_CONN}")
			(pintype "passive")
		)
		(pad "2" smd roundrect
			(at 0.48 0 270)
			(size 0.59 0.64)
			(layers "F.Cu" "F.Mask" "F.Paste")
			(roundrect_rratio 0.25)
			(net 172 "/Power/~{PERST}")
			(pintype "passive")
		)
	)
	(footprint "antmicro-footprints:R_0402_1005Metric"
		(layer "F.Cu")
		(at 142.721321 50.8 -90)
		(descr "Resistor SMD 0402")
		(tags "resistor SMD 0402")
		(property "Reference" "R50"
			(at 0.95 0.321321 270)
			(layer "F.SilkS")
			(effects
				(font
					(size 0.7 0.7)
					(thickness 0.15)
				)
				(justify right top)
			)
		)
		(property "Value" "R_0R_0402"
			(at -1.011843 1.772046 90)
			(layer "F.Fab")
			(effects
				(font
					(size 0.7 0.7)
					(thickness 0.15)
				)
				(justify right top)
			)
		)
		(property "Datasheet" "https://industrial.panasonic.com/cdbs/www-data/pdf/RDA0000/AOA0000C301.pdf"
			(at 0 0 90)
			(layer "F.Fab")
			(hide yes)
			(effects
				(font
					(size 1.27 1.27)
					(thickness 0.15)
				)
			)
		)
		(property "Description" "SMD Chip Resistor, Jumper, 0 ohm, 100 mW, 0402 [1005 Metric], Thick Film, General Purpose"
			(at 0 0 90)
			(layer "F.Fab")
			(hide yes)
			(effects
				(font
					(size 1.27 1.27)
					(thickness 0.15)
				)
			)
		)
		(property "MPN" "ERJ2GE0R00X"
			(at 0 0 270)
			(unlocked yes)
			(layer "F.Fab")
			(hide yes)
			(effects
				(font
					(size 1 1)
					(thickness 0.15)
				)
			)
		)
		(property "Manufacturer" "Panasonic"
			(at 0 0 270)
			(unlocked yes)
			(layer "F.Fab")
			(hide yes)
			(effects
				(font
					(size 1 1)
					(thickness 0.15)
				)
			)
		)
		(property "License" "Apache-2.0"
			(at 0 0 270)
			(unlocked yes)
			(layer "F.Fab")
			(hide yes)
			(effects
				(font
					(size 1 1)
					(thickness 0.15)
				)
			)
		)
		(property "Author" "Antmicro"
			(at 0 0 270)
			(unlocked yes)
			(layer "F.Fab")
			(hide yes)
			(effects
				(font
					(size 1 1)
					(thickness 0.15)
				)
			)
		)
		(property "Val" "0R"
			(at 0 0 270)
			(unlocked yes)
			(layer "F.Fab")
			(hide yes)
			(effects
				(font
					(size 1 1)
					(thickness 0.15)
				)
			)
		)
		(property "Tolerance" ""
			(at 0 0 270)
			(unlocked yes)
			(layer "F.Fab")
			(hide yes)
			(effects
				(font
					(size 1 1)
					(thickness 0.15)
				)
			)
		)
		(property "Current" "1A"
			(at 0 0 270)
			(unlocked yes)
			(layer "F.Fab")
			(hide yes)
			(effects
				(font
					(size 1 1)
					(thickness 0.15)
				)
			)
		)
		(sheetname "/OCuLink/")
		(sheetfile "oculink.kicad_sch")
		(attr smd)
		(fp_rect
			(start -0.925 -0.47)
			(end 0.925 0.47)
			(stroke
				(width 0.05)
				(type default)
			)
			(fill no)
			(layer "F.CrtYd")
		)
		(fp_rect
			(start -0.5 -0.25)
			(end 0.5 0.25)
			(stroke
				(width 0.15)
				(type solid)
			)
			(fill no)
			(layer "F.Fab")
		)
		(fp_text user "License: Apache-2.0"
			(at -0.949999 5.169 90)
			(layer "F.Fab")
			(effects
				(font
					(size 0.7 0.7)
					(thickness 0.15)
				)
				(justify right top)
			)
		)
		(fp_text user "${REFERENCE}"
			(at 0 0 90)
			(layer "F.Fab")
			(effects
				(font
					(size 0.7 0.7)
					(thickness 0.15)
				)
				(justify right top)
			)
		)
		(fp_text user "Author: Antmicro"
			(at -0.95 4.169 90)
			(layer "F.Fab")
			(effects
				(font
					(size 0.7 0.7)
					(thickness 0.15)
				)
				(justify right top)
			)
		)
		(pad "1" smd roundrect
			(at -0.48 0 270)
			(size 0.59 0.64)
			(layers "F.Cu" "F.Mask" "F.Paste")
			(roundrect_rratio 0.25)
			(net 183 "/OCuLink/~{PERSTC}")
			(pintype "passive")
		)
		(pad "2" smd roundrect
			(at 0.48 0 270)
			(size 0.59 0.64)
			(layers "F.Cu" "F.Mask" "F.Paste")
			(roundrect_rratio 0.25)
			(net 185 "/Power/~{PERST_CONN}")
			(pintype "passive")
		)
	)
	(footprint "antmicro-footprints:F_1206_3216Metric"
		(layer "F.Cu")
		(at 142.999999 137.6 180)
		(property "Reference" "F2"
			(at 2.399999 0.4 180)
			(layer "F.SilkS")
			(effects
				(font
					(size 0.7 0.7)
					(thickness 0.15)
				)
				(justify right top)
			)
		)
		(property "Value" "F_7A_1206"
			(at 0 2.000001 0)
			(layer "F.Fab")
			(effects
				(font
					(size 0.7 0.7)
					(thickness 0.15)
				)
				(justify right top)
			)
		)
		(property "Datasheet" "https://us.schurter.com/pdf/english/typ_UST_1206.pdf"
			(at 0 0 0)
			(layer "F.Fab")
			(hide yes)
			(effects
				(font
					(size 1.27 1.27)
					(thickness 0.15)
				)
			)
		)
		(property "Description" "7 A 32 V AC 63 V DC Fuse Board Mount (Cartridge Style Excluded) Surface Mount 1206 (3216 Metric)"
			(at 0 0 0)
			(layer "F.Fab")
			(hide yes)
			(effects
				(font
					(size 1.27 1.27)
					(thickness 0.15)
				)
			)
		)
		(property "Manufacturer" "Schurter"
			(at 0 0 180)
			(unlocked yes)
			(layer "F.Fab")
			(hide yes)
			(effects
				(font
					(size 1 1)
					(thickness 0.15)
				)
			)
		)
		(property "MPN" "3413.0326.11"
			(at 0 0 180)
			(unlocked yes)
			(layer "F.Fab")
			(hide yes)
			(effects
				(font
					(size 1 1)
					(thickness 0.15)
				)
			)
		)
		(property "Author" "Antmicro"
			(at 0 0 180)
			(unlocked yes)
			(layer "F.Fab")
			(hide yes)
			(effects
				(font
					(size 1 1)
					(thickness 0.15)
				)
			)
		)
		(property "License" "Apache-2.0"
			(at 0 0 180)
			(unlocked yes)
			(layer "F.Fab")
			(hide yes)
			(effects
				(font
					(size 1 1)
					(thickness 0.15)
				)
			)
		)
		(sheetname "/Power/")
		(sheetfile "power.kicad_sch")
		(attr smd)
		(fp_line
			(start 0.8 0.901)
			(end -0.8 0.901)
			(stroke
				(width 0.15)
				(type solid)
			)
			(layer "F.SilkS")
		)
		(fp_line
			(start 0.8 -0.899)
			(end -0.8 -0.899)
			(stroke
				(width 0.15)
				(type solid)
			)
			(layer "F.SilkS")
		)
		(fp_rect
			(start -2.325 -1.15)
			(end 2.325 1.15)
			(stroke
				(width 0.05)
				(type default)
			)
			(fill no)
			(layer "F.CrtYd")
		)
		(fp_line
			(start 1.624 0.792)
			(end -1.677 0.792)
			(stroke
				(width 0.15)
				(type solid)
			)
			(layer "F.Fab")
		)
		(fp_line
			(start 1.624 -0.861)
			(end 1.624 0.792)
			(stroke
				(width 0.15)
				(type solid)
			)
			(layer "F.Fab")
		)
		(fp_line
			(start -1.677 0.792)
			(end -1.677 -0.861)
			(stroke
				(width 0.15)
				(type solid)
			)
			(layer "F.Fab")
		)
		(fp_line
			(start -1.677 -0.861)
			(end 1.624 -0.861)
			(stroke
				(width 0.15)
				(type solid)
			)
			(layer "F.Fab")
		)
		(fp_text user "${REFERENCE}"
			(at 0 0 0)
			(layer "F.Fab")
			(effects
				(font
					(size 0.7 0.7)
					(thickness 0.15)
				)
				(justify right top)
			)
		)
		(fp_text user "License: Apache-2.0"
			(at -1.95 5.2 0)
			(layer "F.Fab")
			(effects
				(font
					(size 0.7 0.7)
					(thickness 0.15)
				)
				(justify right top)
			)
		)
		(fp_text user "Author: Antmicro"
			(at -1.95 6.4 0)
			(layer "F.Fab")
			(effects
				(font
					(size 0.7 0.7)
					(thickness 0.15)
				)
				(justify right top)
			)
		)
		(pad "1" smd roundrect
			(at -1.5 0.001 180)
			(size 1.15 1.8)
			(layers "F.Cu" "F.Mask" "F.Paste")
			(roundrect_rratio 0.25)
			(net 169 "/Power/VCC_DC_CONN_2")
			(pintype "passive")
		)
		(pad "2" smd roundrect
			(at 1.5 0.001 180)
			(size 1.15 1.8)
			(layers "F.Cu" "F.Mask" "F.Paste")
			(roundrect_rratio 0.25)
			(net 116 "/Power/Ideal-diode-2/VIN")
			(pintype "passive")
		)
	)
	(footprint "antmicro-footprints:R_0402_1005Metric"
		(layer "F.Cu")
		(at 152.737001 57.376 -90)
		(descr "Resistor SMD 0402")
		(tags "resistor SMD 0402")
		(property "Reference" "R24"
			(at 1.074 0.361 90)
			(layer "F.SilkS")
			(effects
				(font
					(size 0.7 0.7)
					(thickness 0.15)
				)
				(justify right top)
			)
		)
		(property "Value" "R_1k_0402"
			(at -1.011843 1.772046 90)
			(layer "F.Fab")
			(effects
				(font
					(size 0.7 0.7)
					(thickness 0.15)
				)
				(justify right top)
			)
		)
		(property "Datasheet" "https://www.bourns.com/docs/product-datasheets/cr.pdf"
			(at 0 0 90)
			(layer "F.Fab")
			(hide yes)
			(effects
				(font
					(size 1.27 1.27)
					(thickness 0.15)
				)
			)
		)
		(property "Description" "SMD Chip Resistor, 1 kohm, ± 1%, 63 mW, 0402 [1005 Metric], Thick Film, General Purpose"
			(at 0 0 90)
			(layer "F.Fab")
			(hide yes)
			(effects
				(font
					(size 1.27 1.27)
					(thickness 0.15)
				)
			)
		)
		(property "MPN" "CR0402-FX-1001GLF"
			(at 0 0 270)
			(unlocked yes)
			(layer "F.Fab")
			(hide yes)
			(effects
				(font
					(size 1 1)
					(thickness 0.15)
				)
			)
		)
		(property "Manufacturer" "Bourns"
			(at 0 0 270)
			(unlocked yes)
			(layer "F.Fab")
			(hide yes)
			(effects
				(font
					(size 1 1)
					(thickness 0.15)
				)
			)
		)
		(property "License" "Apache-2.0"
			(at 0 0 270)
			(unlocked yes)
			(layer "F.Fab")
			(hide yes)
			(effects
				(font
					(size 1 1)
					(thickness 0.15)
				)
			)
		)
		(property "Author" "Antmicro"
			(at 0 0 270)
			(unlocked yes)
			(layer "F.Fab")
			(hide yes)
			(effects
				(font
					(size 1 1)
					(thickness 0.15)
				)
			)
		)
		(property "Val" "1k"
			(at 0 0 270)
			(unlocked yes)
			(layer "F.Fab")
			(hide yes)
			(effects
				(font
					(size 1 1)
					(thickness 0.15)
				)
			)
		)
		(property "Tolerance" "1%"
			(at 0 0 270)
			(unlocked yes)
			(layer "F.Fab")
			(hide yes)
			(effects
				(font
					(size 1 1)
					(thickness 0.15)
				)
			)
		)
		(sheetname "/USB-PD/")
		(sheetfile "usb-pd.kicad_sch")
		(attr smd exclude_from_bom dnp)
		(fp_rect
			(start -0.925 -0.47)
			(end 0.925 0.47)
			(stroke
				(width 0.05)
				(type default)
			)
			(fill no)
			(layer "F.CrtYd")
		)
		(fp_rect
			(start -0.5 -0.25)
			(end 0.5 0.25)
			(stroke
				(width 0.15)
				(type solid)
			)
			(fill no)
			(layer "F.Fab")
		)
		(fp_text user "Author: Antmicro"
			(at -0.95 4.169 90)
			(layer "F.Fab")
			(effects
				(font
					(size 0.7 0.7)
					(thickness 0.15)
				)
				(justify right top)
			)
		)
		(fp_text user "${REFERENCE}"
			(at 0 0 90)
			(layer "F.Fab")
			(effects
				(font
					(size 0.7 0.7)
					(thickness 0.15)
				)
				(justify right top)
			)
		)
		(fp_text user "License: Apache-2.0"
			(at -0.949999 5.169 90)
			(layer "F.Fab")
			(effects
				(font
					(size 0.7 0.7)
					(thickness 0.15)
				)
				(justify right top)
			)
		)
		(pad "1" smd roundrect
			(at -0.48 0 270)
			(size 0.59 0.64)
			(layers "F.Cu" "F.Mask" "F.Paste")
			(roundrect_rratio 0.25)
			(net 137 "/USB-PD/ISNK_FINE")
			(pintype "passive")
		)
		(pad "2" smd roundrect
			(at 0.48 0 270)
			(size 0.59 0.64)
			(layers "F.Cu" "F.Mask" "F.Paste")
			(roundrect_rratio 0.25)
			(net 117 "/USB-PD/VDDD_3V3")
			(pintype "passive")
		)
	)
	(footprint "antmicro-footprints:R_0402_1005Metric"
		(layer "F.Cu")
		(at 120.499999 131.8 180)
		(descr "Resistor SMD 0402")
		(tags "resistor SMD 0402")
		(property "Reference" "R9"
			(at 3.299999 0.4 180)
			(layer "F.SilkS")
			(effects
				(font
					(size 0.7 0.7)
					(thickness 0.15)
				)
				(justify left top)
			)
		)
		(property "Value" "R_68k_0402"
			(at -1.011843 1.772046 0)
			(layer "F.Fab")
			(effects
				(font
					(size 0.7 0.7)
					(thickness 0.15)
				)
				(justify right top)
			)
		)
		(property "Datasheet" "https://www.bourns.com/docs/product-datasheets/cr.pdf"
			(at 0 0 0)
			(layer "F.Fab")
			(hide yes)
			(effects
				(font
					(size 1.27 1.27)
					(thickness 0.15)
				)
			)
		)
		(property "Description" "SMD Chip Resistor"
			(at 0 0 0)
			(layer "F.Fab")
			(hide yes)
			(effects
				(font
					(size 1.27 1.27)
					(thickness 0.15)
				)
			)
		)
		(property "MPN" "CR0402-FX-6802GLF"
			(at 0 0 180)
			(unlocked yes)
			(layer "F.Fab")
			(hide yes)
			(effects
				(font
					(size 1 1)
					(thickness 0.15)
				)
			)
		)
		(property "Manufacturer" "Bourns"
			(at 0 0 180)
			(unlocked yes)
			(layer "F.Fab")
			(hide yes)
			(effects
				(font
					(size 1 1)
					(thickness 0.15)
				)
			)
		)
		(property "License" "Apache-2.0"
			(at 0 0 180)
			(unlocked yes)
			(layer "F.Fab")
			(hide yes)
			(effects
				(font
					(size 1 1)
					(thickness 0.15)
				)
			)
		)
		(property "Author" "Antmicro"
			(at 0 0 180)
			(unlocked yes)
			(layer "F.Fab")
			(hide yes)
			(effects
				(font
					(size 1 1)
					(thickness 0.15)
				)
			)
		)
		(property "Val" "68k"
			(at 0 0 180)
			(unlocked yes)
			(layer "F.Fab")
			(hide yes)
			(effects
				(font
					(size 1 1)
					(thickness 0.15)
				)
			)
		)
		(property "Tolerance" "1%"
			(at 0 0 180)
			(unlocked yes)
			(layer "F.Fab")
			(hide yes)
			(effects
				(font
					(size 1 1)
					(thickness 0.15)
				)
			)
		)
		(sheetname "/Power/")
		(sheetfile "power.kicad_sch")
		(attr smd)
		(fp_rect
			(start -0.925 -0.47)
			(end 0.925 0.47)
			(stroke
				(width 0.05)
				(type default)
			)
			(fill no)
			(layer "F.CrtYd")
		)
		(fp_rect
			(start -0.5 -0.25)
			(end 0.5 0.25)
			(stroke
				(width 0.15)
				(type solid)
			)
			(fill no)
			(layer "F.Fab")
		)
		(fp_text user "${REFERENCE}"
			(at 0 0 0)
			(layer "F.Fab")
			(effects
				(font
					(size 0.7 0.7)
					(thickness 0.15)
				)
				(justify right top)
			)
		)
		(fp_text user "License: Apache-2.0"
			(at -0.949999 5.169 0)
			(layer "F.Fab")
			(effects
				(font
					(size 0.7 0.7)
					(thickness 0.15)
				)
				(justify right top)
			)
		)
		(fp_text user "Author: Antmicro"
			(at -0.95 4.169 0)
			(layer "F.Fab")
			(effects
				(font
					(size 0.7 0.7)
					(thickness 0.15)
				)
				(justify right top)
			)
		)
		(pad "1" smd roundrect
			(at -0.48 0 180)
			(size 0.59 0.64)
			(layers "F.Cu" "F.Mask" "F.Paste")
			(roundrect_rratio 0.25)
			(net 108 "/Power/3V3_FB")
			(pintype "passive")
		)
		(pad "2" smd roundrect
			(at 0.48 0 180)
			(size 0.59 0.64)
			(layers "F.Cu" "F.Mask" "F.Paste")
			(roundrect_rratio 0.25)
			(net 186 "/Power/3V3_CONV")
			(pintype "passive")
		)
	)
	(footprint "antmicro-footprints:QFN-20-1EP_3x3mm_P0.45mm"
		(layer "F.Cu")
		(at 123.75 133.025001 180)
		(property "Reference" "U1"
			(at -0.65 2.825001 180)
			(layer "F.SilkS")
			(effects
				(font
					(size 0.7 0.7)
					(thickness 0.15)
				)
				(justify right top)
			)
		)
		(property "Value" "TPS56C230"
			(at 0 2.897999 0)
			(layer "F.Fab")
			(effects
				(font
					(size 0.7 0.7)
					(thickness 0.15)
				)
				(justify right top)
			)
		)
		(property "Datasheet" "https://www.ti.com/lit/ds/symlink/tps56c230.pdf"
			(at 0 0 0)
			(layer "F.Fab")
			(hide yes)
			(effects
				(font
					(size 1.27 1.27)
					(thickness 0.15)
				)
			)
		)
		(property "Description" "DC/DC converter"
			(at 0 0 0)
			(layer "F.Fab")
			(hide yes)
			(effects
				(font
					(size 1.27 1.27)
					(thickness 0.15)
				)
			)
		)
		(property "Manufacturer" "Texas Instruments"
			(at 0 0 180)
			(unlocked yes)
			(layer "F.Fab")
			(hide yes)
			(effects
				(font
					(size 1 1)
					(thickness 0.15)
				)
			)
		)
		(property "MPN" "TPS56C230RJER"
			(at 0 0 180)
			(unlocked yes)
			(layer "F.Fab")
			(hide yes)
			(effects
				(font
					(size 1 1)
					(thickness 0.15)
				)
			)
		)
		(property "Author" "Antmicro"
			(at 0 0 180)
			(unlocked yes)
			(layer "F.Fab")
			(hide yes)
			(effects
				(font
					(size 1 1)
					(thickness 0.15)
				)
			)
		)
		(property "License" "Apache-2.0"
			(at 0 0 180)
			(unlocked yes)
			(layer "F.Fab")
			(hide yes)
			(effects
				(font
					(size 1 1)
					(thickness 0.15)
				)
			)
		)
		(sheetname "/Power/")
		(sheetfile "power.kicad_sch")
		(attr smd)
		(fp_line
			(start 1.5 -1.5)
			(end 1.5 -1.2)
			(stroke
				(width 0.15)
				(type solid)
			)
			(layer "F.SilkS")
		)
		(fp_line
			(start 1.499 1.5)
			(end 1.499 1.202)
			(stroke
				(width 0.15)
				(type solid)
			)
			(layer "F.SilkS")
		)
		(fp_line
			(start 1.202 -1.5)
			(end 1.5 -1.5)
			(stroke
				(width 0.15)
				(type solid)
			)
			(layer "F.SilkS")
		)
		(fp_line
			(start 1.201 1.5)
			(end 1.499 1.5)
			(stroke
				(width 0.15)
				(type solid)
			)
			(layer "F.SilkS")
		)
		(fp_line
			(start -1.2 1.498)
			(end -1.5 1.498)
			(stroke
				(width 0.15)
				(type solid)
			)
			(layer "F.SilkS")
		)
		(fp_line
			(start -1.5 1.498)
			(end -1.5 1.2)
			(stroke
				(width 0.15)
				(type solid)
			)
			(layer "F.SilkS")
		)
		(fp_line
			(start -1.5 -1.201)
			(end -1.5 -1.499)
			(stroke
				(width 0.15)
				(type solid)
			)
			(layer "F.SilkS")
		)
		(fp_line
			(start -1.5 -1.499)
			(end -1.2 -1.499)
			(stroke
				(width 0.15)
				(type solid)
			)
			(layer "F.SilkS")
		)
		(fp_circle
			(center -1.75 -1.15)
			(end -1.7 -1.15)
			(stroke
				(width 0.15)
				(type solid)
			)
			(fill yes)
			(layer "F.SilkS")
		)
		(fp_rect
			(start -1.8 -1.8)
			(end 1.8 1.8)
			(stroke
				(width 0.05)
				(type solid)
			)
			(fill no)
			(layer "F.CrtYd")
		)
		(fp_line
			(start 1.499 1.499)
			(end 1.499 -1.5)
			(stroke
				(width 0.15)
				(type solid)
			)
			(layer "F.Fab")
		)
		(fp_line
			(start 1.499 -1.5)
			(end -0.5 -1.5)
			(stroke
				(width 0.15)
				(type solid)
			)
			(layer "F.Fab")
		)
		(fp_line
			(start -0.5 -1.5)
			(end -1.5 -0.5)
			(stroke
				(width 0.15)
				(type solid)
			)
			(layer "F.Fab")
		)
		(fp_line
			(start -1.5 1.499)
			(end 1.499 1.499)
			(stroke
				(width 0.15)
				(type solid)
			)
			(layer "F.Fab")
		)
		(fp_line
			(start -1.5 -0.5)
			(end -1.5 1.499)
			(stroke
				(width 0.15)
				(type solid)
			)
			(layer "F.Fab")
		)
		(fp_text user "License: Apache-2.0"
			(at -2.1844 2.844799 0)
			(layer "F.Fab")
			(effects
				(font
					(size 0.7 0.7)
					(thickness 0.15)
				)
				(justify right top)
			)
		)
		(fp_text user "Author: Antmicro"
			(at -2.184401 4.0448 0)
			(layer "F.Fab")
			(effects
				(font
					(size 0.7 0.7)
					(thickness 0.15)
				)
				(justify right top)
			)
		)
		(fp_text user "${REFERENCE}"
			(at -0.025 0 0)
			(layer "F.Fab")
			(effects
				(font
					(size 0.7 0.7)
					(thickness 0.15)
				)
				(justify right top)
			)
		)
		(pad "1" smd oval
			(at -1.401 -0.903 270)
			(size 0.2 0.6)
			(layers "F.Cu" "F.Mask" "F.Paste")
			(net 85 "/Power/3V3_BST")
			(pinfunction "BST")
			(pintype "passive")
		)
		(pad "2" smd oval
			(at -1.401 -0.453 270)
			(size 0.2 0.6)
			(layers "F.Cu" "F.Mask" "F.Paste")
			(net 87 "+12V")
			(pinfunction "V_{IN}")
			(pintype "power_in")
		)
		(pad "3" smd oval
			(at -1.401 0 270)
			(size 0.2 0.6)
			(layers "F.Cu" "F.Mask" "F.Paste")
			(net 87 "+12V")
			(pinfunction "V_{IN}")
			(pintype "passive")
		)
		(pad "4" smd oval
			(at -1.401 0.45 270)
			(size 0.2 0.6)
			(layers "F.Cu" "F.Mask" "F.Paste")
			(net 87 "+12V")
			(pinfunction "V_{IN}")
			(pintype "passive")
		)
		(pad "5" smd oval
			(at -1.401 0.9 270)
			(size 0.2 0.6)
			(layers "F.Cu" "F.Mask" "F.Paste")
			(net 87 "+12V")
			(pinfunction "V_{IN}")
			(pintype "passive")
		)
		(pad "6" smd oval
			(at -0.903 1.398 180)
			(size 0.2 0.6)
			(layers "F.Cu" "F.Mask" "F.Paste")
			(net 86 "/Power/3V3_SW")
			(pinfunction "SW")
			(pintype "passive")
		)
		(pad "7" smd oval
			(at -0.453 1.398 180)
			(size 0.2 0.6)
			(layers "F.Cu" "F.Mask" "F.Paste")
			(net 66 "GND")
			(pinfunction "PGND")
			(pintype "passive")
		)
		(pad "8" smd oval
			(at 0 1.398 180)
			(size 0.2 0.6)
			(layers "F.Cu" "F.Mask" "F.Paste")
			(net 66 "GND")
			(pinfunction "PGND")
			(pintype "passive")
		)
		(pad "9" smd oval
			(at 0.45 1.398 180)
			(size 0.2 0.6)
			(layers "F.Cu" "F.Mask" "F.Paste")
			(net 105 "/Power/3V3_PG")
			(pinfunction "PG")
			(pintype "passive")
		)
		(pad "10" smd oval
			(at 0.9 1.398 180)
			(size 0.2 0.6)
			(layers "F.Cu" "F.Mask" "F.Paste")
			(net 110 "unconnected-(U1-NC-Pad10)")
			(pinfunction "NC")
			(pintype "no_connect")
		)
		(pad "11" smd oval
			(at 1.398 0.9 270)
			(size 0.2 0.6)
			(layers "F.Cu" "F.Mask" "F.Paste")
			(net 111 "unconnected-(U1-SS-Pad11)")
			(pinfunction "SS")
			(pintype "passive+no_connect")
		)
		(pad "12" smd oval
			(at 1.398 0.45 270)
			(size 0.2 0.6)
			(layers "F.Cu" "F.Mask" "F.Paste")
			(net 106 "/Power/3V3_EN")
			(pinfunction "EN")
			(pintype "passive")
		)
		(pad "13" smd oval
			(at 1.398 0 270)
			(size 0.2 0.6)
			(layers "F.Cu" "F.Mask" "F.Paste")
			(net 66 "GND")
			(pinfunction "AGND")
			(pintype "passive")
		)
		(pad "14" smd oval
			(at 1.398 -0.453 270)
			(size 0.2 0.6)
			(layers "F.Cu" "F.Mask" "F.Paste")
			(net 108 "/Power/3V3_FB")
			(pinfunction "FB")
			(pintype "passive")
		)
		(pad "15" smd oval
			(at 1.398 -0.903 270)
			(size 0.2 0.6)
			(layers "F.Cu" "F.Mask" "F.Paste")
			(net 107 "/Power/3V3_MODE")
			(pinfunction "MODE")
			(pintype "passive")
		)
		(pad "16" smd oval
			(at 0.9 -1.401 180)
			(size 0.2 0.6)
			(layers "F.Cu" "F.Mask" "F.Paste")
			(net 109 "unconnected-(U1-NC-Pad16)")
			(pinfunction "NC")
			(pintype "no_connect")
		)
		(pad "17" smd oval
			(at 0.45 -1.401 180)
			(size 0.2 0.6)
			(layers "F.Cu" "F.Mask" "F.Paste")
			(net 88 "/Power/3V3_VCC")
			(pinfunction "V_{CC}")
			(pintype "passive")
		)
		(pad "18" smd oval
			(at 0 -1.401 180)
			(size 0.2 0.6)
			(layers "F.Cu" "F.Mask" "F.Paste")
			(net 66 "GND")
			(pinfunction "PGND")
			(pintype "passive")
		)
		(pad "19" smd oval
			(at -0.453 -1.401 180)
			(size 0.2 0.6)
			(layers "F.Cu" "F.Mask" "F.Paste")
			(net 86 "/Power/3V3_SW")
			(pinfunction "SW")
			(pintype "passive")
		)
		(pad "20" smd oval
			(at -0.903 -1.401 180)
			(size 0.2 0.6)
			(layers "F.Cu" "F.Mask" "F.Paste")
			(net 86 "/Power/3V3_SW")
			(pinfunction "SW")
			(pintype "passive")
		)
		(pad "21" smd roundrect
			(at 0 0 180)
			(size 1 1)
			(layers "F.Cu" "F.Mask" "F.Paste")
			(roundrect_rratio 0.1)
			(net 66 "GND")
			(pinfunction "PGND")
			(pintype "passive")
		)
	)
	(footprint "antmicro-footprints:L_WE-MAPI-4020"
		(layer "F.Cu")
		(at 125.9 137.55 -90)
		(property "Reference" "L1"
			(at 3.65 0.7 180)
			(layer "F.SilkS")
			(effects
				(font
					(size 0.7 0.7)
					(thickness 0.15)
				)
				(justify left bottom)
			)
		)
		(property "Value" "L_1u8_6.8A_WE-MAPI-4020"
			(at -2.4 3.4 90)
			(layer "F.Fab")
			(effects
				(font
					(size 0.7 0.7)
					(thickness 0.15)
				)
				(justify left bottom)
			)
		)
		(property "Datasheet" "https://www.we-online.com/components/products/datasheet/74438356018.pdf"
			(at 0 0 90)
			(layer "F.Fab")
			(hide yes)
			(effects
				(font
					(size 1.27 1.27)
					(thickness 0.15)
				)
			)
		)
		(property "Description" "Power Inductors - SMD WE-MAPI 1.8uH 4.6A DCR=30mOhms AEC-Q200"
			(at 0 0 90)
			(layer "F.Fab")
			(hide yes)
			(effects
				(font
					(size 1.27 1.27)
					(thickness 0.15)
				)
			)
		)
		(property "Val" "1u8/6.8A"
			(at 0 0 270)
			(unlocked yes)
			(layer "F.Fab")
			(hide yes)
			(effects
				(font
					(size 1 1)
					(thickness 0.15)
				)
			)
		)
		(property "Manufacturer" "Würth Elektronik"
			(at 0 0 270)
			(unlocked yes)
			(layer "F.Fab")
			(hide yes)
			(effects
				(font
					(size 1 1)
					(thickness 0.15)
				)
			)
		)
		(property "MPN" "74438356018"
			(at 0 0 270)
			(unlocked yes)
			(layer "F.Fab")
			(hide yes)
			(effects
				(font
					(size 1 1)
					(thickness 0.15)
				)
			)
		)
		(property "ISat" "6.5 A"
			(at 0 0 270)
			(unlocked yes)
			(layer "F.Fab")
			(hide yes)
			(effects
				(font
					(size 1 1)
					(thickness 0.15)
				)
			)
		)
		(property "IMax" "6.8 A"
			(at 0 0 270)
			(unlocked yes)
			(layer "F.Fab")
			(hide yes)
			(effects
				(font
					(size 1 1)
					(thickness 0.15)
				)
			)
		)
		(property "Size" "4.1x4.1mm"
			(at 0 0 270)
			(unlocked yes)
			(layer "F.Fab")
			(hide yes)
			(effects
				(font
					(size 1 1)
					(thickness 0.15)
				)
			)
		)
		(property "Author" "Antmicro"
			(at 0 0 270)
			(unlocked yes)
			(layer "F.Fab")
			(hide yes)
			(effects
				(font
					(size 1 1)
					(thickness 0.15)
				)
			)
		)
		(property "License" "Apache-2.0"
			(at 0 0 270)
			(unlocked yes)
			(layer "F.Fab")
			(hide yes)
			(effects
				(font
					(size 1 1)
					(thickness 0.15)
				)
			)
		)
		(sheetname "/Power/")
		(sheetfile "power.kicad_sch")
		(attr smd)
		(fp_rect
			(start -2.2 -2.2)
			(end 2.2 2.2)
			(stroke
				(width 0.15)
				(type solid)
			)
			(fill no)
			(layer "F.SilkS")
		)
		(fp_rect
			(start -2.3 -2.3)
			(end 2.3 2.3)
			(stroke
				(width 0.05)
				(type solid)
			)
			(fill no)
			(layer "F.CrtYd")
		)
		(fp_rect
			(start -2.05 -2.05)
			(end 2.05 2.05)
			(stroke
				(width 0.15)
				(type solid)
			)
			(fill no)
			(layer "F.Fab")
		)
		(fp_text user "${REFERENCE}"
			(at 0 0 90)
			(layer "F.Fab")
			(effects
				(font
					(size 0.7 0.7)
					(thickness 0.15)
				)
				(justify right top)
			)
		)
		(fp_text user "License: Apache-2.0"
			(at -2.4 5.4 90)
			(layer "F.Fab")
			(effects
				(font
					(size 0.7 0.7)
					(thickness 0.15)
				)
				(justify right top)
			)
		)
		(fp_text user "Author: Antmicro"
			(at -2.4 6.6 90)
			(layer "F.Fab")
			(effects
				(font
					(size 0.7 0.7)
					(thickness 0.15)
				)
				(justify right top)
			)
		)
		(pad "1" smd roundrect
			(at -1.185 0)
			(size 3.7 1)
			(layers "F.Cu" "F.Mask" "F.Paste")
			(roundrect_rratio 0.1)
			(net 86 "/Power/3V3_SW")
			(pintype "passive")
		)
		(pad "2" smd roundrect
			(at 1.185 0)
			(size 3.7 1)
			(layers "F.Cu" "F.Mask" "F.Paste")
			(roundrect_rratio 0.1)
			(net 186 "/Power/3V3_CONV")
			(pintype "passive")
		)
	)
	(footprint "antmicro-footprints:SOT-23-3"
		(layer "F.Cu")
		(at 133.4 71.35 90)
		(property "Reference" "Q8"
			(at 2.406999 -1.4735 90)
			(layer "F.SilkS")
			(effects
				(font
					(size 0.7 0.7)
					(thickness 0.15)
				)
				(justify right top)
			)
		)
		(property "Value" "BSS138-7-F"
			(at -1.9 2.7 90)
			(layer "F.Fab")
			(effects
				(font
					(size 0.7 0.7)
					(thickness 0.15)
				)
				(justify left bottom)
			)
		)
		(property "Datasheet" "https://www.diodes.com/assets/Datasheets/ds30144.pdf"
			(at 0 0 90)
			(layer "F.Fab")
			(hide yes)
			(effects
				(font
					(size 1.27 1.27)
					(thickness 0.15)
				)
			)
		)
		(property "Description" "Power MOSFET, N Channel, 50 V, 200 mA, 1.4 ohm, SOT-23, Surface Mount"
			(at 0 0 90)
			(layer "F.Fab")
			(hide yes)
			(effects
				(font
					(size 1.27 1.27)
					(thickness 0.15)
				)
			)
		)
		(property "MPN" "BSS138-7-F"
			(at 0 0 90)
			(unlocked yes)
			(layer "F.Fab")
			(hide yes)
			(effects
				(font
					(size 1 1)
					(thickness 0.15)
				)
			)
		)
		(property "Manufacturer" "Diodes Incorporated"
			(at 0 0 90)
			(unlocked yes)
			(layer "F.Fab")
			(hide yes)
			(effects
				(font
					(size 1 1)
					(thickness 0.15)
				)
			)
		)
		(property "Author" "Antmicro"
			(at 0 0 90)
			(unlocked yes)
			(layer "F.Fab")
			(hide yes)
			(effects
				(font
					(size 1 1)
					(thickness 0.15)
				)
			)
		)
		(property "License" "Apache-2.0"
			(at 0 0 90)
			(unlocked yes)
			(layer "F.Fab")
			(hide yes)
			(effects
				(font
					(size 1 1)
					(thickness 0.15)
				)
			)
		)
		(sheetname "/USB-PD/")
		(sheetfile "usb-pd.kicad_sch")
		(attr smd)
		(fp_line
			(start 0.7 -1.5)
			(end -0.7 -1.5)
			(stroke
				(width 0.15)
				(type solid)
			)
			(layer "F.SilkS")
		)
		(fp_line
			(start -0.85 -1.35)
			(end -0.7 -1.5)
			(stroke
				(width 0.15)
				(type solid)
			)
			(layer "F.SilkS")
		)
		(fp_line
			(start -1.45 -1.35)
			(end -0.85 -1.35)
			(stroke
				(width 0.15)
				(type solid)
			)
			(layer "F.SilkS")
		)
		(fp_line
			(start 0.7 -0.4)
			(end 0.7 -1.5)
			(stroke
				(width 0.15)
				(type solid)
			)
			(layer "F.SilkS")
		)
		(fp_line
			(start 0.7 0.4)
			(end 0.7 1.5)
			(stroke
				(width 0.15)
				(type solid)
			)
			(layer "F.SilkS")
		)
		(fp_line
			(start 0.7 1.5)
			(end -0.7 1.5)
			(stroke
				(width 0.15)
				(type solid)
			)
			(layer "F.SilkS")
		)
		(fp_line
			(start -0.7 1.5)
			(end -0.7 1.35)
			(stroke
				(width 0.15)
				(type solid)
			)
			(layer "F.SilkS")
		)
		(fp_line
			(start 0.825 -1.6)
			(end 0.825 -0.45)
			(stroke
				(width 0.05)
				(type solid)
			)
			(layer "F.CrtYd")
		)
		(fp_line
			(start -0.9 -1.6)
			(end 0.825 -1.6)
			(stroke
				(width 0.05)
				(type solid)
			)
			(layer "F.CrtYd")
		)
		(fp_line
			(start -0.9 -1.6)
			(end -0.9 -1.4)
			(stroke
				(width 0.05)
				(type solid)
			)
			(layer "F.CrtYd")
		)
		(fp_line
			(start -0.9 -1.4)
			(end -1.75 -1.4)
			(stroke
				(width 0.05)
				(type solid)
			)
			(layer "F.CrtYd")
		)
		(fp_line
			(start -0.85 -0.5)
			(end -1.75 -0.5)
			(stroke
				(width 0.05)
				(type solid)
			)
			(layer "F.CrtYd")
		)
		(fp_line
			(start -1.75 -0.5)
			(end -1.75 -1.4)
			(stroke
				(width 0.05)
				(type solid)
			)
			(layer "F.CrtYd")
		)
		(fp_line
			(start 1.75 -0.45)
			(end 1.75 0.45)
			(stroke
				(width 0.05)
				(type solid)
			)
			(layer "F.CrtYd")
		)
		(fp_line
			(start 0.825 -0.45)
			(end 1.75 -0.45)
			(stroke
				(width 0.05)
				(type solid)
			)
			(layer "F.CrtYd")
		)
		(fp_line
			(start 1.75 0.45)
			(end 0.85 0.45)
			(stroke
				(width 0.05)
				(type solid)
			)
			(layer "F.CrtYd")
		)
		(fp_line
			(start 0.85 0.45)
			(end 0.85 1.65)
			(stroke
				(width 0.05)
				(type solid)
			)
			(layer "F.CrtYd")
		)
		(fp_line
			(start -0.85 0.5)
			(end -0.85 -0.5)
			(stroke
				(width 0.05)
				(type solid)
			)
			(layer "F.CrtYd")
		)
		(fp_line
			(start -1.75 0.5)
			(end -0.85 0.5)
			(stroke
				(width 0.05)
				(type solid)
			)
			(layer "F.CrtYd")
		)
		(fp_line
			(start -0.85 1.4)
			(end -1.75 1.4)
			(stroke
				(width 0.05)
				(type solid)
			)
			(layer "F.CrtYd")
		)
		(fp_line
			(start -1.75 1.4)
			(end -1.75 0.5)
			(stroke
				(width 0.05)
				(type solid)
			)
			(layer "F.CrtYd")
		)
		(fp_line
			(start 0.85 1.65)
			(end -0.85 1.65)
			(stroke
				(width 0.05)
				(type solid)
			)
			(layer "F.CrtYd")
		)
		(fp_line
			(start -0.85 1.65)
			(end -0.85 1.4)
			(stroke
				(width 0.05)
				(type solid)
			)
			(layer "F.CrtYd")
		)
		(fp_line
			(start -0.437 -1.526)
			(end 0.688 -1.526)
			(stroke
				(width 0.15)
				(type solid)
			)
			(layer "F.Fab")
		)
		(fp_line
			(start -0.437 -1.526)
			(end -0.712 -1.325)
			(stroke
				(width 0.15)
				(type solid)
			)
			(layer "F.Fab")
		)
		(fp_line
			(start -0.712 -1.325)
			(end -0.712 1.523)
			(stroke
				(width 0.15)
				(type solid)
			)
			(layer "F.Fab")
		)
		(fp_line
			(start 0.688 1.519)
			(end 0.688 -1.52)
			(stroke
				(width 0.15)
				(type solid)
			)
			(layer "F.Fab")
		)
		(fp_line
			(start -0.712 1.519)
			(end 0.688 1.519)
			(stroke
				(width 0.15)
				(type solid)
			)
			(layer "F.Fab")
		)
		(fp_text user "License: Apache-2.0"
			(at -1.8 6.8 90)
			(layer "F.Fab")
			(effects
				(font
					(size 0.7 0.7)
					(thickness 0.15)
				)
				(justify left bottom)
			)
		)
		(fp_text user "Author: Antmicro"
			(at -1.837 5.3 90)
			(layer "F.Fab")
			(effects
				(font
					(size 0.7 0.7)
					(thickness 0.15)
				)
				(justify left bottom)
			)
		)
		(fp_text user "${REFERENCE}"
			(at 0 0.025 270)
			(layer "F.Fab")
			(effects
				(font
					(size 0.7 0.7)
					(thickness 0.15)
				)
				(justify right top)
			)
		)
		(pad "1" smd roundrect
			(at -1.1 -0.951 90)
			(size 1 0.6)
			(layers "F.Cu" "F.Mask" "F.Paste")
			(roundrect_rratio 0.15)
			(net 124 "/USB-PD/FAULT")
			(pinfunction "G")
			(pintype "input")
		)
		(pad "2" smd roundrect
			(at -1.1 0.949 90)
			(size 1 0.6)
			(layers "F.Cu" "F.Mask" "F.Paste")
			(roundrect_rratio 0.15)
			(net 66 "GND")
			(pinfunction "S")
			(pintype "passive")
		)
		(pad "3" smd roundrect
			(at 1.1 -0.0005 90)
			(size 1 0.6)
			(layers "F.Cu" "F.Mask" "F.Paste")
			(roundrect_rratio 0.15)
			(net 176 "Net-(Q8-D)")
			(pinfunction "D")
			(pintype "passive")
		)
	)
	(footprint "antmicro-footprints:Vishay_PowerPAK_1212-8_Single"
		(layer "F.Cu")
		(at 132.25 104 90)
		(descr "PowerPAK 1212-8 Single")
		(tags "Vishay PowerPAK 1212-8 Single")
		(property "Reference" "Q5"
			(at 1.2 -3.45 180)
			(layer "F.SilkS")
			(effects
				(font
					(size 0.7 0.7)
					(thickness 0.15)
				)
				(justify left bottom)
			)
		)
		(property "Value" "SQS401EN-T1_BE3"
			(at 0 2.7 90)
			(layer "F.Fab")
			(effects
				(font
					(size 0.7 0.7)
					(thickness 0.15)
				)
				(justify left bottom)
			)
		)
		(property "Datasheet" "https://www.vishay.com/docs/65529/sqs401en.pdf"
			(at 0 0 90)
			(layer "F.Fab")
			(hide yes)
			(effects
				(font
					(size 1.27 1.27)
					(thickness 0.15)
				)
			)
		)
		(property "Description" "MOSFET, P Channel, 40 V, 16A, 0.047 ohm, PowerPAK 1212-8, Surface Mount"
			(at 0 0 90)
			(layer "F.Fab")
			(hide yes)
			(effects
				(font
					(size 1.27 1.27)
					(thickness 0.15)
				)
			)
		)
		(property "MPN" "SQS401EN-T1_BE3"
			(at 0 0 90)
			(unlocked yes)
			(layer "F.Fab")
			(hide yes)
			(effects
				(font
					(size 1 1)
					(thickness 0.15)
				)
			)
		)
		(property "Manufacturer" "Vishay"
			(at 0 0 90)
			(unlocked yes)
			(layer "F.Fab")
			(hide yes)
			(effects
				(font
					(size 1 1)
					(thickness 0.15)
				)
			)
		)
		(property "Author" "Antmicro"
			(at 0 0 90)
			(unlocked yes)
			(layer "F.Fab")
			(hide yes)
			(effects
				(font
					(size 1 1)
					(thickness 0.15)
				)
			)
		)
		(property "License" "Apache-2.0"
			(at 0 0 90)
			(unlocked yes)
			(layer "F.Fab")
			(hide yes)
			(effects
				(font
					(size 1 1)
					(thickness 0.15)
				)
			)
		)
		(sheetname "/Power/Ideal-diode-0/")
		(sheetfile "ideal-diode.kicad_sch")
		(attr smd)
		(fp_line
			(start 1.648 -1.651)
			(end 1.648 -1.317)
			(stroke
				(width 0.15)
				(type solid)
			)
			(layer "F.SilkS")
		)
		(fp_line
			(start -1.651 -1.651)
			(end 1.648 -1.651)
			(stroke
				(width 0.15)
				(type solid)
			)
			(layer "F.SilkS")
		)
		(fp_line
			(start -1.651 -1.651)
			(end -1.651 -1.317)
			(stroke
				(width 0.15)
				(type solid)
			)
			(layer "F.SilkS")
		)
		(fp_line
			(start 1.634 1.3)
			(end 1.634 1.634)
			(stroke
				(width 0.15)
				(type solid)
			)
			(layer "F.SilkS")
		)
		(fp_line
			(start -1.635 1.3)
			(end -1.635 1.634)
			(stroke
				(width 0.15)
				(type solid)
			)
			(layer "F.SilkS")
		)
		(fp_line
			(start -1.635 1.634)
			(end 1.634 1.634)
			(stroke
				(width 0.15)
				(type solid)
			)
			(layer "F.SilkS")
		)
		(fp_circle
			(center -1.9 -1.4)
			(end -1.85 -1.4)
			(stroke
				(width 0.15)
				(type solid)
			)
			(fill yes)
			(layer "F.SilkS")
		)
		(fp_rect
			(start -2 -1.8)
			(end 2 1.798)
			(stroke
				(width 0.05)
				(type solid)
			)
			(fill no)
			(layer "F.CrtYd")
		)
		(fp_line
			(start -1.6425 -1.4175)
			(end -1.4175 -1.6425)
			(stroke
				(width 0.15)
				(type solid)
			)
			(layer "F.Fab")
		)
		(fp_rect
			(start -1.651 -1.651)
			(end 1.648 1.648)
			(stroke
				(width 0.15)
				(type solid)
			)
			(fill no)
			(layer "F.Fab")
		)
		(fp_text user "${REFERENCE}"
			(at 0 -0.001 90)
			(layer "F.Fab")
			(effects
				(font
					(size 0.7 0.7)
					(thickness 0.15)
				)
				(justify left bottom)
			)
		)
		(fp_text user "License: Apache-2.0"
			(at -8 7.1 90)
			(layer "F.Fab")
			(effects
				(font
					(size 0.7 0.7)
					(thickness 0.15)
				)
				(justify left bottom)
			)
		)
		(fp_text user "Author: Antmicro"
			(at -8 5.9 90)
			(layer "F.Fab")
			(effects
				(font
					(size 0.7 0.7)
					(thickness 0.15)
				)
				(justify left bottom)
			)
		)
		(pad "1" smd rect
			(at -1.436 -0.99 90)
			(size 0.99 0.405)
			(layers "F.Cu" "F.Mask" "F.Paste")
			(net 87 "+12V")
			(pinfunction "S")
			(pintype "passive")
		)
		(pad "2" smd rect
			(at -1.436 -0.332 90)
			(size 0.99 0.405)
			(layers "F.Cu" "F.Mask" "F.Paste")
			(net 87 "+12V")
			(pinfunction "S")
			(pintype "passive")
		)
		(pad "3" smd rect
			(at -1.436 0.33 90)
			(size 0.99 0.405)
			(layers "F.Cu" "F.Mask" "F.Paste")
			(net 87 "+12V")
			(pinfunction "S")
			(pintype "passive")
		)
		(pad "4" smd rect
			(at -1.436 0.988 90)
			(size 0.99 0.405)
			(layers "F.Cu" "F.Mask" "F.Paste")
			(net 151 "Net-(Q5-G)")
			(pinfunction "G")
			(pintype "input")
		)
		(pad "5" smd custom
			(at 0.557 0 90)
			(size 1.725 2.235)
			(layers "F.Cu" "F.Mask" "F.Paste")
			(net 119 "/Power/VCC_PD")
			(pinfunction "D")
			(pintype "passive")
			(zone_connect 2)
			(options
				(clearance outline)
				(anchor rect)
			)
			(primitives
				(gr_poly
					(pts
						(xy 0.8625 0.1275) (xy 0.8625 -0.1275) (xy 1.3725 -0.1275) (xy 1.3725 -0.5325) (xy 0.8625 -0.5325)
						(xy 0.8625 -0.7875) (xy 1.3725 -0.7875) (xy 1.3725 -1.195) (xy 0.6125 -1.195) (xy 0.6125 1.195)
						(xy 1.3725 1.195) (xy 1.3725 0.7875) (xy 0.8625 0.7875) (xy 0.8625 0.5325) (xy 1.3725 0.5325)
						(xy 1.3725 0.1275)
					)
					(width 0)
					(fill yes)
				)
			)
		)
	)
	(footprint "antmicro-footprints:C_0805_2012Metric"
		(layer "F.Cu")
		(at 119.8 114.2)
		(descr "Capacitor SMD 0805")
		(tags "capacitor SMD 0805")
		(property "Reference" "C36"
			(at -0.4 -1.2 180)
			(layer "F.SilkS")
			(effects
				(font
					(size 0.7 0.7)
					(thickness 0.15)
				)
				(justify left bottom)
			)
		)
		(property "Value" "C_10u_0805_35V"
			(at -2.055717 1.963153 0)
			(layer "F.Fab")
			(effects
				(font
					(size 0.7 0.7)
					(thickness 0.15)
				)
				(justify left bottom)
			)
		)
		(property "Datasheet" "https://www.murata.com/products/productdetail?partno=GRM21BR6YA106KE43%23"
			(at 0 0 0)
			(layer "F.Fab")
			(hide yes)
			(effects
				(font
					(size 1.27 1.27)
					(thickness 0.15)
				)
			)
		)
		(property "Description" "SMD Multilayer Ceramic Capacitor, 10 µF, 35 V, 0805 [2012 Metric], ± 10%, X5R, GRM Series"
			(at 0 0 0)
			(layer "F.Fab")
			(hide yes)
			(effects
				(font
					(size 1.27 1.27)
					(thickness 0.15)
				)
			)
		)
		(property "MPN" "GRM21BR6YA106KE43L"
			(at 0 0 0)
			(unlocked yes)
			(layer "F.Fab")
			(hide yes)
			(effects
				(font
					(size 1 1)
					(thickness 0.15)
				)
			)
		)
		(property "Manufacturer" "Murata"
			(at 0 0 0)
			(unlocked yes)
			(layer "F.Fab")
			(hide yes)
			(effects
				(font
					(size 1 1)
					(thickness 0.15)
				)
			)
		)
		(property "License" "Apache-2.0"
			(at 0 0 0)
			(unlocked yes)
			(layer "F.Fab")
			(hide yes)
			(effects
				(font
					(size 1 1)
					(thickness 0.15)
				)
			)
		)
		(property "Author" "Antmicro"
			(at 0 0 0)
			(unlocked yes)
			(layer "F.Fab")
			(hide yes)
			(effects
				(font
					(size 1 1)
					(thickness 0.15)
				)
			)
		)
		(property "Val" "10u"
			(at 0 0 0)
			(unlocked yes)
			(layer "F.Fab")
			(hide yes)
			(effects
				(font
					(size 1 1)
					(thickness 0.15)
				)
			)
		)
		(property "Voltage" "35V"
			(at 0 0 0)
			(unlocked yes)
			(layer "F.Fab")
			(hide yes)
			(effects
				(font
					(size 1 1)
					(thickness 0.15)
				)
			)
		)
		(property "Dielectric" ""
			(at 0 0 0)
			(unlocked yes)
			(layer "F.Fab")
			(hide yes)
			(effects
				(font
					(size 1 1)
					(thickness 0.15)
				)
			)
		)
		(property "Public" "False"
			(at 0 0 0)
			(unlocked yes)
			(layer "F.Fab")
			(hide yes)
			(effects
				(font
					(size 1 1)
					(thickness 0.15)
				)
			)
		)
		(sheetname "/PCIe-connector/")
		(sheetfile "pcie-connector.kicad_sch")
		(attr smd)
		(fp_line
			(start -0.3 -0.7)
			(end 0.3 -0.7)
			(stroke
				(width 0.15)
				(type solid)
			)
			(layer "F.SilkS")
		)
		(fp_line
			(start -0.3 0.7)
			(end 0.3 0.7)
			(stroke
				(width 0.15)
				(type solid)
			)
			(layer "F.SilkS")
		)
		(fp_rect
			(start 1.95 -0.9)
			(end -1.95 0.9)
			(stroke
				(width 0.05)
				(type default)
			)
			(fill no)
			(layer "F.CrtYd")
		)
		(fp_rect
			(start -0.95 -0.675)
			(end 0.95 0.675)
			(stroke
				(width 0.15)
				(type solid)
			)
			(fill no)
			(layer "F.Fab")
		)
		(fp_text user "License: Apache-2.0"
			(at -1.9 4.947 0)
			(layer "F.Fab")
			(effects
				(font
					(size 0.7 0.7)
					(thickness 0.15)
				)
				(justify left bottom)
			)
		)
		(fp_text user "${REFERENCE}"
			(at 0 0 0)
			(layer "F.Fab")
			(effects
				(font
					(size 0.7 0.7)
					(thickness 0.15)
				)
				(justify left bottom)
			)
		)
		(fp_text user "Author: Antmicro"
			(at -1.9 5.947 0)
			(layer "F.Fab")
			(effects
				(font
					(size 0.7 0.7)
					(thickness 0.15)
				)
				(justify left bottom)
			)
		)
		(pad "1" smd roundrect
			(at -1.1 0)
			(size 1.2 1.3)
			(layers "F.Cu" "F.Mask" "F.Paste")
			(roundrect_rratio 0.25)
			(net 134 "+3V3")
			(pintype "passive")
		)
		(pad "2" smd roundrect
			(at 1.1 0)
			(size 1.2 1.3)
			(layers "F.Cu" "F.Mask" "F.Paste")
			(roundrect_rratio 0.25)
			(net 66 "GND")
			(pintype "passive")
		)
	)
	(footprint "antmicro-footprints:C_0402_1005Metric"
		(layer "F.Cu")
		(at 143.5 120.402999 -90)
		(descr "Capacitor SMD 0402")
		(tags "capacitor SMD 0402")
		(property "Reference" "C34"
			(at -1.002999 -0.8 90)
			(layer "F.SilkS")
			(effects
				(font
					(size 0.7 0.7)
					(thickness 0.15)
				)
				(justify right top)
			)
		)
		(property "Value" "C_100n_0402"
			(at -1.022927 2.155213 90)
			(layer "F.Fab")
			(effects
				(font
					(size 0.7 0.7)
					(thickness 0.15)
				)
				(justify right top)
			)
		)
		(property "Datasheet" "https://www.murata.com/products/productdetail?partno=GRM155R61H104KE14%23"
			(at 0 0 90)
			(layer "F.Fab")
			(hide yes)
			(effects
				(font
					(size 1.27 1.27)
					(thickness 0.15)
				)
			)
		)
		(property "Description" "SMD Multilayer Ceramic Capacitor, 0.1 µF, 50 V, 0402 [1005 Metric], ± 10%, X5R, GRM Series"
			(at 0 0 90)
			(layer "F.Fab")
			(hide yes)
			(effects
				(font
					(size 1.27 1.27)
					(thickness 0.15)
				)
			)
		)
		(property "MPN" "GRM155R61H104KE14D"
			(at 0 0 270)
			(unlocked yes)
			(layer "F.Fab")
			(hide yes)
			(effects
				(font
					(size 1 1)
					(thickness 0.15)
				)
			)
		)
		(property "Manufacturer" "Murata"
			(at 0 0 270)
			(unlocked yes)
			(layer "F.Fab")
			(hide yes)
			(effects
				(font
					(size 1 1)
					(thickness 0.15)
				)
			)
		)
		(property "License" "Apache-2.0"
			(at 0 0 270)
			(unlocked yes)
			(layer "F.Fab")
			(hide yes)
			(effects
				(font
					(size 1 1)
					(thickness 0.15)
				)
			)
		)
		(property "Author" "Antmicro"
			(at 0 0 270)
			(unlocked yes)
			(layer "F.Fab")
			(hide yes)
			(effects
				(font
					(size 1 1)
					(thickness 0.15)
				)
			)
		)
		(property "Val" "100n"
			(at 0 0 270)
			(unlocked yes)
			(layer "F.Fab")
			(hide yes)
			(effects
				(font
					(size 1 1)
					(thickness 0.15)
				)
			)
		)
		(property "Voltage" "50V"
			(at 0 0 270)
			(unlocked yes)
			(layer "F.Fab")
			(hide yes)
			(effects
				(font
					(size 1 1)
					(thickness 0.15)
				)
			)
		)
		(property "Dielectric" "X5R"
			(at 0 0 270)
			(unlocked yes)
			(layer "F.Fab")
			(hide yes)
			(effects
				(font
					(size 1 1)
					(thickness 0.15)
				)
			)
		)
		(sheetname "/Power/Ideal-diode-1/")
		(sheetfile "ideal-diode.kicad_sch")
		(attr smd)
		(fp_rect
			(start -0.925 -0.47)
			(end 0.925 0.47)
			(stroke
				(width 0.05)
				(type default)
			)
			(fill no)
			(layer "F.CrtYd")
		)
		(fp_line
			(start -0.494 0.248)
			(end -0.494 -0.25)
			(stroke
				(width 0.15)
				(type solid)
			)
			(layer "F.Fab")
		)
		(fp_line
			(start 0.504 0.248)
			(end -0.494 0.248)
			(stroke
				(width 0.15)
				(type solid)
			)
			(layer "F.Fab")
		)
		(fp_line
			(start -0.494 -0.25)
			(end 0.504 -0.25)
			(stroke
				(width 0.15)
				(type solid)
			)
			(layer "F.Fab")
		)
		(fp_line
			(start 0.504 -0.25)
			(end 0.504 0.248)
			(stroke
				(width 0.15)
				(type solid)
			)
			(layer "F.Fab")
		)
		(fp_text user "Author: Antmicro"
			(at -0.939 3.399 90)
			(layer "F.Fab")
			(effects
				(font
					(size 0.7 0.7)
					(thickness 0.15)
				)
				(justify right top)
			)
		)
		(fp_text user "${REFERENCE}"
			(at 0 0 90)
			(layer "F.Fab")
			(effects
				(font
					(size 0.7 0.7)
					(thickness 0.15)
				)
				(justify right top)
			)
		)
		(fp_text user "License: Apache-2.0"
			(at -0.939 5.799 90)
			(layer "F.Fab")
			(effects
				(font
					(size 0.7 0.7)
					(thickness 0.15)
				)
				(justify right top)
			)
		)
		(pad "1" smd roundrect
			(at -0.48 0 270)
			(size 0.59 0.64)
			(layers "F.Cu" "F.Mask" "F.Paste")
			(roundrect_rratio 0.25)
			(net 66 "GND")
			(pintype "passive")
		)
		(pad "2" smd roundrect
			(at 0.48 0 270)
			(size 0.59 0.64)
			(layers "F.Cu" "F.Mask" "F.Paste")
			(roundrect_rratio 0.25)
			(net 118 "/Power/Ideal-diode-1/VIN")
			(pintype "passive")
		)
	)
	(footprint "antmicro-footprints:C_0805_2012Metric"
		(layer "F.Cu")
		(at 136.35 89.499998 90)
		(descr "Capacitor SMD 0805")
		(tags "capacitor SMD 0805")
		(property "Reference" "C24"
			(at 0.299998 -3.95 90)
			(layer "F.SilkS")
			(effects
				(font
					(size 0.7 0.7)
					(thickness 0.15)
				)
				(justify left bottom)
			)
		)
		(property "Value" "C_10u_0805_35V"
			(at -2.055717 1.963153 90)
			(layer "F.Fab")
			(effects
				(font
					(size 0.7 0.7)
					(thickness 0.15)
				)
				(justify left bottom)
			)
		)
		(property "Datasheet" "https://www.murata.com/products/productdetail?partno=GRM21BR6YA106KE43%23"
			(at 0 0 90)
			(layer "F.Fab")
			(hide yes)
			(effects
				(font
					(size 1.27 1.27)
					(thickness 0.15)
				)
			)
		)
		(property "Description" "SMD Multilayer Ceramic Capacitor, 10 µF, 35 V, 0805 [2012 Metric], ± 10%, X5R, GRM Series"
			(at 0 0 90)
			(layer "F.Fab")
			(hide yes)
			(effects
				(font
					(size 1.27 1.27)
					(thickness 0.15)
				)
			)
		)
		(property "MPN" "GRM21BR6YA106KE43L"
			(at 0 0 90)
			(unlocked yes)
			(layer "F.Fab")
			(hide yes)
			(effects
				(font
					(size 1 1)
					(thickness 0.15)
				)
			)
		)
		(property "Manufacturer" "Murata"
			(at 0 0 90)
			(unlocked yes)
			(layer "F.Fab")
			(hide yes)
			(effects
				(font
					(size 1 1)
					(thickness 0.15)
				)
			)
		)
		(property "License" "Apache-2.0"
			(at 0 0 90)
			(unlocked yes)
			(layer "F.Fab")
			(hide yes)
			(effects
				(font
					(size 1 1)
					(thickness 0.15)
				)
			)
		)
		(property "Author" "Antmicro"
			(at 0 0 90)
			(unlocked yes)
			(layer "F.Fab")
			(hide yes)
			(effects
				(font
					(size 1 1)
					(thickness 0.15)
				)
			)
		)
		(property "Val" "10u"
			(at 0 0 90)
			(unlocked yes)
			(layer "F.Fab")
			(hide yes)
			(effects
				(font
					(size 1 1)
					(thickness 0.15)
				)
			)
		)
		(property "Voltage" "35V"
			(at 0 0 90)
			(unlocked yes)
			(layer "F.Fab")
			(hide yes)
			(effects
				(font
					(size 1 1)
					(thickness 0.15)
				)
			)
		)
		(property "Dielectric" ""
			(at 0 0 90)
			(unlocked yes)
			(layer "F.Fab")
			(hide yes)
			(effects
				(font
					(size 1 1)
					(thickness 0.15)
				)
			)
		)
		(property "Public" "False"
			(at 0 0 90)
			(unlocked yes)
			(layer "F.Fab")
			(hide yes)
			(effects
				(font
					(size 1 1)
					(thickness 0.15)
				)
			)
		)
		(sheetname "/USB-PD/")
		(sheetfile "usb-pd.kicad_sch")
		(attr smd)
		(fp_line
			(start -0.3 -0.7)
			(end 0.3 -0.7)
			(stroke
				(width 0.15)
				(type solid)
			)
			(layer "F.SilkS")
		)
		(fp_line
			(start -0.3 0.7)
			(end 0.3 0.7)
			(stroke
				(width 0.15)
				(type solid)
			)
			(layer "F.SilkS")
		)
		(fp_rect
			(start 1.95 -0.9)
			(end -1.95 0.9)
			(stroke
				(width 0.05)
				(type default)
			)
			(fill no)
			(layer "F.CrtYd")
		)
		(fp_rect
			(start -0.95 -0.675)
			(end 0.95 0.675)
			(stroke
				(width 0.15)
				(type solid)
			)
			(fill no)
			(layer "F.Fab")
		)
		(fp_text user "Author: Antmicro"
			(at -1.9 5.947 90)
			(layer "F.Fab")
			(effects
				(font
					(size 0.7 0.7)
					(thickness 0.15)
				)
				(justify left bottom)
			)
		)
		(fp_text user "License: Apache-2.0"
			(at -1.9 4.947 90)
			(layer "F.Fab")
			(effects
				(font
					(size 0.7 0.7)
					(thickness 0.15)
				)
				(justify left bottom)
			)
		)
		(fp_text user "${REFERENCE}"
			(at 0 0 90)
			(layer "F.Fab")
			(effects
				(font
					(size 0.7 0.7)
					(thickness 0.15)
				)
				(justify left bottom)
			)
		)
		(pad "1" smd roundrect
			(at -1.1 0 90)
			(size 1.2 1.3)
			(layers "F.Cu" "F.Mask" "F.Paste")
			(roundrect_rratio 0.25)
			(net 66 "GND")
			(pintype "passive")
		)
		(pad "2" smd roundrect
			(at 1.1 0 90)
			(size 1.2 1.3)
			(layers "F.Cu" "F.Mask" "F.Paste")
			(roundrect_rratio 0.25)
			(net 115 "/USB-PD/VCC")
			(pintype "passive")
		)
	)
	(footprint "antmicro-footprints:USON-10_2.5x1mm_P0.5mm"
		(layer "F.Cu")
		(at 142.579 46.914999 -90)
		(descr "USON-10 2.5x1mm_ Pitch 0.5mm")
		(tags "USON-10 2.5x1mm Pitch 0.5mm")
		(property "Reference" "D15"
			(at 1.085001 -0.421 180)
			(layer "F.SilkS")
			(effects
				(font
					(size 0.7 0.7)
					(thickness 0.15)
				)
				(justify right top)
			)
		)
		(property "Value" "ESD204DQAR"
			(at 0.018 2.499 90)
			(layer "F.Fab")
			(effects
				(font
					(size 0.7 0.7)
					(thickness 0.15)
				)
				(justify right top)
			)
		)
		(property "Datasheet" "https://www.ti.com/lit/ds/symlink/esd204.pdf?ts=1706004844383&ref_url=https%253A%252F%252Fwww.ti.com%252Finterface%252Fdiodes%252Fesd-protection-diodes%252Fproducts.html"
			(at 0 0 90)
			(layer "F.Fab")
			(hide yes)
			(effects
				(font
					(size 1.27 1.27)
					(thickness 0.15)
				)
			)
		)
		(property "Description" "TVS diode array, 30 kV, USON-10, 3.6 V, 0.55 pF"
			(at 0 0 90)
			(layer "F.Fab")
			(hide yes)
			(effects
				(font
					(size 1.27 1.27)
					(thickness 0.15)
				)
			)
		)
		(property "MPN" "ESD204DQAR"
			(at 0 0 270)
			(unlocked yes)
			(layer "F.Fab")
			(hide yes)
			(effects
				(font
					(size 1 1)
					(thickness 0.15)
				)
			)
		)
		(property "Manufacturer" "Texas Instruments"
			(at 0 0 270)
			(unlocked yes)
			(layer "F.Fab")
			(hide yes)
			(effects
				(font
					(size 1 1)
					(thickness 0.15)
				)
			)
		)
		(property "Author" "Antmicro"
			(at 0 0 270)
			(unlocked yes)
			(layer "F.Fab")
			(hide yes)
			(effects
				(font
					(size 1 1)
					(thickness 0.15)
				)
			)
		)
		(property "License" "Apache-2.0"
			(at 0 0 270)
			(unlocked yes)
			(layer "F.Fab")
			(hide yes)
			(effects
				(font
					(size 1 1)
					(thickness 0.15)
				)
			)
		)
		(sheetname "/OCuLink/")
		(sheetfile "oculink.kicad_sch")
		(attr smd)
		(fp_line
			(start 0.498 1.398)
			(end -0.5 1.398)
			(stroke
				(width 0.15)
				(type solid)
			)
			(layer "F.SilkS")
		)
		(fp_line
			(start 0.498 -1.401)
			(end -0.5 -1.401)
			(stroke
				(width 0.15)
				(type solid)
			)
			(layer "F.SilkS")
		)
		(fp_circle
			(center -0.68 -1.27)
			(end -0.63 -1.27)
			(stroke
				(width 0.15)
				(type solid)
			)
			(fill yes)
			(layer "F.SilkS")
		)
		(fp_rect
			(start -0.8 -1.5)
			(end 0.8 1.499)
			(stroke
				(width 0.05)
				(type solid)
			)
			(fill no)
			(layer "F.CrtYd")
		)
		(fp_line
			(start -0.5 1.249)
			(end 0.498 1.249)
			(stroke
				(width 0.15)
				(type solid)
			)
			(layer "F.Fab")
		)
		(fp_line
			(start -0.5 -1)
			(end -0.5 1.249)
			(stroke
				(width 0.15)
				(type solid)
			)
			(layer "F.Fab")
		)
		(fp_line
			(start -0.25 -1.25)
			(end -0.5 -1)
			(stroke
				(width 0.15)
				(type solid)
			)
			(layer "F.Fab")
		)
		(fp_line
			(start 0.498 -1.25)
			(end 0.498 1.249)
			(stroke
				(width 0.15)
				(type solid)
			)
			(layer "F.Fab")
		)
		(fp_line
			(start 0.498 -1.25)
			(end -0.25 -1.25)
			(stroke
				(width 0.15)
				(type solid)
			)
			(layer "F.Fab")
		)
		(fp_text user "${REFERENCE}"
			(at 0 -0.000501 90)
			(layer "F.Fab")
			(effects
				(font
					(size 0.7 0.7)
					(thickness 0.15)
				)
				(justify right top)
			)
		)
		(fp_text user "Author: Antmicro"
			(at -0.802 5.7 90)
			(layer "F.Fab")
			(effects
				(font
					(size 0.7 0.7)
					(thickness 0.15)
				)
				(justify right top)
			)
		)
		(fp_text user "License: Apache-2.0"
			(at -0.802 6.9 90)
			(layer "F.Fab")
			(effects
				(font
					(size 0.7 0.7)
					(thickness 0.15)
				)
				(justify right top)
			)
		)
		(pad "1" smd roundrect
			(at -0.387 -1 180)
			(size 0.25 0.55)
			(layers "F.Cu" "F.Mask" "F.Paste")
			(roundrect_rratio 0.25)
			(net 182 "/OCuLink/~{CPRSNTC}")
			(pintype "passive")
		)
		(pad "2" smd roundrect
			(at -0.387 -0.5 180)
			(size 0.25 0.55)
			(layers "F.Cu" "F.Mask" "F.Paste")
			(roundrect_rratio 0.25)
			(net 183 "/OCuLink/~{PERSTC}")
			(pintype "passive")
		)
		(pad "3" smd roundrect
			(at -0.387 0 180)
			(size 0.4 0.55)
			(layers "F.Cu" "F.Mask" "F.Paste")
			(roundrect_rratio 0.25)
			(net 66 "GND")
			(pintype "power_in")
		)
		(pad "4" smd roundrect
			(at -0.387 0.498 180)
			(size 0.25 0.55)
			(layers "F.Cu" "F.Mask" "F.Paste")
			(roundrect_rratio 0.25)
			(net 95 "/OCuLink/I2C0C_SDA")
			(pintype "passive")
		)
		(pad "5" smd roundrect
			(at -0.387 0.998 180)
			(size 0.25 0.55)
			(layers "F.Cu" "F.Mask" "F.Paste")
			(roundrect_rratio 0.25)
			(net 101 "/OCuLink/I2C0C_SCL")
			(pintype "passive")
		)
		(pad "6" smd roundrect
			(at 0.385 0.998 180)
			(size 0.25 0.55)
			(layers "F.Cu" "F.Mask" "F.Paste")
			(roundrect_rratio 0.25)
			(net 101 "/OCuLink/I2C0C_SCL")
			(pintype "passive")
		)
		(pad "7" smd roundrect
			(at 0.385 0.498 180)
			(size 0.25 0.55)
			(layers "F.Cu" "F.Mask" "F.Paste")
			(roundrect_rratio 0.25)
			(net 95 "/OCuLink/I2C0C_SDA")
			(pintype "passive")
		)
		(pad "8" smd roundrect
			(at 0.385 0 180)
			(size 0.4 0.55)
			(layers "F.Cu" "F.Mask" "F.Paste")
			(roundrect_rratio 0.25)
			(net 66 "GND")
			(pintype "passive")
		)
		(pad "9" smd roundrect
			(at 0.385 -0.5 180)
			(size 0.25 0.55)
			(layers "F.Cu" "F.Mask" "F.Paste")
			(roundrect_rratio 0.25)
			(net 183 "/OCuLink/~{PERSTC}")
			(pintype "passive")
		)
		(pad "10" smd roundrect
			(at 0.385 -1 180)
			(size 0.25 0.55)
			(layers "F.Cu" "F.Mask" "F.Paste")
			(roundrect_rratio 0.25)
			(net 182 "/OCuLink/~{CPRSNTC}")
			(pintype "passive")
		)
	)
	(footprint "antmicro-footprints:SOD-123FL"
		(layer "F.Cu")
		(at 120.571 123.6)
		(property "Reference" "D9"
			(at -0.571 -1.4 180)
			(layer "F.SilkS")
			(effects
				(font
					(size 0.7 0.7)
					(thickness 0.15)
				)
				(justify left bottom)
			)
		)
		(property "Value" "SZSMF4L14AT3G"
			(at 0 1.967 0)
			(layer "F.Fab")
			(effects
				(font
					(size 0.7 0.7)
					(thickness 0.15)
				)
				(justify left bottom)
			)
		)
		(property "Datasheet" "https://www.mouser.com/datasheet/2/240/media-3320461.pdf"
			(at 0 0 0)
			(layer "F.Fab")
			(hide yes)
			(effects
				(font
					(size 1.27 1.27)
					(thickness 0.15)
				)
			)
		)
		(property "Description" "ESD, TVS Diode, 14V, UNI, 400W, SOD-123FL"
			(at 0 0 0)
			(layer "F.Fab")
			(hide yes)
			(effects
				(font
					(size 1.27 1.27)
					(thickness 0.15)
				)
			)
		)
		(property "MPN" "SZSMF4L12AT3G"
			(at 0 0 0)
			(unlocked yes)
			(layer "F.Fab")
			(hide yes)
			(effects
				(font
					(size 1 1)
					(thickness 0.15)
				)
			)
		)
		(property "Author" "Antmicro"
			(at 0 0 0)
			(unlocked yes)
			(layer "F.Fab")
			(hide yes)
			(effects
				(font
					(size 1 1)
					(thickness 0.15)
				)
			)
		)
		(property "License" "Apache-2.0"
			(at 0 0 0)
			(unlocked yes)
			(layer "F.Fab")
			(hide yes)
			(effects
				(font
					(size 1 1)
					(thickness 0.15)
				)
			)
		)
		(property "Manufacturer" "Littelfuse"
			(at 0 0 0)
			(unlocked yes)
			(layer "F.Fab")
			(hide yes)
			(effects
				(font
					(size 1 1)
					(thickness 0.15)
				)
			)
		)
		(sheetname "/PCIe-connector/")
		(sheetfile "pcie-connector.kicad_sch")
		(attr smd)
		(fp_line
			(start -2.3 -1.1)
			(end -2.3 1.1)
			(stroke
				(width 0.15)
				(type solid)
			)
			(layer "F.SilkS")
		)
		(fp_line
			(start -2.3 1.1)
			(end 0 1.1)
			(stroke
				(width 0.15)
				(type solid)
			)
			(layer "F.SilkS")
		)
		(fp_line
			(start 0 -1.1)
			(end -2.3 -1.1)
			(stroke
				(width 0.15)
				(type solid)
			)
			(layer "F.SilkS")
		)
		(fp_rect
			(start -2.35 -1.125)
			(end 2.35 1.125)
			(stroke
				(width 0.05)
				(type solid)
			)
			(fill no)
			(layer "F.CrtYd")
		)
		(fp_rect
			(start -1.825 -0.875)
			(end 1.824 0.873)
			(stroke
				(width 0.15)
				(type solid)
			)
			(fill no)
			(layer "F.Fab")
		)
		(fp_rect
			(start -0.775 -0.875)
			(end -0.525 0.875)
			(stroke
				(width 0.15)
				(type solid)
			)
			(fill yes)
			(layer "F.Fab")
		)
		(fp_text user "Author: Antmicro"
			(at -2.406 5.168 0)
			(layer "F.Fab")
			(effects
				(font
					(size 0.7 0.7)
					(thickness 0.15)
				)
				(justify left bottom)
			)
		)
		(fp_text user "License: Apache-2.0"
			(at -2.406 6.368 0)
			(layer "F.Fab")
			(effects
				(font
					(size 0.7 0.7)
					(thickness 0.15)
				)
				(justify left bottom)
			)
		)
		(fp_text user "${REFERENCE}"
			(at -2.406 3.967 0)
			(layer "F.Fab")
			(effects
				(font
					(size 0.7 0.7)
					(thickness 0.15)
				)
				(justify left bottom)
			)
		)
		(pad "1" smd roundrect
			(at -1.43 0)
			(size 1.34 1.8)
			(layers "F.Cu" "F.Mask" "F.Paste")
			(roundrect_rratio 0.14)
			(net 87 "+12V")
			(pinfunction "C")
			(pintype "passive")
		)
		(pad "2" smd roundrect
			(at 1.429 0)
			(size 1.34 1.8)
			(layers "F.Cu" "F.Mask" "F.Paste")
			(roundrect_rratio 0.14)
			(net 66 "GND")
			(pinfunction "A")
			(pintype "passive")
		)
	)
	(footprint "antmicro-footprints:Vishay_PowerPAK_1212-8_Single"
		(layer "F.Cu")
		(at 153.4 44.8)
		(descr "PowerPAK 1212-8 Single")
		(tags "Vishay PowerPAK 1212-8 Single")
		(property "Reference" "Q6"
			(at 2 -0.8 180)
			(layer "F.SilkS")
			(effects
				(font
					(size 0.7 0.7)
					(thickness 0.15)
				)
				(justify left bottom)
			)
		)
		(property "Value" "SQS401EN-T1_BE3"
			(at 0 2.7 0)
			(layer "F.Fab")
			(effects
				(font
					(size 0.7 0.7)
					(thickness 0.15)
				)
				(justify left bottom)
			)
		)
		(property "Datasheet" "https://www.vishay.com/docs/65529/sqs401en.pdf"
			(at 0 0 0)
			(layer "F.Fab")
			(hide yes)
			(effects
				(font
					(size 1.27 1.27)
					(thickness 0.15)
				)
			)
		)
		(property "Description" "MOSFET, P Channel, 40 V, 16A, 0.047 ohm, PowerPAK 1212-8, Surface Mount"
			(at 0 0 0)
			(layer "F.Fab")
			(hide yes)
			(effects
				(font
					(size 1.27 1.27)
					(thickness 0.15)
				)
			)
		)
		(property "MPN" "SQS401EN-T1_BE3"
			(at 0 0 0)
			(unlocked yes)
			(layer "F.Fab")
			(hide yes)
			(effects
				(font
					(size 1 1)
					(thickness 0.15)
				)
			)
		)
		(property "Manufacturer" "Vishay"
			(at 0 0 0)
			(unlocked yes)
			(layer "F.Fab")
			(hide yes)
			(effects
				(font
					(size 1 1)
					(thickness 0.15)
				)
			)
		)
		(property "Author" "Antmicro"
			(at 0 0 0)
			(unlocked yes)
			(layer "F.Fab")
			(hide yes)
			(effects
				(font
					(size 1 1)
					(thickness 0.15)
				)
			)
		)
		(property "License" "Apache-2.0"
			(at 0 0 0)
			(unlocked yes)
			(layer "F.Fab")
			(hide yes)
			(effects
				(font
					(size 1 1)
					(thickness 0.15)
				)
			)
		)
		(sheetname "/USB-PD/")
		(sheetfile "usb-pd.kicad_sch")
		(attr smd)
		(fp_line
			(start -1.651 -1.651)
			(end -1.651 -1.317)
			(stroke
				(width 0.15)
				(type solid)
			)
			(layer "F.SilkS")
		)
		(fp_line
			(start -1.651 -1.651)
			(end 1.648 -1.651)
			(stroke
				(width 0.15)
				(type solid)
			)
			(layer "F.SilkS")
		)
		(fp_line
			(start -1.635 1.3)
			(end -1.635 1.634)
			(stroke
				(width 0.15)
				(type solid)
			)
			(layer "F.SilkS")
		)
		(fp_line
			(start -1.635 1.634)
			(end 1.634 1.634)
			(stroke
				(width 0.15)
				(type solid)
			)
			(layer "F.SilkS")
		)
		(fp_line
			(start 1.634 1.3)
			(end 1.634 1.634)
			(stroke
				(width 0.15)
				(type solid)
			)
			(layer "F.SilkS")
		)
		(fp_line
			(start 1.648 -1.651)
			(end 1.648 -1.317)
			(stroke
				(width 0.15)
				(type solid)
			)
			(layer "F.SilkS")
		)
		(fp_circle
			(center -1.9 -1.4)
			(end -1.85 -1.4)
			(stroke
				(width 0.15)
				(type solid)
			)
			(fill yes)
			(layer "F.SilkS")
		)
		(fp_rect
			(start -2 -1.8)
			(end 2 1.798)
			(stroke
				(width 0.05)
				(type solid)
			)
			(fill no)
			(layer "F.CrtYd")
		)
		(fp_line
			(start -1.6425 -1.4175)
			(end -1.4175 -1.6425)
			(stroke
				(width 0.15)
				(type solid)
			)
			(layer "F.Fab")
		)
		(fp_rect
			(start -1.651 -1.651)
			(end 1.648 1.648)
			(stroke
				(width 0.15)
				(type solid)
			)
			(fill no)
			(layer "F.Fab")
		)
		(fp_text user "Author: Antmicro"
			(at -8 5.9 0)
			(layer "F.Fab")
			(effects
				(font
					(size 0.7 0.7)
					(thickness 0.15)
				)
				(justify left bottom)
			)
		)
		(fp_text user "License: Apache-2.0"
			(at -8 7.1 0)
			(layer "F.Fab")
			(effects
				(font
					(size 0.7 0.7)
					(thickness 0.15)
				)
				(justify left bottom)
			)
		)
		(fp_text user "${REFERENCE}"
			(at 0 -0.001 0)
			(layer "F.Fab")
			(effects
				(font
					(size 0.7 0.7)
					(thickness 0.15)
				)
				(justify left bottom)
			)
		)
		(pad "1" smd rect
			(at -1.436 -0.99)
			(size 0.99 0.405)
			(layers "F.Cu" "F.Mask" "F.Paste")
			(net 113 "VBUS")
			(pinfunction "S")
			(pintype "passive")
		)
		(pad "2" smd rect
			(at -1.436 -0.332)
			(size 0.99 0.405)
			(layers "F.Cu" "F.Mask" "F.Paste")
			(net 113 "VBUS")
			(pinfunction "S")
			(pintype "passive")
		)
		(pad "3" smd rect
			(at -1.436 0.33)
			(size 0.99 0.405)
			(layers "F.Cu" "F.Mask" "F.Paste")
			(net 113 "VBUS")
			(pinfunction "S")
			(pintype "passive")
		)
		(pad "4" smd rect
			(at -1.436 0.988)
			(size 0.99 0.405)
			(layers "F.Cu" "F.Mask" "F.Paste")
			(net 84 "Net-(Q6-G)")
			(pinfunction "G")
			(pintype "input")
		)
		(pad "5" smd custom
			(at 0.557 0)
			(size 1.725 2.235)
			(layers "F.Cu" "F.Mask" "F.Paste")
			(net 115 "/USB-PD/VCC")
			(pinfunction "D")
			(pintype "passive")
			(zone_connect 2)
			(options
				(clearance outline)
				(anchor rect)
			)
			(primitives
				(gr_poly
					(pts
						(xy 0.8625 0.1275) (xy 0.8625 -0.1275) (xy 1.3725 -0.1275) (xy 1.3725 -0.5325) (xy 0.8625 -0.5325)
						(xy 0.8625 -0.7875) (xy 1.3725 -0.7875) (xy 1.3725 -1.195) (xy 0.6125 -1.195) (xy 0.6125 1.195)
						(xy 1.3725 1.195) (xy 1.3725 0.7875) (xy 0.8625 0.7875) (xy 0.8625 0.5325) (xy 1.3725 0.5325)
						(xy 1.3725 0.1275)
					)
					(width 0)
					(fill yes)
				)
			)
		)
	)
	(footprint "antmicro-footprints:C_0402_1005Metric"
		(layer "F.Cu")
		(at 151.900001 47.620001 90)
		(descr "Capacitor SMD 0402")
		(tags "capacitor SMD 0402")
		(property "Reference" "C10"
			(at 1.020001 3.699998 90)
			(layer "F.SilkS")
			(effects
				(font
					(size 0.7 0.7)
					(thickness 0.15)
				)
				(justify right top)
			)
		)
		(property "Value" "C_1u_25V_0402"
			(at -1.022927 2.155213 90)
			(layer "F.Fab")
			(effects
				(font
					(size 0.7 0.7)
					(thickness 0.15)
				)
				(justify left bottom)
			)
		)
		(property "Datasheet" "https://www.murata.com/products/productdetail?partno=GRM155R61E105KE11%23"
			(at 0 0 90)
			(layer "F.Fab")
			(hide yes)
			(effects
				(font
					(size 1.27 1.27)
					(thickness 0.15)
				)
			)
		)
		(property "Description" "SMD Multilayer Ceramic Capacitor, 1 µF, 25 V, 0402 [1005 Metric], ± 10%, X5R, GRM Series"
			(at 0 0 90)
			(layer "F.Fab")
			(hide yes)
			(effects
				(font
					(size 1.27 1.27)
					(thickness 0.15)
				)
			)
		)
		(property "MPN" "GRM155R61E105KE11J"
			(at 0 0 90)
			(unlocked yes)
			(layer "F.Fab")
			(hide yes)
			(effects
				(font
					(size 1 1)
					(thickness 0.15)
				)
			)
		)
		(property "Manufacturer" "Murata"
			(at 0 0 90)
			(unlocked yes)
			(layer "F.Fab")
			(hide yes)
			(effects
				(font
					(size 1 1)
					(thickness 0.15)
				)
			)
		)
		(property "License" "Apache-2.0"
			(at 0 0 90)
			(unlocked yes)
			(layer "F.Fab")
			(hide yes)
			(effects
				(font
					(size 1 1)
					(thickness 0.15)
				)
			)
		)
		(property "Author" "Antmicro"
			(at 0 0 90)
			(unlocked yes)
			(layer "F.Fab")
			(hide yes)
			(effects
				(font
					(size 1 1)
					(thickness 0.15)
				)
			)
		)
		(property "Val" "1u"
			(at 0 0 90)
			(unlocked yes)
			(layer "F.Fab")
			(hide yes)
			(effects
				(font
					(size 1 1)
					(thickness 0.15)
				)
			)
		)
		(property "Voltage" "25V"
			(at 0 0 90)
			(unlocked yes)
			(layer "F.Fab")
			(hide yes)
			(effects
				(font
					(size 1 1)
					(thickness 0.15)
				)
			)
		)
		(property "Dielectric" "X5R"
			(at 0 0 90)
			(unlocked yes)
			(layer "F.Fab")
			(hide yes)
			(effects
				(font
					(size 1 1)
					(thickness 0.15)
				)
			)
		)
		(sheetname "/USB-PD/")
		(sheetfile "usb-pd.kicad_sch")
		(attr smd)
		(fp_rect
			(start -0.925 -0.47)
			(end 0.925 0.47)
			(stroke
				(width 0.05)
				(type default)
			)
			(fill no)
			(layer "F.CrtYd")
		)
		(fp_line
			(start 0.504 -0.25)
			(end 0.504 0.248)
			(stroke
				(width 0.15)
				(type solid)
			)
			(layer "F.Fab")
		)
		(fp_line
			(start -0.494 -0.25)
			(end 0.504 -0.25)
			(stroke
				(width 0.15)
				(type solid)
			)
			(layer "F.Fab")
		)
		(fp_line
			(start 0.504 0.248)
			(end -0.494 0.248)
			(stroke
				(width 0.15)
				(type solid)
			)
			(layer "F.Fab")
		)
		(fp_line
			(start -0.494 0.248)
			(end -0.494 -0.25)
			(stroke
				(width 0.15)
				(type solid)
			)
			(layer "F.Fab")
		)
		(fp_text user "License: Apache-2.0"
			(at -0.939 5.799 90)
			(layer "F.Fab")
			(effects
				(font
					(size 0.7 0.7)
					(thickness 0.15)
				)
				(justify left bottom)
			)
		)
		(fp_text user "Author: Antmicro"
			(at -0.939 3.399 90)
			(layer "F.Fab")
			(effects
				(font
					(size 0.7 0.7)
					(thickness 0.15)
				)
				(justify left bottom)
			)
		)
		(fp_text user "${REFERENCE}"
			(at 0 0 270)
			(layer "F.Fab")
			(effects
				(font
					(size 0.7 0.7)
					(thickness 0.15)
				)
				(justify right top)
			)
		)
		(pad "1" smd roundrect
			(at -0.48 0 90)
			(size 0.59 0.64)
			(layers "F.Cu" "F.Mask" "F.Paste")
			(roundrect_rratio 0.25)
			(net 84 "Net-(Q6-G)")
			(pintype "passive")
		)
		(pad "2" smd roundrect
			(at 0.48 0 90)
			(size 0.59 0.64)
			(layers "F.Cu" "F.Mask" "F.Paste")
			(roundrect_rratio 0.25)
			(net 113 "VBUS")
			(pintype "passive")
		)
	)
	(footprint "antmicro-footprints:R_0402_1005Metric"
		(layer "F.Cu")
		(at 131.72 151.999999)
		(descr "Resistor SMD 0402")
		(tags "resistor SMD 0402")
		(property "Reference" "R42"
			(at 1.08 0.400001 180)
			(layer "F.SilkS")
			(effects
				(font
					(size 0.7 0.7)
					(thickness 0.15)
				)
				(justify left bottom)
			)
		)
		(property "Value" "R_1k_0402"
			(at -1.011843 1.772046 0)
			(layer "F.Fab")
			(effects
				(font
					(size 0.7 0.7)
					(thickness 0.15)
				)
				(justify left bottom)
			)
		)
		(property "Datasheet" "https://www.bourns.com/docs/product-datasheets/cr.pdf"
			(at 0 0 0)
			(layer "F.Fab")
			(hide yes)
			(effects
				(font
					(size 1.27 1.27)
					(thickness 0.15)
				)
			)
		)
		(property "Description" "SMD Chip Resistor, 1 kohm, ± 1%, 63 mW, 0402 [1005 Metric], Thick Film, General Purpose"
			(at 0 0 0)
			(layer "F.Fab")
			(hide yes)
			(effects
				(font
					(size 1.27 1.27)
					(thickness 0.15)
				)
			)
		)
		(property "MPN" "CR0402-FX-1001GLF"
			(at 0 0 0)
			(unlocked yes)
			(layer "F.Fab")
			(hide yes)
			(effects
				(font
					(size 1 1)
					(thickness 0.15)
				)
			)
		)
		(property "Manufacturer" "Bourns"
			(at 0 0 0)
			(unlocked yes)
			(layer "F.Fab")
			(hide yes)
			(effects
				(font
					(size 1 1)
					(thickness 0.15)
				)
			)
		)
		(property "License" "Apache-2.0"
			(at 0 0 0)
			(unlocked yes)
			(layer "F.Fab")
			(hide yes)
			(effects
				(font
					(size 1 1)
					(thickness 0.15)
				)
			)
		)
		(property "Author" "Antmicro"
			(at 0 0 0)
			(unlocked yes)
			(layer "F.Fab")
			(hide yes)
			(effects
				(font
					(size 1 1)
					(thickness 0.15)
				)
			)
		)
		(property "Val" "1k"
			(at 0 0 0)
			(unlocked yes)
			(layer "F.Fab")
			(hide yes)
			(effects
				(font
					(size 1 1)
					(thickness 0.15)
				)
			)
		)
		(property "Tolerance" "1%"
			(at 0 0 0)
			(unlocked yes)
			(layer "F.Fab")
			(hide yes)
			(effects
				(font
					(size 1 1)
					(thickness 0.15)
				)
			)
		)
		(sheetname "/Power/")
		(sheetfile "power.kicad_sch")
		(attr smd)
		(fp_rect
			(start -0.925 -0.47)
			(end 0.925 0.47)
			(stroke
				(width 0.05)
				(type default)
			)
			(fill no)
			(layer "F.CrtYd")
		)
		(fp_rect
			(start -0.5 -0.25)
			(end 0.5 0.25)
			(stroke
				(width 0.15)
				(type solid)
			)
			(fill no)
			(layer "F.Fab")
		)
		(fp_text user "${REFERENCE}"
			(at 0 0 0)
			(layer "F.Fab")
			(effects
				(font
					(size 0.7 0.7)
					(thickness 0.15)
				)
				(justify left bottom)
			)
		)
		(fp_text user "License: Apache-2.0"
			(at -0.949999 5.169 0)
			(layer "F.Fab")
			(effects
				(font
					(size 0.7 0.7)
					(thickness 0.15)
				)
				(justify left bottom)
			)
		)
		(fp_text user "Author: Antmicro"
			(at -0.95 4.169 0)
			(layer "F.Fab")
			(effects
				(font
					(size 0.7 0.7)
					(thickness 0.15)
				)
				(justify left bottom)
			)
		)
		(pad "1" smd roundrect
			(at -0.48 0)
			(size 0.59 0.64)
			(layers "F.Cu" "F.Mask" "F.Paste")
			(roundrect_rratio 0.25)
			(net 161 "Net-(Q3-D)")
			(pintype "passive")
		)
		(pad "2" smd roundrect
			(at 0.48 0)
			(size 0.59 0.64)
			(layers "F.Cu" "F.Mask" "F.Paste")
			(roundrect_rratio 0.25)
			(net 90 "Net-(D2-C)")
			(pintype "passive")
		)
	)
	(footprint "antmicro-footprints:C_0805_2012Metric"
		(layer "F.Cu")
		(at 132 96.650001)
		(descr "Capacitor SMD 0805")
		(tags "capacitor SMD 0805")
		(property "Reference" "C19"
			(at -4.2 0.349999 180)
			(layer "F.SilkS")
			(effects
				(font
					(size 0.7 0.7)
					(thickness 0.15)
				)
				(justify left bottom)
			)
		)
		(property "Value" "C_22u_25V_0805"
			(at -2.055717 1.963153 0)
			(layer "F.Fab")
			(effects
				(font
					(size 0.7 0.7)
					(thickness 0.15)
				)
				(justify left bottom)
			)
		)
		(property "Datasheet" "https://product.samsungsem.com/mlcc/CL21A226MAYNNN.do"
			(at 0 0 0)
			(layer "F.Fab")
			(hide yes)
			(effects
				(font
					(size 1.27 1.27)
					(thickness 0.15)
				)
			)
		)
		(property "Description" "SMT Multilayer Ceramic Capacitor, 22uF, +/-20%, 25V, X5R, 0805 [2012 Metric]"
			(at 0 0 0)
			(layer "F.Fab")
			(hide yes)
			(effects
				(font
					(size 1.27 1.27)
					(thickness 0.15)
				)
			)
		)
		(property "MPN" "CL21A226MAYNNNE"
			(at 0 0 0)
			(unlocked yes)
			(layer "F.Fab")
			(hide yes)
			(effects
				(font
					(size 1 1)
					(thickness 0.15)
				)
			)
		)
		(property "Manufacturer" "Samsung Electro-Mechanics"
			(at 0 0 0)
			(unlocked yes)
			(layer "F.Fab")
			(hide yes)
			(effects
				(font
					(size 1 1)
					(thickness 0.15)
				)
			)
		)
		(property "License" "Apache-2.0"
			(at 0 0 0)
			(unlocked yes)
			(layer "F.Fab")
			(hide yes)
			(effects
				(font
					(size 1 1)
					(thickness 0.15)
				)
			)
		)
		(property "Author" "Antmicro"
			(at 0 0 0)
			(unlocked yes)
			(layer "F.Fab")
			(hide yes)
			(effects
				(font
					(size 1 1)
					(thickness 0.15)
				)
			)
		)
		(property "Val" "22u"
			(at 0 0 0)
			(unlocked yes)
			(layer "F.Fab")
			(hide yes)
			(effects
				(font
					(size 1 1)
					(thickness 0.15)
				)
			)
		)
		(property "Voltage" "25V"
			(at 0 0 0)
			(unlocked yes)
			(layer "F.Fab")
			(hide yes)
			(effects
				(font
					(size 1 1)
					(thickness 0.15)
				)
			)
		)
		(property "Dielectric" "X5R"
			(at 0 0 0)
			(unlocked yes)
			(layer "F.Fab")
			(hide yes)
			(effects
				(font
					(size 1 1)
					(thickness 0.15)
				)
			)
		)
		(property "Public" "False"
			(at 0 0 0)
			(unlocked yes)
			(layer "F.Fab")
			(hide yes)
			(effects
				(font
					(size 1 1)
					(thickness 0.15)
				)
			)
		)
		(sheetname "/USB-PD/")
		(sheetfile "usb-pd.kicad_sch")
		(attr smd)
		(fp_line
			(start -0.3 -0.7)
			(end 0.3 -0.7)
			(stroke
				(width 0.15)
				(type solid)
			)
			(layer "F.SilkS")
		)
		(fp_line
			(start -0.3 0.7)
			(end 0.3 0.7)
			(stroke
				(width 0.15)
				(type solid)
			)
			(layer "F.SilkS")
		)
		(fp_rect
			(start 1.95 -0.9)
			(end -1.95 0.9)
			(stroke
				(width 0.05)
				(type default)
			)
			(fill no)
			(layer "F.CrtYd")
		)
		(fp_rect
			(start -0.95 -0.675)
			(end 0.95 0.675)
			(stroke
				(width 0.15)
				(type solid)
			)
			(fill no)
			(layer "F.Fab")
		)
		(fp_text user "Author: Antmicro"
			(at -1.9 5.947 0)
			(layer "F.Fab")
			(effects
				(font
					(size 0.7 0.7)
					(thickness 0.15)
				)
				(justify left bottom)
			)
		)
		(fp_text user "${REFERENCE}"
			(at 0 0 0)
			(layer "F.Fab")
			(effects
				(font
					(size 0.7 0.7)
					(thickness 0.15)
				)
				(justify left bottom)
			)
		)
		(fp_text user "License: Apache-2.0"
			(at -1.9 4.947 0)
			(layer "F.Fab")
			(effects
				(font
					(size 0.7 0.7)
					(thickness 0.15)
				)
				(justify left bottom)
			)
		)
		(pad "1" smd roundrect
			(at -1.1 0)
			(size 1.2 1.3)
			(layers "F.Cu" "F.Mask" "F.Paste")
			(roundrect_rratio 0.25)
			(net 66 "GND")
			(pintype "passive")
		)
		(pad "2" smd roundrect
			(at 1.1 0)
			(size 1.2 1.3)
			(layers "F.Cu" "F.Mask" "F.Paste")
			(roundrect_rratio 0.25)
			(net 187 "/USB-PD/12V_CONV")
			(pintype "passive")
		)
	)
	(footprint "antmicro-footprints:R_0402_1005Metric"
		(layer "F.Cu")
		(at 120.5 128.8)
		(descr "Resistor SMD 0402")
		(tags "resistor SMD 0402")
		(property "Reference" "R54"
			(at -3.3 0.4 180)
			(layer "F.SilkS")
			(effects
				(font
					(size 0.7 0.7)
					(thickness 0.15)
				)
				(justify left bottom)
			)
		)
		(property "Value" "R_10k_0402"
			(at -1.011843 1.772046 0)
			(layer "F.Fab")
			(effects
				(font
					(size 0.7 0.7)
					(thickness 0.15)
				)
				(justify left bottom)
			)
		)
		(property "Datasheet" "https://www.bourns.com/docs/product-datasheets/cr.pdf"
			(at 0 0 0)
			(layer "F.Fab")
			(hide yes)
			(effects
				(font
					(size 1.27 1.27)
					(thickness 0.15)
				)
			)
		)
		(property "Description" "SMD Chip Resistor, 10 kohm, ± 1%, 62.5 mW, 0402 [1005 Metric], Thick Film, General Purpose"
			(at 0 0 0)
			(layer "F.Fab")
			(hide yes)
			(effects
				(font
					(size 1.27 1.27)
					(thickness 0.15)
				)
			)
		)
		(property "MPN" "CR0402-FX-1002GLF"
			(at 0 0 0)
			(unlocked yes)
			(layer "F.Fab")
			(hide yes)
			(effects
				(font
					(size 1 1)
					(thickness 0.15)
				)
			)
		)
		(property "Manufacturer" "Bourns"
			(at 0 0 0)
			(unlocked yes)
			(layer "F.Fab")
			(hide yes)
			(effects
				(font
					(size 1 1)
					(thickness 0.15)
				)
			)
		)
		(property "License" "Apache-2.0"
			(at 0 0 0)
			(unlocked yes)
			(layer "F.Fab")
			(hide yes)
			(effects
				(font
					(size 1 1)
					(thickness 0.15)
				)
			)
		)
		(property "Author" "Antmicro"
			(at 0 0 0)
			(unlocked yes)
			(layer "F.Fab")
			(hide yes)
			(effects
				(font
					(size 1 1)
					(thickness 0.15)
				)
			)
		)
		(property "Val" "10k"
			(at 0 0 0)
			(unlocked yes)
			(layer "F.Fab")
			(hide yes)
			(effects
				(font
					(size 1 1)
					(thickness 0.15)
				)
			)
		)
		(property "Tolerance" "1%"
			(at 0 0 0)
			(unlocked yes)
			(layer "F.Fab")
			(hide yes)
			(effects
				(font
					(size 1 1)
					(thickness 0.15)
				)
			)
		)
		(sheetname "/Power/")
		(sheetfile "power.kicad_sch")
		(attr smd)
		(fp_rect
			(start -0.925 -0.47)
			(end 0.925 0.47)
			(stroke
				(width 0.05)
				(type default)
			)
			(fill no)
			(layer "F.CrtYd")
		)
		(fp_rect
			(start -0.5 -0.25)
			(end 0.5 0.25)
			(stroke
				(width 0.15)
				(type solid)
			)
			(fill no)
			(layer "F.Fab")
		)
		(fp_text user "Author: Antmicro"
			(at -0.95 4.169 0)
			(layer "F.Fab")
			(effects
				(font
					(size 0.7 0.7)
					(thickness 0.15)
				)
				(justify left bottom)
			)
		)
		(fp_text user "License: Apache-2.0"
			(at -0.949999 5.169 0)
			(layer "F.Fab")
			(effects
				(font
					(size 0.7 0.7)
					(thickness 0.15)
				)
				(justify left bottom)
			)
		)
		(fp_text user "${REFERENCE}"
			(at 0 0 0)
			(layer "F.Fab")
			(effects
				(font
					(size 0.7 0.7)
					(thickness 0.15)
				)
				(justify left bottom)
			)
		)
		(pad "1" smd roundrect
			(at -0.48 0)
			(size 0.59 0.64)
			(layers "F.Cu" "F.Mask" "F.Paste")
			(roundrect_rratio 0.25)
			(net 87 "+12V")
			(pintype "passive")
		)
		(pad "2" smd roundrect
			(at 0.48 0)
			(size 0.59 0.64)
			(layers "F.Cu" "F.Mask" "F.Paste")
			(roundrect_rratio 0.25)
			(net 106 "/Power/3V3_EN")
			(pintype "passive")
		)
	)
	(footprint "antmicro-footprints:R_0402_1005Metric"
		(layer "F.Cu")
		(at 154.312 51.001)
		(descr "Resistor SMD 0402")
		(tags "resistor SMD 0402")
		(property "Reference" "R18"
			(at 1.088 0.399 180)
			(layer "F.SilkS")
			(effects
				(font
					(size 0.7 0.7)
					(thickness 0.15)
				)
				(justify left bottom)
			)
		)
		(property "Value" "R_2k_0402"
			(at -1.011843 1.772046 0)
			(layer "F.Fab")
			(effects
				(font
					(size 0.7 0.7)
					(thickness 0.15)
				)
				(justify left bottom)
			)
		)
		(property "Datasheet" "https://www.bourns.com/docs/product-datasheets/cr.pdf"
			(at 0 0 0)
			(layer "F.Fab")
			(hide yes)
			(effects
				(font
					(size 1.27 1.27)
					(thickness 0.15)
				)
			)
		)
		(property "Description" "SMD Chip Resistor, 2 kohm, ± 1%, 62.5 mW, 0402 [1005 Metric], Thick Film, General Purpose"
			(at 0 0 0)
			(layer "F.Fab")
			(hide yes)
			(effects
				(font
					(size 1.27 1.27)
					(thickness 0.15)
				)
			)
		)
		(property "MPN" "CR0402-FX-2001GLF"
			(at 0 0 0)
			(unlocked yes)
			(layer "F.Fab")
			(hide yes)
			(effects
				(font
					(size 1 1)
					(thickness 0.15)
				)
			)
		)
		(property "Manufacturer" "Bourns"
			(at 0 0 0)
			(unlocked yes)
			(layer "F.Fab")
			(hide yes)
			(effects
				(font
					(size 1 1)
					(thickness 0.15)
				)
			)
		)
		(property "License" "Apache-2.0"
			(at 0 0 0)
			(unlocked yes)
			(layer "F.Fab")
			(hide yes)
			(effects
				(font
					(size 1 1)
					(thickness 0.15)
				)
			)
		)
		(property "Author" "Antmicro"
			(at 0 0 0)
			(unlocked yes)
			(layer "F.Fab")
			(hide yes)
			(effects
				(font
					(size 1 1)
					(thickness 0.15)
				)
			)
		)
		(property "Val" "2k"
			(at 0 0 0)
			(unlocked yes)
			(layer "F.Fab")
			(hide yes)
			(effects
				(font
					(size 1 1)
					(thickness 0.15)
				)
			)
		)
		(property "Tolerance" "1%"
			(at 0 0 0)
			(unlocked yes)
			(layer "F.Fab")
			(hide yes)
			(effects
				(font
					(size 1 1)
					(thickness 0.15)
				)
			)
		)
		(sheetname "/USB-PD/")
		(sheetfile "usb-pd.kicad_sch")
		(attr smd)
		(fp_rect
			(start -0.925 -0.47)
			(end 0.925 0.47)
			(stroke
				(width 0.05)
				(type default)
			)
			(fill no)
			(layer "F.CrtYd")
		)
		(fp_rect
			(start -0.5 -0.25)
			(end 0.5 0.25)
			(stroke
				(width 0.15)
				(type solid)
			)
			(fill no)
			(layer "F.Fab")
		)
		(fp_text user "${REFERENCE}"
			(at 0 0 0)
			(layer "F.Fab")
			(effects
				(font
					(size 0.7 0.7)
					(thickness 0.15)
				)
				(justify left bottom)
			)
		)
		(fp_text user "License: Apache-2.0"
			(at -0.949999 5.169 0)
			(layer "F.Fab")
			(effects
				(font
					(size 0.7 0.7)
					(thickness 0.15)
				)
				(justify left bottom)
			)
		)
		(fp_text user "Author: Antmicro"
			(at -0.95 4.169 0)
			(layer "F.Fab")
			(effects
				(font
					(size 0.7 0.7)
					(thickness 0.15)
				)
				(justify left bottom)
			)
		)
		(pad "1" smd roundrect
			(at -0.48 0)
			(size 0.59 0.64)
			(layers "F.Cu" "F.Mask" "F.Paste")
			(roundrect_rratio 0.25)
			(net 142 "/USB-PD/SCL")
			(pintype "passive")
		)
		(pad "2" smd roundrect
			(at 0.48 0)
			(size 0.59 0.64)
			(layers "F.Cu" "F.Mask" "F.Paste")
			(roundrect_rratio 0.25)
			(net 117 "/USB-PD/VDDD_3V3")
			(pintype "passive")
		)
	)
	(footprint "antmicro-footprints:USB-C_Receptacle_GCT_USB4105-GF-A"
		(locked yes)
		(layer "F.Cu")
		(at 144.2 35 180)
		(property "Reference" "J3"
			(at -1.6 -5.4 180)
			(layer "F.SilkS")
			(effects
				(font
					(size 0.7 0.7)
					(thickness 0.15)
				)
				(justify left bottom)
			)
		)
		(property "Value" "USB-C_GCT_USB4105-GF-A"
			(at 0 5 0)
			(layer "F.Fab")
			(effects
				(font
					(size 0.7 0.7)
					(thickness 0.15)
				)
				(justify right top)
			)
		)
		(property "Datasheet" "https://gct.co/files/drawings/usb4105.pdf"
			(at 0 0 0)
			(layer "F.Fab")
			(hide yes)
			(effects
				(font
					(size 1.27 1.27)
					(thickness 0.15)
				)
			)
		)
		(property "Description" "USB-C (USB TYPE-C) USB 2.0 Receptacle Connector 24 (16+8 Dummy) Position Surface Mount, Right Angle"
			(at 0 0 0)
			(layer "F.Fab")
			(hide yes)
			(effects
				(font
					(size 1.27 1.27)
					(thickness 0.15)
				)
			)
		)
		(property "Manufacturer" "GCT"
			(at 0 0 180)
			(unlocked yes)
			(layer "F.Fab")
			(hide yes)
			(effects
				(font
					(size 1 1)
					(thickness 0.15)
				)
			)
		)
		(property "MPN" "USB4105-GF-A"
			(at 0 0 180)
			(unlocked yes)
			(layer "F.Fab")
			(hide yes)
			(effects
				(font
					(size 1 1)
					(thickness 0.15)
				)
			)
		)
		(property "Author" "Antmicro"
			(at 0 0 180)
			(unlocked yes)
			(layer "F.Fab")
			(hide yes)
			(effects
				(font
					(size 1 1)
					(thickness 0.15)
				)
			)
		)
		(property "License" "Apache-2.0"
			(at 0 0 180)
			(unlocked yes)
			(layer "F.Fab")
			(hide yes)
			(effects
				(font
					(size 1 1)
					(thickness 0.15)
				)
			)
		)
		(sheetname "/USB-PD/")
		(sheetfile "usb-pd.kicad_sch")
		(attr smd)
		(fp_line
			(start 4.788 3.854)
			(end 4.788 2.575)
			(stroke
				(width 0.15)
				(type solid)
			)
			(layer "F.SilkS")
		)
		(fp_line
			(start 4.788 -1.395)
			(end 4.788 -0.145)
			(stroke
				(width 0.15)
				(type solid)
			)
			(layer "F.SilkS")
		)
		(fp_line
			(start -4.79 3.854)
			(end 4.788 3.854)
			(stroke
				(width 0.15)
				(type solid)
			)
			(layer "F.SilkS")
		)
		(fp_line
			(start -4.79 2.575)
			(end -4.79 3.854)
			(stroke
				(width 0.15)
				(type solid)
			)
			(layer "F.SilkS")
		)
		(fp_line
			(start -4.79 -1.395)
			(end -4.79 -0.145)
			(stroke
				(width 0.15)
				(type solid)
			)
			(layer "F.SilkS")
		)
		(fp_circle
			(center -3.8 -4.27071)
			(end -3.75 -4.22071)
			(stroke
				(width 0.15)
				(type solid)
			)
			(fill yes)
			(layer "F.SilkS")
		)
		(fp_rect
			(start -5.1 -4.4)
			(end 5.1 3.9)
			(stroke
				(width 0.05)
				(type solid)
			)
			(fill no)
			(layer "F.CrtYd")
		)
		(fp_line
			(start 4.788 3.854)
			(end -4.79 3.854)
			(stroke
				(width 0.15)
				(type solid)
			)
			(layer "F.Fab")
		)
		(fp_line
			(start 4.788 -3.676)
			(end 4.788 3.854)
			(stroke
				(width 0.15)
				(type solid)
			)
			(layer "F.Fab")
		)
		(fp_line
			(start -4.702 3.854)
			(end 4.788 3.854)
			(stroke
				(width 0.15)
				(type solid)
			)
			(layer "F.Fab")
		)
		(fp_line
			(start -4.79 3.854)
			(end -4.79 -3.676)
			(stroke
				(width 0.15)
				(type solid)
			)
			(layer "F.Fab")
		)
		(fp_line
			(start -4.79 -3.676)
			(end 4.788 -3.676)
			(stroke
				(width 0.15)
				(type solid)
			)
			(layer "F.Fab")
		)
		(fp_text user "Author: Antmicro"
			(at -4.79 7.853 0)
			(layer "F.Fab")
			(effects
				(font
					(size 0.7 0.7)
					(thickness 0.15)
				)
				(justify right top)
			)
		)
		(fp_text user "License: Apache-2.0"
			(at -4.79 8.855 0)
			(layer "F.Fab")
			(effects
				(font
					(size 0.7 0.7)
					(thickness 0.15)
				)
				(justify right top)
			)
		)
		(fp_text user "${REFERENCE}"
			(at 0 -0.247999 180)
			(layer "F.Fab")
			(effects
				(font
					(size 0.7 0.7)
					(thickness 0.15)
				)
				(justify left bottom)
			)
		)
		(fp_text user "PCB-EDGE"
			(at -4.789999 5.853 0)
			(layer "F.Fab")
			(effects
				(font
					(size 0.7 0.7)
					(thickness 0.15)
				)
				(justify right top)
			)
		)
		(pad "" np_thru_hole circle
			(at -2.891 -2.426 180)
			(size 0.65 0.65)
			(drill 0.65)
			(layers "*.Cu" "*.Mask")
		)
		(pad "" np_thru_hole circle
			(at 2.89 -2.426 180)
			(size 0.65 0.65)
			(drill 0.65)
			(layers "*.Cu" "*.Mask")
		)
		(pad "A1" smd roundrect
			(at -3.202 -3.5 180)
			(size 0.6 1.15)
			(layers "F.Cu" "F.Mask" "F.Paste")
			(roundrect_rratio 0.25)
			(net 66 "GND")
			(pinfunction "GND")
			(pintype "power_in")
		)
		(pad "A4" smd roundrect
			(at -2.4 -3.5 180)
			(size 0.6 1.15)
			(layers "F.Cu" "F.Mask" "F.Paste")
			(roundrect_rratio 0.25)
			(net 113 "VBUS")
			(pinfunction "VBUS")
			(pintype "passive")
		)
		(pad "A5" smd roundrect
			(at -1.25 -3.5 180)
			(size 0.3 1.15)
			(layers "F.Cu" "F.Mask" "F.Paste")
			(roundrect_rratio 0.25)
			(net 140 "/USB-PD/CC1")
			(pinfunction "CC_{1}")
			(pintype "bidirectional")
		)
		(pad "A6" smd roundrect
			(at -0.25 -3.5 180)
			(size 0.3 1.15)
			(layers "F.Cu" "F.Mask" "F.Paste")
			(roundrect_rratio 0.25)
			(net 128 "unconnected-(J3-D_{A}+-PadA6)")
			(pinfunction "D_{A}+")
			(pintype "bidirectional+no_connect")
		)
		(pad "A7" smd roundrect
			(at 0.248 -3.5 180)
			(size 0.3 1.15)
			(layers "F.Cu" "F.Mask" "F.Paste")
			(roundrect_rratio 0.25)
			(net 126 "unconnected-(J3-D_{A}--PadA7)")
			(pinfunction "D_{A}-")
			(pintype "bidirectional+no_connect")
		)
		(pad "A8" smd roundrect
			(at 1.249 -3.5 180)
			(size 0.3 1.15)
			(layers "F.Cu" "F.Mask" "F.Paste")
			(roundrect_rratio 0.25)
			(net 130 "unconnected-(J3-SBU_{1}-PadA8)")
			(pinfunction "SBU_{1}")
			(pintype "bidirectional+no_connect")
		)
		(pad "A9" smd roundrect
			(at 2.398 -3.5 180)
			(size 0.6 1.15)
			(layers "F.Cu" "F.Mask" "F.Paste")
			(roundrect_rratio 0.25)
			(net 113 "VBUS")
			(pinfunction "VBUS")
			(pintype "passive")
		)
		(pad "A12" smd roundrect
			(at 3.2 -3.5 180)
			(size 0.6 1.15)
			(layers "F.Cu" "F.Mask" "F.Paste")
			(roundrect_rratio 0.25)
			(net 66 "GND")
			(pinfunction "GND")
			(pintype "passive")
		)
		(pad "B1" smd roundrect
			(at 3.2 -3.5 180)
			(size 0.6 1.15)
			(layers "F.Cu" "F.Mask" "F.Paste")
			(roundrect_rratio 0.25)
			(net 66 "GND")
			(pinfunction "GND")
			(pintype "passive")
		)
		(pad "B4" smd roundrect
			(at 2.398 -3.5 180)
			(size 0.6 1.15)
			(layers "F.Cu" "F.Mask" "F.Paste")
			(roundrect_rratio 0.25)
			(net 113 "VBUS")
			(pinfunction "VBUS")
			(pintype "passive")
		)
		(pad "B5" smd roundrect
			(at 1.749 -3.5 180)
			(size 0.3 1.15)
			(layers "F.Cu" "F.Mask" "F.Paste")
			(roundrect_rratio 0.25)
			(net 139 "/USB-PD/CC2")
			(pinfunction "CC_{2}")
			(pintype "bidirectional")
		)
		(pad "B6" smd roundrect
			(at 0.748 -3.5 180)
			(size 0.3 1.15)
			(layers "F.Cu" "F.Mask" "F.Paste")
			(roundrect_rratio 0.25)
			(net 127 "unconnected-(J3-D_{B}+-PadB6)")
			(pinfunction "D_{B}+")
			(pintype "bidirectional+no_connect")
		)
		(pad "B7" smd roundrect
			(at -0.75 -3.5 180)
			(size 0.3 1.15)
			(layers "F.Cu" "F.Mask" "F.Paste")
			(roundrect_rratio 0.25)
			(net 129 "unconnected-(J3-D_{B}--PadB7)")
			(pinfunction "D_{B}-")
			(pintype "bidirectional+no_connect")
		)
		(pad "B8" smd roundrect
			(at -1.75 -3.5 180)
			(size 0.3 1.15)
			(layers "F.Cu" "F.Mask" "F.Paste")
			(roundrect_rratio 0.25)
			(net 131 "unconnected-(J3-SBU_{2}-PadB8)")
			(pinfunction "SBU_{2}")
			(pintype "bidirectional+no_connect")
		)
		(pad "B9" smd roundrect
			(at -2.4 -3.5 180)
			(size 0.6 1.15)
			(layers "F.Cu" "F.Mask" "F.Paste")
			(roundrect_rratio 0.25)
			(net 113 "VBUS")
			(pinfunction "VBUS")
			(pintype "passive")
		)
		(pad "B12" smd roundrect
			(at -3.202 -3.5 180)
			(size 0.6 1.15)
			(layers "F.Cu" "F.Mask" "F.Paste")
			(roundrect_rratio 0.25)
			(net 66 "GND")
			(pinfunction "GND")
			(pintype "passive")
		)
		(pad "SH" thru_hole oval
			(at -4.321 -2.926 180)
			(size 1.05 2.1)
			(drill oval 0.6 1.7)
			(layers "*.Cu" "*.Mask")
			(remove_unused_layers no)
			(net 66 "GND")
			(pinfunction "SH")
			(pintype "passive")
		)
		(pad "SH" thru_hole oval
			(at -4.321 1.255 180)
			(size 1 2)
			(drill oval 0.6 1.4)
			(layers "*.Cu" "*.Mask")
			(remove_unused_layers no)
			(net 66 "GND")
			(pinfunction "SH")
			(pintype "passive")
		)
		(pad "SH" thru_hole oval
			(at 4.32 -2.926 180)
			(size 1.05 2.1)
			(drill oval 0.6 1.7)
			(layers "*.Cu" "*.Mask")
			(remove_unused_layers no)
			(net 66 "GND")
			(pinfunction "SH")
			(pintype "passive")
		)
		(pad "SH" thru_hole oval
			(at 4.32 1.255 180)
			(size 1 2)
			(drill oval 0.6 1.4)
			(layers "*.Cu" "*.Mask")
			(remove_unused_layers no)
			(net 66 "GND")
			(pinfunction "SH")
			(pintype "passive")
		)
	)
	(footprint "antmicro-footprints:R_0402_1005Metric"
		(layer "F.Cu")
		(at 148.736999 57.376001 -90)
		(descr "Resistor SMD 0402")
		(tags "resistor SMD 0402")
		(property "Reference" "R4"
			(at 1.773999 0.360998 90)
			(layer "F.SilkS")
			(effects
				(font
					(size 0.7 0.7)
					(thickness 0.15)
				)
				(justify right top)
			)
		)
		(property "Value" "R_1k_0402"
			(at -1.011843 1.772046 90)
			(layer "F.Fab")
			(effects
				(font
					(size 0.7 0.7)
					(thickness 0.15)
				)
				(justify right top)
			)
		)
		(property "Datasheet" "https://www.bourns.com/docs/product-datasheets/cr.pdf"
			(at 0 0 90)
			(layer "F.Fab")
			(hide yes)
			(effects
				(font
					(size 1.27 1.27)
					(thickness 0.15)
				)
			)
		)
		(property "Description" "SMD Chip Resistor, 1 kohm, ± 1%, 63 mW, 0402 [1005 Metric], Thick Film, General Purpose"
			(at 0 0 90)
			(layer "F.Fab")
			(hide yes)
			(effects
				(font
					(size 1.27 1.27)
					(thickness 0.15)
				)
			)
		)
		(property "MPN" "CR0402-FX-1001GLF"
			(at 0 0 270)
			(unlocked yes)
			(layer "F.Fab")
			(hide yes)
			(effects
				(font
					(size 1 1)
					(thickness 0.15)
				)
			)
		)
		(property "Manufacturer" "Bourns"
			(at 0 0 270)
			(unlocked yes)
			(layer "F.Fab")
			(hide yes)
			(effects
				(font
					(size 1 1)
					(thickness 0.15)
				)
			)
		)
		(property "License" "Apache-2.0"
			(at 0 0 270)
			(unlocked yes)
			(layer "F.Fab")
			(hide yes)
			(effects
				(font
					(size 1 1)
					(thickness 0.15)
				)
			)
		)
		(property "Author" "Antmicro"
			(at 0 0 270)
			(unlocked yes)
			(layer "F.Fab")
			(hide yes)
			(effects
				(font
					(size 1 1)
					(thickness 0.15)
				)
			)
		)
		(property "Val" "1k"
			(at 0 0 270)
			(unlocked yes)
			(layer "F.Fab")
			(hide yes)
			(effects
				(font
					(size 1 1)
					(thickness 0.15)
				)
			)
		)
		(property "Tolerance" "1%"
			(at 0 0 270)
			(unlocked yes)
			(layer "F.Fab")
			(hide yes)
			(effects
				(font
					(size 1 1)
					(thickness 0.15)
				)
			)
		)
		(sheetname "/USB-PD/")
		(sheetfile "usb-pd.kicad_sch")
		(attr smd)
		(fp_rect
			(start -0.925 -0.47)
			(end 0.925 0.47)
			(stroke
				(width 0.05)
				(type default)
			)
			(fill no)
			(layer "F.CrtYd")
		)
		(fp_rect
			(start -0.5 -0.25)
			(end 0.5 0.25)
			(stroke
				(width 0.15)
				(type solid)
			)
			(fill no)
			(layer "F.Fab")
		)
		(fp_text user "Author: Antmicro"
			(at -0.95 4.169 90)
			(layer "F.Fab")
			(effects
				(font
					(size 0.7 0.7)
					(thickness 0.15)
				)
				(justify right top)
			)
		)
		(fp_text user "${REFERENCE}"
			(at 0 0 90)
			(layer "F.Fab")
			(effects
				(font
					(size 0.7 0.7)
					(thickness 0.15)
				)
				(justify right top)
			)
		)
		(fp_text user "License: Apache-2.0"
			(at -0.949999 5.169 90)
			(layer "F.Fab")
			(effects
				(font
					(size 0.7 0.7)
					(thickness 0.15)
				)
				(justify right top)
			)
		)
		(pad "1" smd roundrect
			(at -0.48 0 270)
			(size 0.59 0.64)
			(layers "F.Cu" "F.Mask" "F.Paste")
			(roundrect_rratio 0.25)
			(net 136 "/USB-PD/VBUS_MAX")
			(pintype "passive")
		)
		(pad "2" smd roundrect
			(at 0.48 0 270)
			(size 0.59 0.64)
			(layers "F.Cu" "F.Mask" "F.Paste")
			(roundrect_rratio 0.25)
			(net 117 "/USB-PD/VDDD_3V3")
			(pintype "passive")
		)
	)
	(footprint "antmicro-footprints:USON-10_2.5x1mm_P0.5mm"
		(layer "F.Cu")
		(at 134.6 47.001 -90)
		(descr "USON-10 2.5x1mm_ Pitch 0.5mm")
		(tags "USON-10 2.5x1mm Pitch 0.5mm")
		(property "Reference" "D13"
			(at 1.048002 -0.226933 180)
			(layer "F.SilkS")
			(effects
				(font
					(size 0.7 0.7)
					(thickness 0.15)
				)
				(justify right top)
			)
		)
		(property "Value" "ESD204DQAR"
			(at 0.018 2.499 90)
			(layer "F.Fab")
			(effects
				(font
					(size 0.7 0.7)
					(thickness 0.15)
				)
				(justify right top)
			)
		)
		(property "Datasheet" "https://www.ti.com/lit/ds/symlink/esd204.pdf?ts=1706004844383&ref_url=https%253A%252F%252Fwww.ti.com%252Finterface%252Fdiodes%252Fesd-protection-diodes%252Fproducts.html"
			(at 0 0 90)
			(layer "F.Fab")
			(hide yes)
			(effects
				(font
					(size 1.27 1.27)
					(thickness 0.15)
				)
			)
		)
		(property "Description" "TVS diode array, 30 kV, USON-10, 3.6 V, 0.55 pF"
			(at 0 0 90)
			(layer "F.Fab")
			(hide yes)
			(effects
				(font
					(size 1.27 1.27)
					(thickness 0.15)
				)
			)
		)
		(property "MPN" "ESD204DQAR"
			(at 0 0 270)
			(unlocked yes)
			(layer "F.Fab")
			(hide yes)
			(effects
				(font
					(size 1 1)
					(thickness 0.15)
				)
			)
		)
		(property "Manufacturer" "Texas Instruments"
			(at 0 0 270)
			(unlocked yes)
			(layer "F.Fab")
			(hide yes)
			(effects
				(font
					(size 1 1)
					(thickness 0.15)
				)
			)
		)
		(property "Author" "Antmicro"
			(at 0 0 270)
			(unlocked yes)
			(layer "F.Fab")
			(hide yes)
			(effects
				(font
					(size 1 1)
					(thickness 0.15)
				)
			)
		)
		(property "License" "Apache-2.0"
			(at 0 0 270)
			(unlocked yes)
			(layer "F.Fab")
			(hide yes)
			(effects
				(font
					(size 1 1)
					(thickness 0.15)
				)
			)
		)
		(sheetname "/OCuLink/")
		(sheetfile "oculink.kicad_sch")
		(attr smd)
		(fp_line
			(start 0.498 1.398)
			(end -0.5 1.398)
			(stroke
				(width 0.15)
				(type solid)
			)
			(layer "F.SilkS")
		)
		(fp_line
			(start 0.498 -1.401)
			(end -0.5 -1.401)
			(stroke
				(width 0.15)
				(type solid)
			)
			(layer "F.SilkS")
		)
		(fp_circle
			(center -0.68 -1.27)
			(end -0.63 -1.27)
			(stroke
				(width 0.15)
				(type solid)
			)
			(fill yes)
			(layer "F.SilkS")
		)
		(fp_rect
			(start -0.8 -1.5)
			(end 0.8 1.499)
			(stroke
				(width 0.05)
				(type solid)
			)
			(fill no)
			(layer "F.CrtYd")
		)
		(fp_line
			(start -0.5 1.249)
			(end 0.498 1.249)
			(stroke
				(width 0.15)
				(type solid)
			)
			(layer "F.Fab")
		)
		(fp_line
			(start -0.5 -1)
			(end -0.5 1.249)
			(stroke
				(width 0.15)
				(type solid)
			)
			(layer "F.Fab")
		)
		(fp_line
			(start -0.25 -1.25)
			(end -0.5 -1)
			(stroke
				(width 0.15)
				(type solid)
			)
			(layer "F.Fab")
		)
		(fp_line
			(start 0.498 -1.25)
			(end 0.498 1.249)
			(stroke
				(width 0.15)
				(type solid)
			)
			(layer "F.Fab")
		)
		(fp_line
			(start 0.498 -1.25)
			(end -0.25 -1.25)
			(stroke
				(width 0.15)
				(type solid)
			)
			(layer "F.Fab")
		)
		(fp_text user "${REFERENCE}"
			(at 0 -0.000501 90)
			(layer "F.Fab")
			(effects
				(font
					(size 0.7 0.7)
					(thickness 0.15)
				)
				(justify right top)
			)
		)
		(fp_text user "License: Apache-2.0"
			(at -0.802 6.9 90)
			(layer "F.Fab")
			(effects
				(font
					(size 0.7 0.7)
					(thickness 0.15)
				)
				(justify right top)
			)
		)
		(fp_text user "Author: Antmicro"
			(at -0.802 5.7 90)
			(layer "F.Fab")
			(effects
				(font
					(size 0.7 0.7)
					(thickness 0.15)
				)
				(justify right top)
			)
		)
		(pad "1" smd roundrect
			(at -0.387 -1 180)
			(size 0.25 0.55)
			(layers "F.Cu" "F.Mask" "F.Paste")
			(roundrect_rratio 0.25)
			(net 70 "/OCuLink/PCIe_{x4}.TX2+")
			(pintype "passive")
		)
		(pad "2" smd roundrect
			(at -0.387 -0.5 180)
			(size 0.25 0.55)
			(layers "F.Cu" "F.Mask" "F.Paste")
			(roundrect_rratio 0.25)
			(net 76 "/OCuLink/PCIe_{x4}.TX2-")
			(pintype "passive")
		)
		(pad "3" smd roundrect
			(at -0.387 0 180)
			(size 0.4 0.55)
			(layers "F.Cu" "F.Mask" "F.Paste")
			(roundrect_rratio 0.25)
			(net 66 "GND")
			(pintype "power_in")
		)
		(pad "4" smd roundrect
			(at -0.387 0.498 180)
			(size 0.25 0.55)
			(layers "F.Cu" "F.Mask" "F.Paste")
			(roundrect_rratio 0.25)
			(net 82 "/OCuLink/PCIe_{x4}.TX3+")
			(pintype "passive")
		)
		(pad "5" smd roundrect
			(at -0.387 0.998 180)
			(size 0.25 0.55)
			(layers "F.Cu" "F.Mask" "F.Paste")
			(roundrect_rratio 0.25)
			(net 80 "/OCuLink/PCIe_{x4}.TX3-")
			(pintype "passive")
		)
		(pad "6" smd roundrect
			(at 0.385 0.998 180)
			(size 0.25 0.55)
			(layers "F.Cu" "F.Mask" "F.Paste")
			(roundrect_rratio 0.25)
			(net 80 "/OCuLink/PCIe_{x4}.TX3-")
			(pintype "passive")
		)
		(pad "7" smd roundrect
			(at 0.385 0.498 180)
			(size 0.25 0.55)
			(layers "F.Cu" "F.Mask" "F.Paste")
			(roundrect_rratio 0.25)
			(net 82 "/OCuLink/PCIe_{x4}.TX3+")
			(pintype "passive")
		)
		(pad "8" smd roundrect
			(at 0.385 0 180)
			(size 0.4 0.55)
			(layers "F.Cu" "F.Mask" "F.Paste")
			(roundrect_rratio 0.25)
			(net 66 "GND")
			(pintype "passive")
		)
		(pad "9" smd roundrect
			(at 0.385 -0.5 180)
			(size 0.25 0.55)
			(layers "F.Cu" "F.Mask" "F.Paste")
			(roundrect_rratio 0.25)
			(net 76 "/OCuLink/PCIe_{x4}.TX2-")
			(pintype "passive")
		)
		(pad "10" smd roundrect
			(at 0.385 -1 180)
			(size 0.25 0.55)
			(layers "F.Cu" "F.Mask" "F.Paste")
			(roundrect_rratio 0.25)
			(net 70 "/OCuLink/PCIe_{x4}.TX2+")
			(pintype "passive")
		)
	)
	(footprint "antmicro-footprints:C_0805_2012Metric"
		(layer "F.Cu")
		(at 136.35 93.5 -90)
		(descr "Capacitor SMD 0805")
		(tags "capacitor SMD 0805")
		(property "Reference" "C17"
			(at -2.5 4.75 90)
			(layer "F.SilkS")
			(effects
				(font
					(size 0.7 0.7)
					(thickness 0.15)
				)
				(justify right top)
			)
		)
		(property "Value" "C_22u_25V_0805"
			(at -2.055717 1.963153 90)
			(layer "F.Fab")
			(effects
				(font
					(size 0.7 0.7)
					(thickness 0.15)
				)
				(justify right top)
			)
		)
		(property "Datasheet" "https://product.samsungsem.com/mlcc/CL21A226MAYNNN.do"
			(at 0 0 90)
			(layer "F.Fab")
			(hide yes)
			(effects
				(font
					(size 1.27 1.27)
					(thickness 0.15)
				)
			)
		)
		(property "Description" "SMT Multilayer Ceramic Capacitor, 22uF, +/-20%, 25V, X5R, 0805 [2012 Metric]"
			(at 0 0 90)
			(layer "F.Fab")
			(hide yes)
			(effects
				(font
					(size 1.27 1.27)
					(thickness 0.15)
				)
			)
		)
		(property "MPN" "CL21A226MAYNNNE"
			(at 0 0 270)
			(unlocked yes)
			(layer "F.Fab")
			(hide yes)
			(effects
				(font
					(size 1 1)
					(thickness 0.15)
				)
			)
		)
		(property "Manufacturer" "Samsung Electro-Mechanics"
			(at 0 0 270)
			(unlocked yes)
			(layer "F.Fab")
			(hide yes)
			(effects
				(font
					(size 1 1)
					(thickness 0.15)
				)
			)
		)
		(property "License" "Apache-2.0"
			(at 0 0 270)
			(unlocked yes)
			(layer "F.Fab")
			(hide yes)
			(effects
				(font
					(size 1 1)
					(thickness 0.15)
				)
			)
		)
		(property "Author" "Antmicro"
			(at 0 0 270)
			(unlocked yes)
			(layer "F.Fab")
			(hide yes)
			(effects
				(font
					(size 1 1)
					(thickness 0.15)
				)
			)
		)
		(property "Val" "22u"
			(at 0 0 270)
			(unlocked yes)
			(layer "F.Fab")
			(hide yes)
			(effects
				(font
					(size 1 1)
					(thickness 0.15)
				)
			)
		)
		(property "Voltage" "25V"
			(at 0 0 270)
			(unlocked yes)
			(layer "F.Fab")
			(hide yes)
			(effects
				(font
					(size 1 1)
					(thickness 0.15)
				)
			)
		)
		(property "Dielectric" "X5R"
			(at 0 0 270)
			(unlocked yes)
			(layer "F.Fab")
			(hide yes)
			(effects
				(font
					(size 1 1)
					(thickness 0.15)
				)
			)
		)
		(property "Public" "False"
			(at 0 0 270)
			(unlocked yes)
			(layer "F.Fab")
			(hide yes)
			(effects
				(font
					(size 1 1)
					(thickness 0.15)
				)
			)
		)
		(sheetname "/USB-PD/")
		(sheetfile "usb-pd.kicad_sch")
		(attr smd)
		(fp_line
			(start -0.3 0.7)
			(end 0.3 0.7)
			(stroke
				(width 0.15)
				(type solid)
			)
			(layer "F.SilkS")
		)
		(fp_line
			(start -0.3 -0.7)
			(end 0.3 -0.7)
			(stroke
				(width 0.15)
				(type solid)
			)
			(layer "F.SilkS")
		)
		(fp_rect
			(start 1.95 -0.9)
			(end -1.95 0.9)
			(stroke
				(width 0.05)
				(type default)
			)
			(fill no)
			(layer "F.CrtYd")
		)
		(fp_rect
			(start -0.95 -0.675)
			(end 0.95 0.675)
			(stroke
				(width 0.15)
				(type solid)
			)
			(fill no)
			(layer "F.Fab")
		)
		(fp_text user "License: Apache-2.0"
			(at -1.9 4.947 90)
			(layer "F.Fab")
			(effects
				(font
					(size 0.7 0.7)
					(thickness 0.15)
				)
				(justify right top)
			)
		)
		(fp_text user "Author: Antmicro"
			(at -1.9 5.947 90)
			(layer "F.Fab")
			(effects
				(font
					(size 0.7 0.7)
					(thickness 0.15)
				)
				(justify right top)
			)
		)
		(fp_text user "${REFERENCE}"
			(at 0 0 90)
			(layer "F.Fab")
			(effects
				(font
					(size 0.7 0.7)
					(thickness 0.15)
				)
				(justify right top)
			)
		)
		(pad "1" smd roundrect
			(at -1.1 0 270)
			(size 1.2 1.3)
			(layers "F.Cu" "F.Mask" "F.Paste")
			(roundrect_rratio 0.25)
			(net 66 "GND")
			(pintype "passive")
		)
		(pad "2" smd roundrect
			(at 1.1 0 270)
			(size 1.2 1.3)
			(layers "F.Cu" "F.Mask" "F.Paste")
			(roundrect_rratio 0.25)
			(net 187 "/USB-PD/12V_CONV")
			(pintype "passive")
		)
	)
	(footprint "antmicro-footprints:R_0402_1005Metric"
		(layer "F.Cu")
		(at 143.781981 50.8 -90)
		(descr "Resistor SMD 0402")
		(tags "resistor SMD 0402")
		(property "Reference" "R51"
			(at 0.95 0.381981 270)
			(layer "F.SilkS")
			(effects
				(font
					(size 0.7 0.7)
					(thickness 0.15)
				)
				(justify right top)
			)
		)
		(property "Value" "R_0R_0402"
			(at -1.011843 1.772046 90)
			(layer "F.Fab")
			(effects
				(font
					(size 0.7 0.7)
					(thickness 0.15)
				)
				(justify right top)
			)
		)
		(property "Datasheet" "https://industrial.panasonic.com/cdbs/www-data/pdf/RDA0000/AOA0000C301.pdf"
			(at 0 0 90)
			(layer "F.Fab")
			(hide yes)
			(effects
				(font
					(size 1.27 1.27)
					(thickness 0.15)
				)
			)
		)
		(property "Description" "SMD Chip Resistor, Jumper, 0 ohm, 100 mW, 0402 [1005 Metric], Thick Film, General Purpose"
			(at 0 0 90)
			(layer "F.Fab")
			(hide yes)
			(effects
				(font
					(size 1.27 1.27)
					(thickness 0.15)
				)
			)
		)
		(property "MPN" "ERJ2GE0R00X"
			(at 0 0 270)
			(unlocked yes)
			(layer "F.Fab")
			(hide yes)
			(effects
				(font
					(size 1 1)
					(thickness 0.15)
				)
			)
		)
		(property "Manufacturer" "Panasonic"
			(at 0 0 270)
			(unlocked yes)
			(layer "F.Fab")
			(hide yes)
			(effects
				(font
					(size 1 1)
					(thickness 0.15)
				)
			)
		)
		(property "License" "Apache-2.0"
			(at 0 0 270)
			(unlocked yes)
			(layer "F.Fab")
			(hide yes)
			(effects
				(font
					(size 1 1)
					(thickness 0.15)
				)
			)
		)
		(property "Author" "Antmicro"
			(at 0 0 270)
			(unlocked yes)
			(layer "F.Fab")
			(hide yes)
			(effects
				(font
					(size 1 1)
					(thickness 0.15)
				)
			)
		)
		(property "Val" "0R"
			(at 0 0 270)
			(unlocked yes)
			(layer "F.Fab")
			(hide yes)
			(effects
				(font
					(size 1 1)
					(thickness 0.15)
				)
			)
		)
		(property "Tolerance" ""
			(at 0 0 270)
			(unlocked yes)
			(layer "F.Fab")
			(hide yes)
			(effects
				(font
					(size 1 1)
					(thickness 0.15)
				)
			)
		)
		(property "Current" "1A"
			(at 0 0 270)
			(unlocked yes)
			(layer "F.Fab")
			(hide yes)
			(effects
				(font
					(size 1 1)
					(thickness 0.15)
				)
			)
		)
		(sheetname "/OCuLink/")
		(sheetfile "oculink.kicad_sch")
		(attr smd)
		(fp_rect
			(start -0.925 -0.47)
			(end 0.925 0.47)
			(stroke
				(width 0.05)
				(type default)
			)
			(fill no)
			(layer "F.CrtYd")
		)
		(fp_rect
			(start -0.5 -0.25)
			(end 0.5 0.25)
			(stroke
				(width 0.15)
				(type solid)
			)
			(fill no)
			(layer "F.Fab")
		)
		(fp_text user "${REFERENCE}"
			(at 0 0 90)
			(layer "F.Fab")
			(effects
				(font
					(size 0.7 0.7)
					(thickness 0.15)
				)
				(justify right top)
			)
		)
		(fp_text user "Author: Antmicro"
			(at -0.95 4.169 90)
			(layer "F.Fab")
			(effects
				(font
					(size 0.7 0.7)
					(thickness 0.15)
				)
				(justify right top)
			)
		)
		(fp_text user "License: Apache-2.0"
			(at -0.949999 5.169 90)
			(layer "F.Fab")
			(effects
				(font
					(size 0.7 0.7)
					(thickness 0.15)
				)
				(justify right top)
			)
		)
		(pad "1" smd roundrect
			(at -0.48 0 270)
			(size 0.59 0.64)
			(layers "F.Cu" "F.Mask" "F.Paste")
			(roundrect_rratio 0.25)
			(net 182 "/OCuLink/~{CPRSNTC}")
			(pintype "passive")
		)
		(pad "2" smd roundrect
			(at 0.48 0 270)
			(size 0.59 0.64)
			(layers "F.Cu" "F.Mask" "F.Paste")
			(roundrect_rratio 0.25)
			(net 99 "/OCuLink/~{CPRSNT}")
			(pintype "passive")
		)
	)
	(footprint "antmicro-footprints:R_0402_1005Metric"
		(layer "F.Cu")
		(at 141.660661 50.8 -90)
		(descr "Resistor SMD 0402")
		(tags "resistor SMD 0402")
		(property "Reference" "R2"
			(at 0.95 0.410661 270)
			(layer "F.SilkS")
			(effects
				(font
					(size 0.7 0.7)
					(thickness 0.15)
				)
				(justify right top)
			)
		)
		(property "Value" "R_0R_0402"
			(at -1.011843 1.772046 90)
			(layer "F.Fab")
			(effects
				(font
					(size 0.7 0.7)
					(thickness 0.15)
				)
				(justify right top)
			)
		)
		(property "Datasheet" "https://industrial.panasonic.com/cdbs/www-data/pdf/RDA0000/AOA0000C301.pdf"
			(at 0 0 90)
			(layer "F.Fab")
			(hide yes)
			(effects
				(font
					(size 1.27 1.27)
					(thickness 0.15)
				)
			)
		)
		(property "Description" "SMD Chip Resistor, Jumper, 0 ohm, 100 mW, 0402 [1005 Metric], Thick Film, General Purpose"
			(at 0 0 90)
			(layer "F.Fab")
			(hide yes)
			(effects
				(font
					(size 1.27 1.27)
					(thickness 0.15)
				)
			)
		)
		(property "MPN" "ERJ2GE0R00X"
			(at 0 0 270)
			(unlocked yes)
			(layer "F.Fab")
			(hide yes)
			(effects
				(font
					(size 1 1)
					(thickness 0.15)
				)
			)
		)
		(property "Manufacturer" "Panasonic"
			(at 0 0 270)
			(unlocked yes)
			(layer "F.Fab")
			(hide yes)
			(effects
				(font
					(size 1 1)
					(thickness 0.15)
				)
			)
		)
		(property "License" "Apache-2.0"
			(at 0 0 270)
			(unlocked yes)
			(layer "F.Fab")
			(hide yes)
			(effects
				(font
					(size 1 1)
					(thickness 0.15)
				)
			)
		)
		(property "Author" "Antmicro"
			(at 0 0 270)
			(unlocked yes)
			(layer "F.Fab")
			(hide yes)
			(effects
				(font
					(size 1 1)
					(thickness 0.15)
				)
			)
		)
		(property "Val" "0R"
			(at 0 0 270)
			(unlocked yes)
			(layer "F.Fab")
			(hide yes)
			(effects
				(font
					(size 1 1)
					(thickness 0.15)
				)
			)
		)
		(property "Tolerance" ""
			(at 0 0 270)
			(unlocked yes)
			(layer "F.Fab")
			(hide yes)
			(effects
				(font
					(size 1 1)
					(thickness 0.15)
				)
			)
		)
		(property "Current" "1A"
			(at 0 0 270)
			(unlocked yes)
			(layer "F.Fab")
			(hide yes)
			(effects
				(font
					(size 1 1)
					(thickness 0.15)
				)
			)
		)
		(sheetname "/OCuLink/")
		(sheetfile "oculink.kicad_sch")
		(attr smd dnp)
		(fp_rect
			(start -0.925 -0.47)
			(end 0.925 0.47)
			(stroke
				(width 0.05)
				(type default)
			)
			(fill no)
			(layer "F.CrtYd")
		)
		(fp_rect
			(start -0.5 -0.25)
			(end 0.5 0.25)
			(stroke
				(width 0.15)
				(type solid)
			)
			(fill no)
			(layer "F.Fab")
		)
		(fp_text user "Author: Antmicro"
			(at -0.95 4.169 90)
			(layer "F.Fab")
			(effects
				(font
					(size 0.7 0.7)
					(thickness 0.15)
				)
				(justify right top)
			)
		)
		(fp_text user "${REFERENCE}"
			(at 0 0 90)
			(layer "F.Fab")
			(effects
				(font
					(size 0.7 0.7)
					(thickness 0.15)
				)
				(justify right top)
			)
		)
		(fp_text user "License: Apache-2.0"
			(at -0.949999 5.169 90)
			(layer "F.Fab")
			(effects
				(font
					(size 0.7 0.7)
					(thickness 0.15)
				)
				(justify right top)
			)
		)
		(pad "1" smd roundrect
			(at -0.48 0 270)
			(size 0.59 0.64)
			(layers "F.Cu" "F.Mask" "F.Paste")
			(roundrect_rratio 0.25)
			(net 95 "/OCuLink/I2C0C_SDA")
			(pintype "passive")
		)
		(pad "2" smd roundrect
			(at 0.48 0 270)
			(size 0.59 0.64)
			(layers "F.Cu" "F.Mask" "F.Paste")
			(roundrect_rratio 0.25)
			(net 103 "/OCuLink/I2C0.SDA")
			(pintype "passive")
		)
	)
	(footprint "antmicro-footprints:R_0402_1005Metric"
		(layer "F.Cu")
		(at 148.152 92 180)
		(descr "Resistor SMD 0402")
		(tags "resistor SMD 0402")
		(property "Reference" "R31"
			(at -3.448 0.5 180)
			(layer "F.SilkS")
			(effects
				(font
					(size 0.7 0.7)
					(thickness 0.15)
				)
				(justify right top)
			)
		)
		(property "Value" "R_68k_0402"
			(at -1.011843 1.772046 0)
			(layer "F.Fab")
			(effects
				(font
					(size 0.7 0.7)
					(thickness 0.15)
				)
				(justify right top)
			)
		)
		(property "Datasheet" "https://www.bourns.com/docs/product-datasheets/cr.pdf"
			(at 0 0 0)
			(layer "F.Fab")
			(hide yes)
			(effects
				(font
					(size 1.27 1.27)
					(thickness 0.15)
				)
			)
		)
		(property "Description" "SMD Chip Resistor"
			(at 0 0 0)
			(layer "F.Fab")
			(hide yes)
			(effects
				(font
					(size 1.27 1.27)
					(thickness 0.15)
				)
			)
		)
		(property "MPN" "CR0402-FX-6802GLF"
			(at 0 0 180)
			(unlocked yes)
			(layer "F.Fab")
			(hide yes)
			(effects
				(font
					(size 1 1)
					(thickness 0.15)
				)
			)
		)
		(property "Manufacturer" "Bourns"
			(at 0 0 180)
			(unlocked yes)
			(layer "F.Fab")
			(hide yes)
			(effects
				(font
					(size 1 1)
					(thickness 0.15)
				)
			)
		)
		(property "License" "Apache-2.0"
			(at 0 0 180)
			(unlocked yes)
			(layer "F.Fab")
			(hide yes)
			(effects
				(font
					(size 1 1)
					(thickness 0.15)
				)
			)
		)
		(property "Author" "Antmicro"
			(at 0 0 180)
			(unlocked yes)
			(layer "F.Fab")
			(hide yes)
			(effects
				(font
					(size 1 1)
					(thickness 0.15)
				)
			)
		)
		(property "Val" "68k"
			(at 0 0 180)
			(unlocked yes)
			(layer "F.Fab")
			(hide yes)
			(effects
				(font
					(size 1 1)
					(thickness 0.15)
				)
			)
		)
		(property "Tolerance" "1%"
			(at 0 0 180)
			(unlocked yes)
			(layer "F.Fab")
			(hide yes)
			(effects
				(font
					(size 1 1)
					(thickness 0.15)
				)
			)
		)
		(sheetname "/USB-PD/")
		(sheetfile "usb-pd.kicad_sch")
		(attr smd exclude_from_bom dnp)
		(fp_rect
			(start -0.925 -0.47)
			(end 0.925 0.47)
			(stroke
				(width 0.05)
				(type default)
			)
			(fill no)
			(layer "F.CrtYd")
		)
		(fp_rect
			(start -0.5 -0.25)
			(end 0.5 0.25)
			(stroke
				(width 0.15)
				(type solid)
			)
			(fill no)
			(layer "F.Fab")
		)
		(fp_text user "License: Apache-2.0"
			(at -0.949999 5.169 0)
			(layer "F.Fab")
			(effects
				(font
					(size 0.7 0.7)
					(thickness 0.15)
				)
				(justify right top)
			)
		)
		(fp_text user "${REFERENCE}"
			(at 0 0 0)
			(layer "F.Fab")
			(effects
				(font
					(size 0.7 0.7)
					(thickness 0.15)
				)
				(justify right top)
			)
		)
		(fp_text user "Author: Antmicro"
			(at -0.95 4.169 0)
			(layer "F.Fab")
			(effects
				(font
					(size 0.7 0.7)
					(thickness 0.15)
				)
				(justify right top)
			)
		)
		(pad "1" smd roundrect
			(at -0.48 0 180)
			(size 0.59 0.64)
			(layers "F.Cu" "F.Mask" "F.Paste")
			(roundrect_rratio 0.25)
			(net 66 "GND")
			(pintype "passive")
		)
		(pad "2" smd roundrect
			(at 0.48 0 180)
			(size 0.59 0.64)
			(layers "F.Cu" "F.Mask" "F.Paste")
			(roundrect_rratio 0.25)
			(net 155 "/USB-PD/12V_ILIM")
			(pintype "passive")
		)
	)
	(footprint "antmicro-footprints:C_0402_1005Metric"
		(layer "F.Cu")
		(at 122.8 138.6 -90)
		(descr "Capacitor SMD 0402")
		(tags "capacitor SMD 0402")
		(property "Reference" "C5"
			(at 1 0.4 90)
			(layer "F.SilkS")
			(effects
				(font
					(size 0.7 0.7)
					(thickness 0.15)
				)
				(justify right top)
			)
		)
		(property "Value" "C_1u_25V_0402"
			(at -1.022927 2.155213 90)
			(layer "F.Fab")
			(effects
				(font
					(size 0.7 0.7)
					(thickness 0.15)
				)
				(justify right top)
			)
		)
		(property "Datasheet" "https://www.murata.com/products/productdetail?partno=GRM155R61E105KE11%23"
			(at 0 0 90)
			(layer "F.Fab")
			(hide yes)
			(effects
				(font
					(size 1.27 1.27)
					(thickness 0.15)
				)
			)
		)
		(property "Description" "SMD Multilayer Ceramic Capacitor, 1 µF, 25 V, 0402 [1005 Metric], ± 10%, X5R, GRM Series"
			(at 0 0 90)
			(layer "F.Fab")
			(hide yes)
			(effects
				(font
					(size 1.27 1.27)
					(thickness 0.15)
				)
			)
		)
		(property "MPN" "GRM155R61E105KE11J"
			(at 0 0 270)
			(unlocked yes)
			(layer "F.Fab")
			(hide yes)
			(effects
				(font
					(size 1 1)
					(thickness 0.15)
				)
			)
		)
		(property "Manufacturer" "Murata"
			(at 0 0 270)
			(unlocked yes)
			(layer "F.Fab")
			(hide yes)
			(effects
				(font
					(size 1 1)
					(thickness 0.15)
				)
			)
		)
		(property "License" "Apache-2.0"
			(at 0 0 270)
			(unlocked yes)
			(layer "F.Fab")
			(hide yes)
			(effects
				(font
					(size 1 1)
					(thickness 0.15)
				)
			)
		)
		(property "Author" "Antmicro"
			(at 0 0 270)
			(unlocked yes)
			(layer "F.Fab")
			(hide yes)
			(effects
				(font
					(size 1 1)
					(thickness 0.15)
				)
			)
		)
		(property "Val" "1u"
			(at 0 0 270)
			(unlocked yes)
			(layer "F.Fab")
			(hide yes)
			(effects
				(font
					(size 1 1)
					(thickness 0.15)
				)
			)
		)
		(property "Voltage" "25V"
			(at 0 0 270)
			(unlocked yes)
			(layer "F.Fab")
			(hide yes)
			(effects
				(font
					(size 1 1)
					(thickness 0.15)
				)
			)
		)
		(property "Dielectric" "X5R"
			(at 0 0 270)
			(unlocked yes)
			(layer "F.Fab")
			(hide yes)
			(effects
				(font
					(size 1 1)
					(thickness 0.15)
				)
			)
		)
		(sheetname "/Power/")
		(sheetfile "power.kicad_sch")
		(attr smd)
		(fp_rect
			(start -0.925 -0.47)
			(end 0.925 0.47)
			(stroke
				(width 0.05)
				(type default)
			)
			(fill no)
			(layer "F.CrtYd")
		)
		(fp_line
			(start -0.494 0.248)
			(end -0.494 -0.25)
			(stroke
				(width 0.15)
				(type solid)
			)
			(layer "F.Fab")
		)
		(fp_line
			(start 0.504 0.248)
			(end -0.494 0.248)
			(stroke
				(width 0.15)
				(type solid)
			)
			(layer "F.Fab")
		)
		(fp_line
			(start -0.494 -0.25)
			(end 0.504 -0.25)
			(stroke
				(width 0.15)
				(type solid)
			)
			(layer "F.Fab")
		)
		(fp_line
			(start 0.504 -0.25)
			(end 0.504 0.248)
			(stroke
				(width 0.15)
				(type solid)
			)
			(layer "F.Fab")
		)
		(fp_text user "${REFERENCE}"
			(at 0 0 90)
			(layer "F.Fab")
			(effects
				(font
					(size 0.7 0.7)
					(thickness 0.15)
				)
				(justify right top)
			)
		)
		(fp_text user "Author: Antmicro"
			(at -0.939 3.399 90)
			(layer "F.Fab")
			(effects
				(font
					(size 0.7 0.7)
					(thickness 0.15)
				)
				(justify right top)
			)
		)
		(fp_text user "License: Apache-2.0"
			(at -0.939 5.799 90)
			(layer "F.Fab")
			(effects
				(font
					(size 0.7 0.7)
					(thickness 0.15)
				)
				(justify right top)
			)
		)
		(pad "1" smd roundrect
			(at -0.48 0 270)
			(size 0.59 0.64)
			(layers "F.Cu" "F.Mask" "F.Paste")
			(roundrect_rratio 0.25)
			(net 66 "GND")
			(pintype "passive")
		)
		(pad "2" smd roundrect
			(at 0.48 0 270)
			(size 0.59 0.64)
			(layers "F.Cu" "F.Mask" "F.Paste")
			(roundrect_rratio 0.25)
			(net 186 "/Power/3V3_CONV")
			(pintype "passive")
		)
	)
	(footprint "antmicro-footprints:SOT-23-3"
		(layer "F.Cu")
		(at 121.125 147.604999 90)
		(property "Reference" "Q2"
			(at 1.004999 0.675 0)
			(layer "F.SilkS")
			(effects
				(font
					(size 0.7 0.7)
					(thickness 0.15)
				)
				(justify left bottom)
			)
		)
		(property "Value" "BSS138-7-F"
			(at -1.9 2.7 90)
			(layer "F.Fab")
			(effects
				(font
					(size 0.7 0.7)
					(thickness 0.15)
				)
				(justify left bottom)
			)
		)
		(property "Datasheet" "https://www.diodes.com/assets/Datasheets/ds30144.pdf"
			(at 0 0 90)
			(layer "F.Fab")
			(hide yes)
			(effects
				(font
					(size 1.27 1.27)
					(thickness 0.15)
				)
			)
		)
		(property "Description" "Power MOSFET, N Channel, 50 V, 200 mA, 1.4 ohm, SOT-23, Surface Mount"
			(at 0 0 90)
			(layer "F.Fab")
			(hide yes)
			(effects
				(font
					(size 1.27 1.27)
					(thickness 0.15)
				)
			)
		)
		(property "MPN" "BSS138-7-F"
			(at 0 0 90)
			(unlocked yes)
			(layer "F.Fab")
			(hide yes)
			(effects
				(font
					(size 1 1)
					(thickness 0.15)
				)
			)
		)
		(property "Manufacturer" "Diodes Incorporated"
			(at 0 0 90)
			(unlocked yes)
			(layer "F.Fab")
			(hide yes)
			(effects
				(font
					(size 1 1)
					(thickness 0.15)
				)
			)
		)
		(property "Author" "Antmicro"
			(at 0 0 90)
			(unlocked yes)
			(layer "F.Fab")
			(hide yes)
			(effects
				(font
					(size 1 1)
					(thickness 0.15)
				)
			)
		)
		(property "License" "Apache-2.0"
			(at 0 0 90)
			(unlocked yes)
			(layer "F.Fab")
			(hide yes)
			(effects
				(font
					(size 1 1)
					(thickness 0.15)
				)
			)
		)
		(sheetname "/Power/")
		(sheetfile "power.kicad_sch")
		(attr smd)
		(fp_line
			(start 0.7 -1.5)
			(end -0.7 -1.5)
			(stroke
				(width 0.15)
				(type solid)
			)
			(layer "F.SilkS")
		)
		(fp_line
			(start -0.85 -1.35)
			(end -0.7 -1.5)
			(stroke
				(width 0.15)
				(type solid)
			)
			(layer "F.SilkS")
		)
		(fp_line
			(start -1.45 -1.35)
			(end -0.85 -1.35)
			(stroke
				(width 0.15)
				(type solid)
			)
			(layer "F.SilkS")
		)
		(fp_line
			(start 0.7 -0.4)
			(end 0.7 -1.5)
			(stroke
				(width 0.15)
				(type solid)
			)
			(layer "F.SilkS")
		)
		(fp_line
			(start 0.7 0.4)
			(end 0.7 1.5)
			(stroke
				(width 0.15)
				(type solid)
			)
			(layer "F.SilkS")
		)
		(fp_line
			(start 0.7 1.5)
			(end -0.7 1.5)
			(stroke
				(width 0.15)
				(type solid)
			)
			(layer "F.SilkS")
		)
		(fp_line
			(start -0.7 1.5)
			(end -0.7 1.35)
			(stroke
				(width 0.15)
				(type solid)
			)
			(layer "F.SilkS")
		)
		(fp_line
			(start 0.825 -1.6)
			(end 0.825 -0.45)
			(stroke
				(width 0.05)
				(type solid)
			)
			(layer "F.CrtYd")
		)
		(fp_line
			(start -0.9 -1.6)
			(end 0.825 -1.6)
			(stroke
				(width 0.05)
				(type solid)
			)
			(layer "F.CrtYd")
		)
		(fp_line
			(start -0.9 -1.6)
			(end -0.9 -1.4)
			(stroke
				(width 0.05)
				(type solid)
			)
			(layer "F.CrtYd")
		)
		(fp_line
			(start -0.9 -1.4)
			(end -1.75 -1.4)
			(stroke
				(width 0.05)
				(type solid)
			)
			(layer "F.CrtYd")
		)
		(fp_line
			(start -0.85 -0.5)
			(end -1.75 -0.5)
			(stroke
				(width 0.05)
				(type solid)
			)
			(layer "F.CrtYd")
		)
		(fp_line
			(start -1.75 -0.5)
			(end -1.75 -1.4)
			(stroke
				(width 0.05)
				(type solid)
			)
			(layer "F.CrtYd")
		)
		(fp_line
			(start 1.75 -0.45)
			(end 1.75 0.45)
			(stroke
				(width 0.05)
				(type solid)
			)
			(layer "F.CrtYd")
		)
		(fp_line
			(start 0.825 -0.45)
			(end 1.75 -0.45)
			(stroke
				(width 0.05)
				(type solid)
			)
			(layer "F.CrtYd")
		)
		(fp_line
			(start 1.75 0.45)
			(end 0.85 0.45)
			(stroke
				(width 0.05)
				(type solid)
			)
			(layer "F.CrtYd")
		)
		(fp_line
			(start 0.85 0.45)
			(end 0.85 1.65)
			(stroke
				(width 0.05)
				(type solid)
			)
			(layer "F.CrtYd")
		)
		(fp_line
			(start -0.85 0.5)
			(end -0.85 -0.5)
			(stroke
				(width 0.05)
				(type solid)
			)
			(layer "F.CrtYd")
		)
		(fp_line
			(start -1.75 0.5)
			(end -0.85 0.5)
			(stroke
				(width 0.05)
				(type solid)
			)
			(layer "F.CrtYd")
		)
		(fp_line
			(start -0.85 1.4)
			(end -1.75 1.4)
			(stroke
				(width 0.05)
				(type solid)
			)
			(layer "F.CrtYd")
		)
		(fp_line
			(start -1.75 1.4)
			(end -1.75 0.5)
			(stroke
				(width 0.05)
				(type solid)
			)
			(layer "F.CrtYd")
		)
		(fp_line
			(start 0.85 1.65)
			(end -0.85 1.65)
			(stroke
				(width 0.05)
				(type solid)
			)
			(layer "F.CrtYd")
		)
		(fp_line
			(start -0.85 1.65)
			(end -0.85 1.4)
			(stroke
				(width 0.05)
				(type solid)
			)
			(layer "F.CrtYd")
		)
		(fp_line
			(start -0.437 -1.526)
			(end 0.688 -1.526)
			(stroke
				(width 0.15)
				(type solid)
			)
			(layer "F.Fab")
		)
		(fp_line
			(start -0.437 -1.526)
			(end -0.712 -1.325)
			(stroke
				(width 0.15)
				(type solid)
			)
			(layer "F.Fab")
		)
		(fp_line
			(start -0.712 -1.325)
			(end -0.712 1.523)
			(stroke
				(width 0.15)
				(type solid)
			)
			(layer "F.Fab")
		)
		(fp_line
			(start 0.688 1.519)
			(end 0.688 -1.52)
			(stroke
				(width 0.15)
				(type solid)
			)
			(layer "F.Fab")
		)
		(fp_line
			(start -0.712 1.519)
			(end 0.688 1.519)
			(stroke
				(width 0.15)
				(type solid)
			)
			(layer "F.Fab")
		)
		(fp_text user "License: Apache-2.0"
			(at -1.8 6.8 90)
			(layer "F.Fab")
			(effects
				(font
					(size 0.7 0.7)
					(thickness 0.15)
				)
				(justify left bottom)
			)
		)
		(fp_text user "${REFERENCE}"
			(at 0.000001 0.025 90)
			(layer "F.Fab")
			(effects
				(font
					(size 0.7 0.7)
					(thickness 0.15)
				)
				(justify left bottom)
			)
		)
		(fp_text user "Author: Antmicro"
			(at -1.837 5.3 90)
			(layer "F.Fab")
			(effects
				(font
					(size 0.7 0.7)
					(thickness 0.15)
				)
				(justify left bottom)
			)
		)
		(pad "1" smd roundrect
			(at -1.1 -0.951 90)
			(size 1 0.6)
			(layers "F.Cu" "F.Mask" "F.Paste")
			(roundrect_rratio 0.15)
			(net 105 "/Power/3V3_PG")
			(pinfunction "G")
			(pintype "input")
		)
		(pad "2" smd roundrect
			(at -1.1 0.949 90)
			(size 1 0.6)
			(layers "F.Cu" "F.Mask" "F.Paste")
			(roundrect_rratio 0.15)
			(net 66 "GND")
			(pinfunction "S")
			(pintype "passive")
		)
		(pad "3" smd roundrect
			(at 1.1 -0.0005 90)
			(size 1 0.6)
			(layers "F.Cu" "F.Mask" "F.Paste")
			(roundrect_rratio 0.15)
			(net 99 "/OCuLink/~{CPRSNT}")
			(pinfunction "D")
			(pintype "passive")
		)
	)
	(footprint "antmicro-footprints:Amphenol_G14A421211112HR"
		(locked yes)
		(layer "F.Cu")
		(at 127.05 36 180)
		(property "Reference" "J1"
			(at -6.35 -6.2 180)
			(layer "F.SilkS")
			(effects
				(font
					(size 0.7 0.7)
					(thickness 0.15)
				)
				(justify left bottom)
			)
		)
		(property "Value" "OCuLink_x4_Amphenol_G14A421211112HR_CUSTOM_device_side"
			(at 0 6.385 180)
			(unlocked yes)
			(layer "F.Fab")
			(effects
				(font
					(size 0.7 0.7)
					(thickness 0.15)
				)
				(justify left bottom)
			)
		)
		(property "Datasheet" "https://cdn.amphenol-cs.com/media/wysiwyg/files/drawing/g14a421x1bxxxhr.pdf"
			(at 0 0 0)
			(layer "F.Fab")
			(hide yes)
			(effects
				(font
					(size 1.27 1.27)
					(thickness 0.15)
				)
			)
		)
		(property "Description" "I/O Connectors OCulink, Receptacle, 0.5mm pitch, 4X, R/A SMT with shell leg SMT type, 30U\" gold plating, LCP, black, T&R packing"
			(at 0 0 0)
			(layer "F.Fab")
			(hide yes)
			(effects
				(font
					(size 1.27 1.27)
					(thickness 0.15)
				)
			)
		)
		(property "Manufacturer" "Amphenol"
			(at 0 0 180)
			(unlocked yes)
			(layer "F.Fab")
			(hide yes)
			(effects
				(font
					(size 1 1)
					(thickness 0.15)
				)
			)
		)
		(property "MPN" "G14A421211112HR"
			(at 0 0 180)
			(unlocked yes)
			(layer "F.Fab")
			(hide yes)
			(effects
				(font
					(size 1 1)
					(thickness 0.15)
				)
			)
		)
		(property "Author" "Antmicro"
			(at 0 0 180)
			(unlocked yes)
			(layer "F.Fab")
			(hide yes)
			(effects
				(font
					(size 1 1)
					(thickness 0.15)
				)
			)
		)
		(property "License" "Apache-2.0"
			(at 0 0 180)
			(unlocked yes)
			(layer "F.Fab")
			(hide yes)
			(effects
				(font
					(size 1 1)
					(thickness 0.15)
				)
			)
		)
		(sheetname "/OCuLink/")
		(sheetfile "oculink.kicad_sch")
		(solder_paste_margin -0.06)
		(attr smd)
		(fp_line
			(start 6.8 -3)
			(end 6.8 -0.4)
			(stroke
				(width 0.1)
				(type default)
			)
			(layer "F.SilkS")
		)
		(fp_line
			(start -6.8 -0.4)
			(end -6.8 -3)
			(stroke
				(width 0.1)
				(type default)
			)
			(layer "F.SilkS")
		)
		(fp_circle
			(center -5.3 -5.52)
			(end -5.25 -5.52)
			(stroke
				(width 0.15)
				(type solid)
			)
			(fill yes)
			(layer "F.SilkS")
		)
		(fp_rect
			(start -8.22 -5.22)
			(end 8.22 4.94)
			(stroke
				(width 0.05)
				(type solid)
			)
			(fill no)
			(layer "F.CrtYd")
		)
		(fp_line
			(start 7 3.065)
			(end -7 3.065)
			(stroke
				(width 0.1)
				(type default)
			)
			(layer "F.Fab")
		)
		(fp_text user "Author: Antmicro"
			(at -8.22 11.085 0)
			(layer "F.Fab")
			(effects
				(font
					(size 0.7 0.7)
					(thickness 0.15)
				)
				(justify right top)
			)
		)
		(fp_text user "License: Apache-2.0"
			(at -8.22 12.285 0)
			(layer "F.Fab")
			(effects
				(font
					(size 0.7 0.7)
					(thickness 0.15)
				)
				(justify right top)
			)
		)
		(fp_text user "PCB EDGE"
			(at 2.8 2.95 180)
			(unlocked yes)
			(layer "F.Fab")
			(effects
				(font
					(size 0.5 0.5)
					(thickness 0.125)
				)
				(justify left bottom)
			)
		)
		(fp_text user "${REFERENCE}"
			(at 0 -0.34 180)
			(layer "F.Fab")
			(effects
				(font
					(size 0.7 0.7)
					(thickness 0.15)
				)
				(justify left bottom)
			)
		)
		(pad "" np_thru_hole circle
			(at -5.42 -1.395 270)
			(size 1 1)
			(drill 1)
			(layers "F&B.Cu" "*.Mask")
		)
		(pad "" np_thru_hole circle
			(at 5.95 -1.395 270)
			(size 1 1)
			(drill 1)
			(layers "F&B.Cu" "*.Mask")
		)
		(pad "A1" smd roundrect
			(at -4.75 -2.115 270)
			(size 0.91 0.31)
			(layers "F.Cu" "F.Mask" "F.Paste")
			(roundrect_rratio 0.5)
			(net 92 "unconnected-(J1-V_{ACT}_RX_3V3-PadA1)")
			(pinfunction "V_{ACT}_RX_3V3")
			(pintype "power_in+no_connect")
		)
		(pad "A2" smd roundrect
			(at -4.25 -2.115 270)
			(size 0.91 0.31)
			(layers "F.Cu" "F.Mask" "F.Paste")
			(roundrect_rratio 0.5)
			(net 66 "GND")
			(pinfunction "GND")
			(pintype "passive")
		)
		(pad "A3" smd roundrect
			(at -3.75 -2.115 270)
			(size 0.91 0.31)
			(layers "F.Cu" "F.Mask" "F.Paste")
			(roundrect_rratio 0.5)
			(net 72 "/OCuLink/PCIe_{x4}.TX0+")
			(pinfunction "PER0+")
			(pintype "output")
		)
		(pad "A4" smd roundrect
			(at -3.25 -2.115 270)
			(size 0.91 0.31)
			(layers "F.Cu" "F.Mask" "F.Paste")
			(roundrect_rratio 0.5)
			(net 74 "/OCuLink/PCIe_{x4}.TX0-")
			(pinfunction "PER0-")
			(pintype "output")
		)
		(pad "A5" smd roundrect
			(at -2.75 -2.115 270)
			(size 0.91 0.31)
			(layers "F.Cu" "F.Mask" "F.Paste")
			(roundrect_rratio 0.5)
			(net 66 "GND")
			(pinfunction "GND")
			(pintype "passive")
		)
		(pad "A6" smd roundrect
			(at -2.25 -2.115 270)
			(size 0.91 0.31)
			(layers "F.Cu" "F.Mask" "F.Paste")
			(roundrect_rratio 0.5)
			(net 77 "/OCuLink/PCIe_{x4}.TX1+")
			(pinfunction "PER1+")
			(pintype "output")
		)
		(pad "A7" smd roundrect
			(at -1.75 -2.115 270)
			(size 0.91 0.31)
			(layers "F.Cu" "F.Mask" "F.Paste")
			(roundrect_rratio 0.5)
			(net 69 "/OCuLink/PCIe_{x4}.TX1-")
			(pinfunction "PER1-")
			(pintype "output")
		)
		(pad "A8" smd roundrect
			(at -1.25 -2.115 270)
			(size 0.91 0.31)
			(layers "F.Cu" "F.Mask" "F.Paste")
			(roundrect_rratio 0.5)
			(net 66 "GND")
			(pinfunction "GND")
			(pintype "passive")
		)
		(pad "A9" smd roundrect
			(at -0.75 -2.115 270)
			(size 0.91 0.31)
			(layers "F.Cu" "F.Mask" "F.Paste")
			(roundrect_rratio 0.5)
			(net 101 "/OCuLink/I2C0C_SCL")
			(pinfunction "SCL")
			(pintype "bidirectional")
		)
		(pad "A10" smd roundrect
			(at -0.25 -2.115 270)
			(size 0.91 0.31)
			(layers "F.Cu" "F.Mask" "F.Paste")
			(roundrect_rratio 0.5)
			(net 95 "/OCuLink/I2C0C_SDA")
			(pinfunction "SDA")
			(pintype "bidirectional")
		)
		(pad "A11" smd roundrect
			(at 0.25 -2.115 270)
			(size 0.91 0.31)
			(layers "F.Cu" "F.Mask" "F.Paste")
			(roundrect_rratio 0.5)
			(net 66 "GND")
			(pinfunction "GND")
			(pintype "passive")
		)
		(pad "A12" smd roundrect
			(at 0.75 -2.115 270)
			(size 0.91 0.31)
			(layers "F.Cu" "F.Mask" "F.Paste")
			(roundrect_rratio 0.5)
			(net 183 "/OCuLink/~{PERSTC}")
			(pinfunction "~{PERST}")
			(pintype "bidirectional")
		)
		(pad "A13" smd roundrect
			(at 1.25 -2.115 270)
			(size 0.91 0.31)
			(layers "F.Cu" "F.Mask" "F.Paste")
			(roundrect_rratio 0.5)
			(net 182 "/OCuLink/~{CPRSNTC}")
			(pinfunction "~{CPRSNT}")
			(pintype "bidirectional")
		)
		(pad "A14" smd roundrect
			(at 1.75 -2.115 270)
			(size 0.91 0.31)
			(layers "F.Cu" "F.Mask" "F.Paste")
			(roundrect_rratio 0.5)
			(net 66 "GND")
			(pinfunction "GND")
			(pintype "passive")
		)
		(pad "A15" smd roundrect
			(at 2.25 -2.115 270)
			(size 0.91 0.31)
			(layers "F.Cu" "F.Mask" "F.Paste")
			(roundrect_rratio 0.5)
			(net 70 "/OCuLink/PCIe_{x4}.TX2+")
			(pinfunction "PER2+")
			(pintype "output")
		)
		(pad "A16" smd roundrect
			(at 2.75 -2.115 270)
			(size 0.91 0.31)
			(layers "F.Cu" "F.Mask" "F.Paste")
			(roundrect_rratio 0.5)
			(net 76 "/OCuLink/PCIe_{x4}.TX2-")
			(pinfunction "PER2-")
			(pintype "output")
		)
		(pad "A17" smd roundrect
			(at 3.25 -2.115 270)
			(size 0.91 0.31)
			(layers "F.Cu" "F.Mask" "F.Paste")
			(roundrect_rratio 0.5)
			(net 66 "GND")
			(pinfunction "GND")
			(pintype "passive")
		)
		(pad "A18" smd roundrect
			(at 3.75 -2.115 270)
			(size 0.91 0.31)
			(layers "F.Cu" "F.Mask" "F.Paste")
			(roundrect_rratio 0.5)
			(net 82 "/OCuLink/PCIe_{x4}.TX3+")
			(pinfunction "PER3+")
			(pintype "output")
		)
		(pad "A19" smd roundrect
			(at 4.25 -2.115 270)
			(size 0.91 0.31)
			(layers "F.Cu" "F.Mask" "F.Paste")
			(roundrect_rratio 0.5)
			(net 80 "/OCuLink/PCIe_{x4}.TX3-")
			(pinfunction "PER3-")
			(pintype "output")
		)
		(pad "A20" smd roundrect
			(at 4.75 -2.115 270)
			(size 0.91 0.31)
			(layers "F.Cu" "F.Mask" "F.Paste")
			(roundrect_rratio 0.5)
			(net 66 "GND")
			(pinfunction "GND")
			(pintype "passive")
		)
		(pad "A21" smd roundrect
			(at 5.25 -2.115 270)
			(size 0.91 0.31)
			(layers "F.Cu" "F.Mask" "F.Paste")
			(roundrect_rratio 0.5)
			(net 100 "unconnected-(J1-5V-PadA21)_1")
			(pinfunction "5V")
			(pintype "passive+no_connect")
		)
		(pad "B1" smd roundrect
			(at -5.25 -4.305 270)
			(size 0.91 0.31)
			(layers "F.Cu" "F.Mask" "F.Paste")
			(roundrect_rratio 0.5)
			(net 98 "unconnected-(J1-5V-PadA21)")
			(pinfunction "5V")
			(pintype "passive+no_connect")
		)
		(pad "B2" smd roundrect
			(at -4.75 -4.305 270)
			(size 0.91 0.31)
			(layers "F.Cu" "F.Mask" "F.Paste")
			(roundrect_rratio 0.5)
			(net 66 "GND")
			(pinfunction "GND")
			(pintype "passive")
		)
		(pad "B3" smd roundrect
			(at -4.25 -4.305 270)
			(size 0.91 0.31)
			(layers "F.Cu" "F.Mask" "F.Paste")
			(roundrect_rratio 0.5)
			(net 78 "/OCuLink/PCIe_{x4}.RX0+")
			(pinfunction "PET0+")
			(pintype "input")
		)
		(pad "B4" smd roundrect
			(at -3.75 -4.305 270)
			(size 0.91 0.31)
			(layers "F.Cu" "F.Mask" "F.Paste")
			(roundrect_rratio 0.5)
			(net 73 "/OCuLink/PCIe_{x4}.RX0-")
			(pinfunction "PET0-")
			(pintype "input")
		)
		(pad "B5" smd roundrect
			(at -3.25 -4.305 270)
			(size 0.91 0.31)
			(layers "F.Cu" "F.Mask" "F.Paste")
			(roundrect_rratio 0.5)
			(net 66 "GND")
			(pinfunction "GND")
			(pintype "passive")
		)
		(pad "B6" smd roundrect
			(at -2.75 -4.305 270)
			(size 0.91 0.31)
			(layers "F.Cu" "F.Mask" "F.Paste")
			(roundrect_rratio 0.5)
			(net 75 "/OCuLink/PCIe_{x4}.RX1+")
			(pinfunction "PET1+")
			(pintype "input")
		)
		(pad "B7" smd roundrect
			(at -2.25 -4.305 270)
			(size 0.91 0.31)
			(layers "F.Cu" "F.Mask" "F.Paste")
			(roundrect_rratio 0.5)
			(net 71 "/OCuLink/PCIe_{x4}.RX1-")
			(pinfunction "PET1-")
			(pintype "input")
		)
		(pad "B8" smd roundrect
			(at -1.75 -4.305 270)
			(size 0.91 0.31)
			(layers "F.Cu" "F.Mask" "F.Paste")
			(roundrect_rratio 0.5)
			(net 66 "GND")
			(pinfunction "GND")
			(pintype "passive")
		)
		(pad "B9" smd roundrect
			(at -1.25 -4.305 270)
			(size 0.91 0.31)
			(layers "F.Cu" "F.Mask" "F.Paste")
			(roundrect_rratio 0.5)
			(net 112 "unconnected-(J1-NC-PadB9)")
			(pinfunction "NC")
			(pintype "no_connect")
		)
		(pad "B10" smd roundrect
			(at -0.75 -4.305 270)
			(size 0.91 0.31)
			(layers "F.Cu" "F.Mask" "F.Paste")
			(roundrect_rratio 0.5)
			(net 184 "/OCuLink/~{WAKEC}")
			(pinfunction "~{CWAKE}")
			(pintype "bidirectional")
		)
		(pad "B11" smd roundrect
			(at -0.25 -4.305 270)
			(size 0.91 0.31)
			(layers "F.Cu" "F.Mask" "F.Paste")
			(roundrect_rratio 0.5)
			(net 66 "GND")
			(pinfunction "GND")
			(pintype "passive")
		)
		(pad "B12" smd roundrect
			(at 0.25 -4.305 270)
			(size 0.91 0.31)
			(layers "F.Cu" "F.Mask" "F.Paste")
			(roundrect_rratio 0.5)
			(net 170 "/OCuLink/PCIe_{REF0}_R.CK+")
			(pinfunction "VSP1")
			(pintype "bidirectional")
		)
		(pad "B13" smd roundrect
			(at 0.75 -4.305 270)
			(size 0.91 0.31)
			(layers "F.Cu" "F.Mask" "F.Paste")
			(roundrect_rratio 0.5)
			(net 171 "/OCuLink/PCIe_{REF0}_R.CK-")
			(pinfunction "VSP2")
			(pintype "bidirectional")
		)
		(pad "B14" smd roundrect
			(at 1.25 -4.305 270)
			(size 0.91 0.31)
			(layers "F.Cu" "F.Mask" "F.Paste")
			(roundrect_rratio 0.5)
			(net 66 "GND")
			(pinfunction "GND")
			(pintype "passive")
		)
		(pad "B15" smd roundrect
			(at 1.75 -4.305 270)
			(size 0.91 0.31)
			(layers "F.Cu" "F.Mask" "F.Paste")
			(roundrect_rratio 0.5)
			(net 81 "/OCuLink/PCIe_{x4}.RX2+")
			(pinfunction "PET2+")
			(pintype "input")
		)
		(pad "B16" smd roundrect
			(at 2.25 -4.305 270)
			(size 0.91 0.31)
			(layers "F.Cu" "F.Mask" "F.Paste")
			(roundrect_rratio 0.5)
			(net 79 "/OCuLink/PCIe_{x4}.RX2-")
			(pinfunction "PET2-")
			(pintype "input")
		)
		(pad "B17" smd roundrect
			(at 2.75 -4.305 270)
			(size 0.91 0.31)
			(layers "F.Cu" "F.Mask" "F.Paste")
			(roundrect_rratio 0.5)
			(net 66 "GND")
			(pinfunction "GND")
			(pintype "passive")
		)
		(pad "B18" smd roundrect
			(at 3.25 -4.305 270)
			(size 0.91 0.31)
			(layers "F.Cu" "F.Mask" "F.Paste")
			(roundrect_rratio 0.5)
			(net 68 "/OCuLink/PCIe_{x4}.RX3+")
			(pinfunction "PET3+")
			(pintype "input")
		)
		(pad "B19" smd roundrect
			(at 3.75 -4.305 270)
			(size 0.91 0.31)
			(layers "F.Cu" "F.Mask" "F.Paste")
			(roundrect_rratio 0.5)
			(net 67 "/OCuLink/PCIe_{x4}.RX3-")
			(pinfunction "PET3-")
			(pintype "input")
		)
		(pad "B20" smd roundrect
			(at 4.25 -4.305 270)
			(size 0.91 0.31)
			(layers "F.Cu" "F.Mask" "F.Paste")
			(roundrect_rratio 0.5)
			(net 66 "GND")
			(pinfunction "GND")
			(pintype "passive")
		)
		(pad "B21" smd roundrect
			(at 4.75 -4.305 270)
			(size 0.91 0.31)
			(layers "F.Cu" "F.Mask" "F.Paste")
			(roundrect_rratio 0.5)
			(net 94 "unconnected-(J1-V_{ACT}_TX_3V3-PadB21)")
			(pinfunction "V_{ACT}_TX_3V3")
			(pintype "power_in+no_connect")
		)
		(pad "SH" smd roundrect
			(at -6.91 -3.915 270)
			(size 1.38 1.81)
			(layers "F.Cu" "F.Mask" "F.Paste")
			(roundrect_rratio 0.1)
			(net 66 "GND")
			(pinfunction "SH")
			(pintype "passive")
		)
		(pad "SH" smd roundrect
			(at -6.91 0.805 270)
			(size 1.81 1.8)
			(layers "F.Cu" "F.Mask" "F.Paste")
			(roundrect_rratio 0.1)
			(net 66 "GND")
			(pinfunction "SH")
			(pintype "passive")
		)
		(pad "SH" smd roundrect
			(at 6.91 -3.915 270)
			(size 1.38 1.81)
			(layers "F.Cu" "F.Mask" "F.Paste")
			(roundrect_rratio 0.1)
			(net 66 "GND")
			(pinfunction "SH")
			(pintype "passive")
		)
		(pad "SH" smd roundrect
			(at 6.91 0.805 270)
			(size 1.81 1.8)
			(layers "F.Cu" "F.Mask" "F.Paste")
			(roundrect_rratio 0.1)
			(net 66 "GND")
			(pinfunction "SH")
			(pintype "passive")
		)
	)
	(footprint "antmicro-footprints:R_0402_1005Metric"
		(layer "F.Cu")
		(at 148.151999 89)
		(descr "Resistor SMD 0402")
		(tags "resistor SMD 0402")
		(property "Reference" "R23"
			(at 1.248001 0.3 180)
			(layer "F.SilkS")
			(effects
				(font
					(size 0.7 0.7)
					(thickness 0.15)
				)
				(justify left bottom)
			)
		)
		(property "Value" "R_2k_0402"
			(at -1.011843 1.772046 0)
			(layer "F.Fab")
			(effects
				(font
					(size 0.7 0.7)
					(thickness 0.15)
				)
				(justify left bottom)
			)
		)
		(property "Datasheet" "https://www.bourns.com/docs/product-datasheets/cr.pdf"
			(at 0 0 0)
			(layer "F.Fab")
			(hide yes)
			(effects
				(font
					(size 1.27 1.27)
					(thickness 0.15)
				)
			)
		)
		(property "Description" "SMD Chip Resistor, 2 kohm, ± 1%, 62.5 mW, 0402 [1005 Metric], Thick Film, General Purpose"
			(at 0 0 0)
			(layer "F.Fab")
			(hide yes)
			(effects
				(font
					(size 1.27 1.27)
					(thickness 0.15)
				)
			)
		)
		(property "Manufacturer" "Bourns"
			(at 0 0 0)
			(unlocked yes)
			(layer "F.Fab")
			(hide yes)
			(effects
				(font
					(size 1 1)
					(thickness 0.15)
				)
			)
		)
		(property "MPN" "CR0402-FX-2001GLF"
			(at 0 0 0)
			(unlocked yes)
			(layer "F.Fab")
			(hide yes)
			(effects
				(font
					(size 1 1)
					(thickness 0.15)
				)
			)
		)
		(property "Val" "2k"
			(at 0 0 0)
			(unlocked yes)
			(layer "F.Fab")
			(hide yes)
			(effects
				(font
					(size 1 1)
					(thickness 0.15)
				)
			)
		)
		(property "License" "Apache-2.0"
			(at 0 0 0)
			(unlocked yes)
			(layer "F.Fab")
			(hide yes)
			(effects
				(font
					(size 1 1)
					(thickness 0.15)
				)
			)
		)
		(property "Author" "Antmicro"
			(at 0 0 0)
			(unlocked yes)
			(layer "F.Fab")
			(hide yes)
			(effects
				(font
					(size 1 1)
					(thickness 0.15)
				)
			)
		)
		(property "Tolerance" "1%"
			(at 0 0 0)
			(unlocked yes)
			(layer "F.Fab")
			(hide yes)
			(effects
				(font
					(size 1 1)
					(thickness 0.15)
				)
			)
		)
		(sheetname "/USB-PD/")
		(sheetfile "usb-pd.kicad_sch")
		(attr smd)
		(fp_rect
			(start -0.925 -0.47)
			(end 0.925 0.47)
			(stroke
				(width 0.05)
				(type default)
			)
			(fill no)
			(layer "F.CrtYd")
		)
		(fp_rect
			(start -0.5 -0.25)
			(end 0.5 0.25)
			(stroke
				(width 0.15)
				(type solid)
			)
			(fill no)
			(layer "F.Fab")
		)
		(fp_text user "${REFERENCE}"
			(at 0 0 0)
			(layer "F.Fab")
			(effects
				(font
					(size 0.7 0.7)
					(thickness 0.15)
				)
				(justify left bottom)
			)
		)
		(fp_text user "License: Apache-2.0"
			(at -0.949999 5.169 0)
			(layer "F.Fab")
			(effects
				(font
					(size 0.7 0.7)
					(thickness 0.15)
				)
				(justify left bottom)
			)
		)
		(fp_text user "Author: Antmicro"
			(at -0.95 4.169 0)
			(layer "F.Fab")
			(effects
				(font
					(size 0.7 0.7)
					(thickness 0.15)
				)
				(justify left bottom)
			)
		)
		(pad "1" smd roundrect
			(at -0.48 0)
			(size 0.59 0.64)
			(layers "F.Cu" "F.Mask" "F.Paste")
			(roundrect_rratio 0.25)
			(net 153 "/USB-PD/12V_MODE")
			(pintype "passive")
		)
		(pad "2" smd roundrect
			(at 0.48 0)
			(size 0.59 0.64)
			(layers "F.Cu" "F.Mask" "F.Paste")
			(roundrect_rratio 0.25)
			(net 66 "GND")
			(pintype "passive")
		)
	)
	(footprint "antmicro-footprints:C_0805_2012Metric"
		(layer "F.Cu")
		(at 130.9 131.05 -90)
		(descr "Capacitor SMD 0805")
		(tags "capacitor SMD 0805")
		(property "Reference" "C2"
			(at -4.45 0.4 90)
			(layer "F.SilkS")
			(effects
				(font
					(size 0.7 0.7)
					(thickness 0.15)
				)
				(justify right top)
			)
		)
		(property "Value" "C_22u_25V_0805"
			(at -2.055717 1.963153 90)
			(layer "F.Fab")
			(effects
				(font
					(size 0.7 0.7)
					(thickness 0.15)
				)
				(justify right top)
			)
		)
		(property "Datasheet" "https://product.samsungsem.com/mlcc/CL21A226MAYNNN.do"
			(at 0 0 90)
			(layer "F.Fab")
			(hide yes)
			(effects
				(font
					(size 1.27 1.27)
					(thickness 0.15)
				)
			)
		)
		(property "Description" "SMT Multilayer Ceramic Capacitor, 22uF, +/-20%, 25V, X5R, 0805 [2012 Metric]"
			(at 0 0 90)
			(layer "F.Fab")
			(hide yes)
			(effects
				(font
					(size 1.27 1.27)
					(thickness 0.15)
				)
			)
		)
		(property "MPN" "CL21A226MAYNNNE"
			(at 0 0 270)
			(unlocked yes)
			(layer "F.Fab")
			(hide yes)
			(effects
				(font
					(size 1 1)
					(thickness 0.15)
				)
			)
		)
		(property "Manufacturer" "Samsung Electro-Mechanics"
			(at 0 0 270)
			(unlocked yes)
			(layer "F.Fab")
			(hide yes)
			(effects
				(font
					(size 1 1)
					(thickness 0.15)
				)
			)
		)
		(property "License" "Apache-2.0"
			(at 0 0 270)
			(unlocked yes)
			(layer "F.Fab")
			(hide yes)
			(effects
				(font
					(size 1 1)
					(thickness 0.15)
				)
			)
		)
		(property "Author" "Antmicro"
			(at 0 0 270)
			(unlocked yes)
			(layer "F.Fab")
			(hide yes)
			(effects
				(font
					(size 1 1)
					(thickness 0.15)
				)
			)
		)
		(property "Val" "22u"
			(at 0 0 270)
			(unlocked yes)
			(layer "F.Fab")
			(hide yes)
			(effects
				(font
					(size 1 1)
					(thickness 0.15)
				)
			)
		)
		(property "Voltage" "25V"
			(at 0 0 270)
			(unlocked yes)
			(layer "F.Fab")
			(hide yes)
			(effects
				(font
					(size 1 1)
					(thickness 0.15)
				)
			)
		)
		(property "Dielectric" "X5R"
			(at 0 0 270)
			(unlocked yes)
			(layer "F.Fab")
			(hide yes)
			(effects
				(font
					(size 1 1)
					(thickness 0.15)
				)
			)
		)
		(property "Public" "False"
			(at 0 0 270)
			(unlocked yes)
			(layer "F.Fab")
			(hide yes)
			(effects
				(font
					(size 1 1)
					(thickness 0.15)
				)
			)
		)
		(sheetname "/Power/")
		(sheetfile "power.kicad_sch")
		(attr smd)
		(fp_line
			(start -0.3 0.7)
			(end 0.3 0.7)
			(stroke
				(width 0.15)
				(type solid)
			)
			(layer "F.SilkS")
		)
		(fp_line
			(start -0.3 -0.7)
			(end 0.3 -0.7)
			(stroke
				(width 0.15)
				(type solid)
			)
			(layer "F.SilkS")
		)
		(fp_rect
			(start 1.95 -0.9)
			(end -1.95 0.9)
			(stroke
				(width 0.05)
				(type default)
			)
			(fill no)
			(layer "F.CrtYd")
		)
		(fp_rect
			(start -0.95 -0.675)
			(end 0.95 0.675)
			(stroke
				(width 0.15)
				(type solid)
			)
			(fill no)
			(layer "F.Fab")
		)
		(fp_text user "Author: Antmicro"
			(at -1.9 5.947 90)
			(layer "F.Fab")
			(effects
				(font
					(size 0.7 0.7)
					(thickness 0.15)
				)
				(justify right top)
			)
		)
		(fp_text user "${REFERENCE}"
			(at -1.899999 3.947 90)
			(layer "F.Fab")
			(effects
				(font
					(size 0.7 0.7)
					(thickness 0.15)
				)
				(justify right top)
			)
		)
		(fp_text user "License: Apache-2.0"
			(at -1.9 4.947 90)
			(layer "F.Fab")
			(effects
				(font
					(size 0.7 0.7)
					(thickness 0.15)
				)
				(justify right top)
			)
		)
		(pad "1" smd roundrect
			(at -1.1 0 270)
			(size 1.2 1.3)
			(layers "F.Cu" "F.Mask" "F.Paste")
			(roundrect_rratio 0.25)
			(net 66 "GND")
			(pintype "passive")
		)
		(pad "2" smd roundrect
			(at 1.1 0 270)
			(size 1.2 1.3)
			(layers "F.Cu" "F.Mask" "F.Paste")
			(roundrect_rratio 0.25)
			(net 87 "+12V")
			(pintype "passive")
		)
	)
	(footprint "antmicro-footprints:R_0402_1005Metric"
		(layer "F.Cu")
		(at 121.2245 150.154999 180)
		(descr "Resistor SMD 0402")
		(tags "resistor SMD 0402")
		(property "Reference" "R15"
			(at 3.2245 -0.445001 180)
			(layer "F.SilkS")
			(effects
				(font
					(size 0.7 0.7)
					(thickness 0.15)
				)
				(justify left bottom)
			)
		)
		(property "Value" "R_100k_0402"
			(at -1.011843 1.772046 0)
			(layer "F.Fab")
			(effects
				(font
					(size 0.7 0.7)
					(thickness 0.15)
				)
				(justify right top)
			)
		)
		(property "Datasheet" "https://www.bourns.com/docs/product-datasheets/cr.pdf"
			(at 0 0 0)
			(layer "F.Fab")
			(hide yes)
			(effects
				(font
					(size 1.27 1.27)
					(thickness 0.15)
				)
			)
		)
		(property "Description" "SMD Chip Resistor, 100 kohm, ± 1%, 62.5 mW, 0402 [1005 Metric], Thick Film, General Purpose"
			(at 0 0 0)
			(layer "F.Fab")
			(hide yes)
			(effects
				(font
					(size 1.27 1.27)
					(thickness 0.15)
				)
			)
		)
		(property "MPN" "CR0402-FX-1003GLF"
			(at 0 0 180)
			(unlocked yes)
			(layer "F.Fab")
			(hide yes)
			(effects
				(font
					(size 1 1)
					(thickness 0.15)
				)
			)
		)
		(property "Manufacturer" "Bourns"
			(at 0 0 180)
			(unlocked yes)
			(layer "F.Fab")
			(hide yes)
			(effects
				(font
					(size 1 1)
					(thickness 0.15)
				)
			)
		)
		(property "License" "Apache-2.0"
			(at 0 0 180)
			(unlocked yes)
			(layer "F.Fab")
			(hide yes)
			(effects
				(font
					(size 1 1)
					(thickness 0.15)
				)
			)
		)
		(property "Author" "Antmicro"
			(at 0 0 180)
			(unlocked yes)
			(layer "F.Fab")
			(hide yes)
			(effects
				(font
					(size 1 1)
					(thickness 0.15)
				)
			)
		)
		(property "Val" "100k"
			(at 0 0 180)
			(unlocked yes)
			(layer "F.Fab")
			(hide yes)
			(effects
				(font
					(size 1 1)
					(thickness 0.15)
				)
			)
		)
		(property "Tolerance" "1%"
			(at 0 0 180)
			(unlocked yes)
			(layer "F.Fab")
			(hide yes)
			(effects
				(font
					(size 1 1)
					(thickness 0.15)
				)
			)
		)
		(sheetname "/Power/")
		(sheetfile "power.kicad_sch")
		(attr smd)
		(fp_rect
			(start -0.925 -0.47)
			(end 0.925 0.47)
			(stroke
				(width 0.05)
				(type default)
			)
			(fill no)
			(layer "F.CrtYd")
		)
		(fp_rect
			(start -0.5 -0.25)
			(end 0.5 0.25)
			(stroke
				(width 0.15)
				(type solid)
			)
			(fill no)
			(layer "F.Fab")
		)
		(fp_text user "License: Apache-2.0"
			(at -0.949999 5.169 0)
			(layer "F.Fab")
			(effects
				(font
					(size 0.7 0.7)
					(thickness 0.15)
				)
				(justify right top)
			)
		)
		(fp_text user "${REFERENCE}"
			(at 0 0 180)
			(layer "F.Fab")
			(effects
				(font
					(size 0.7 0.7)
					(thickness 0.15)
				)
				(justify left bottom)
			)
		)
		(fp_text user "Author: Antmicro"
			(at -0.95 4.169 0)
			(layer "F.Fab")
			(effects
				(font
					(size 0.7 0.7)
					(thickness 0.15)
				)
				(justify right top)
			)
		)
		(pad "1" smd roundrect
			(at -0.48 0 180)
			(size 0.59 0.64)
			(layers "F.Cu" "F.Mask" "F.Paste")
			(roundrect_rratio 0.25)
			(net 66 "GND")
			(pintype "passive")
		)
		(pad "2" smd roundrect
			(at 0.48 0 180)
			(size 0.59 0.64)
			(layers "F.Cu" "F.Mask" "F.Paste")
			(roundrect_rratio 0.25)
			(net 105 "/Power/3V3_PG")
			(pintype "passive")
		)
	)
	(footprint "antmicro-footprints:R_0402_1005Metric"
		(layer "F.Cu")
		(at 131.72 152.999999)
		(descr "Resistor SMD 0402")
		(tags "resistor SMD 0402")
		(property "Reference" "R14"
			(at 1.08 0.500001 180)
			(layer "F.SilkS")
			(effects
				(font
					(size 0.7 0.7)
					(thickness 0.15)
				)
				(justify left bottom)
			)
		)
		(property "Value" "R_1k_0402"
			(at -1.011843 1.772046 0)
			(layer "F.Fab")
			(effects
				(font
					(size 0.7 0.7)
					(thickness 0.15)
				)
				(justify left bottom)
			)
		)
		(property "Datasheet" "https://www.bourns.com/docs/product-datasheets/cr.pdf"
			(at 0 0 0)
			(layer "F.Fab")
			(hide yes)
			(effects
				(font
					(size 1.27 1.27)
					(thickness 0.15)
				)
			)
		)
		(property "Description" "SMD Chip Resistor, 1 kohm, ± 1%, 63 mW, 0402 [1005 Metric], Thick Film, General Purpose"
			(at 0 0 0)
			(layer "F.Fab")
			(hide yes)
			(effects
				(font
					(size 1.27 1.27)
					(thickness 0.15)
				)
			)
		)
		(property "MPN" "CR0402-FX-1001GLF"
			(at 0 0 0)
			(unlocked yes)
			(layer "F.Fab")
			(hide yes)
			(effects
				(font
					(size 1 1)
					(thickness 0.15)
				)
			)
		)
		(property "Manufacturer" "Bourns"
			(at 0 0 0)
			(unlocked yes)
			(layer "F.Fab")
			(hide yes)
			(effects
				(font
					(size 1 1)
					(thickness 0.15)
				)
			)
		)
		(property "License" "Apache-2.0"
			(at 0 0 0)
			(unlocked yes)
			(layer "F.Fab")
			(hide yes)
			(effects
				(font
					(size 1 1)
					(thickness 0.15)
				)
			)
		)
		(property "Author" "Antmicro"
			(at 0 0 0)
			(unlocked yes)
			(layer "F.Fab")
			(hide yes)
			(effects
				(font
					(size 1 1)
					(thickness 0.15)
				)
			)
		)
		(property "Val" "1k"
			(at 0 0 0)
			(unlocked yes)
			(layer "F.Fab")
			(hide yes)
			(effects
				(font
					(size 1 1)
					(thickness 0.15)
				)
			)
		)
		(property "Tolerance" "1%"
			(at 0 0 0)
			(unlocked yes)
			(layer "F.Fab")
			(hide yes)
			(effects
				(font
					(size 1 1)
					(thickness 0.15)
				)
			)
		)
		(sheetname "/Power/")
		(sheetfile "power.kicad_sch")
		(attr smd)
		(fp_rect
			(start -0.925 -0.47)
			(end 0.925 0.47)
			(stroke
				(width 0.05)
				(type default)
			)
			(fill no)
			(layer "F.CrtYd")
		)
		(fp_rect
			(start -0.5 -0.25)
			(end 0.5 0.25)
			(stroke
				(width 0.15)
				(type solid)
			)
			(fill no)
			(layer "F.Fab")
		)
		(fp_text user "License: Apache-2.0"
			(at -0.949999 5.169 0)
			(layer "F.Fab")
			(effects
				(font
					(size 0.7 0.7)
					(thickness 0.15)
				)
				(justify left bottom)
			)
		)
		(fp_text user "${REFERENCE}"
			(at 0 0 0)
			(layer "F.Fab")
			(effects
				(font
					(size 0.7 0.7)
					(thickness 0.15)
				)
				(justify left bottom)
			)
		)
		(fp_text user "Author: Antmicro"
			(at -0.95 4.169 0)
			(layer "F.Fab")
			(effects
				(font
					(size 0.7 0.7)
					(thickness 0.15)
				)
				(justify left bottom)
			)
		)
		(pad "1" smd roundrect
			(at -0.48 0)
			(size 0.59 0.64)
			(layers "F.Cu" "F.Mask" "F.Paste")
			(roundrect_rratio 0.25)
			(net 66 "GND")
			(pintype "passive")
		)
		(pad "2" smd roundrect
			(at 0.48 0)
			(size 0.59 0.64)
			(layers "F.Cu" "F.Mask" "F.Paste")
			(roundrect_rratio 0.25)
			(net 91 "Net-(D3-C)")
			(pintype "passive")
		)
	)
	(footprint "antmicro-footprints:C_Pol_Vishay-T59-EE"
		(layer "F.Cu")
		(at 127.9 116 180)
		(property "Reference" "C30"
			(at -4.9 -0.4 180)
			(layer "F.SilkS")
			(effects
				(font
					(size 0.7 0.7)
					(thickness 0.15)
				)
				(justify left bottom)
			)
		)
		(property "Value" "C_Pol_150u_30V_Vishay-T59-EE"
			(at -5.08 5.08 180)
			(unlocked yes)
			(layer "F.Fab")
			(effects
				(font
					(size 0.7 0.7)
					(thickness 0.15)
				)
				(justify left bottom)
			)
		)
		(property "Datasheet" "https://www.vishay.com/docs/40191/t59.pdf"
			(at 0 0 0)
			(layer "F.Fab")
			(hide yes)
			(effects
				(font
					(size 1.27 1.27)
					(thickness 0.15)
				)
			)
		)
		(property "Description" "Tantalum Capacitors - Polymer 150uF 30volts 20% 75mohms maxESR"
			(at 0 0 0)
			(layer "F.Fab")
			(hide yes)
			(effects
				(font
					(size 1.27 1.27)
					(thickness 0.15)
				)
			)
		)
		(property "MPN" "T59EE157M030C0075"
			(at 0 0 180)
			(unlocked yes)
			(layer "F.Fab")
			(hide yes)
			(effects
				(font
					(size 1 1)
					(thickness 0.15)
				)
			)
		)
		(property "Manufacturer" "Vishay"
			(at 0 0 180)
			(unlocked yes)
			(layer "F.Fab")
			(hide yes)
			(effects
				(font
					(size 1 1)
					(thickness 0.15)
				)
			)
		)
		(property "Voltage" "30V"
			(at 0 0 180)
			(unlocked yes)
			(layer "F.Fab")
			(hide yes)
			(effects
				(font
					(size 1 1)
					(thickness 0.15)
				)
			)
		)
		(property "Val" "150u"
			(at 0 0 180)
			(unlocked yes)
			(layer "F.Fab")
			(hide yes)
			(effects
				(font
					(size 1 1)
					(thickness 0.15)
				)
			)
		)
		(property "Author" "Antmicro"
			(at 0 0 180)
			(unlocked yes)
			(layer "F.Fab")
			(hide yes)
			(effects
				(font
					(size 1 1)
					(thickness 0.15)
				)
			)
		)
		(property "License" "Apache-2.0"
			(at 0 0 180)
			(unlocked yes)
			(layer "F.Fab")
			(hide yes)
			(effects
				(font
					(size 1 1)
					(thickness 0.15)
				)
			)
		)
		(property "Dielectric" "template_dielectric"
			(at 0 0 180)
			(unlocked yes)
			(layer "F.Fab")
			(hide yes)
			(effects
				(font
					(size 1 1)
					(thickness 0.15)
				)
			)
		)
		(sheetname "/Power/")
		(sheetfile "power.kicad_sch")
		(attr smd)
		(fp_line
			(start -2 2.25)
			(end 2 2.25)
			(stroke
				(width 0.15)
				(type solid)
			)
			(layer "F.SilkS")
		)
		(fp_line
			(start -2 -2.25)
			(end 2 -2.25)
			(stroke
				(width 0.15)
				(type solid)
			)
			(layer "F.SilkS")
		)
		(fp_line
			(start -3.5 -2.8)
			(end -3.5 -3.2)
			(stroke
				(width 0.15)
				(type solid)
			)
			(layer "F.SilkS")
		)
		(fp_line
			(start -3.7 -3)
			(end -3.3 -3)
			(stroke
				(width 0.15)
				(type solid)
			)
			(layer "F.SilkS")
		)
		(fp_rect
			(start -4.9 -2.9)
			(end 4.9 2.9)
			(stroke
				(width 0.05)
				(type solid)
			)
			(fill no)
			(layer "F.CrtYd")
		)
		(fp_rect
			(start -3.75 -2.25)
			(end 3.75 2.25)
			(stroke
				(width 0.15)
				(type solid)
			)
			(fill no)
			(layer "F.Fab")
		)
		(fp_text user "Author: Antmicro"
			(at -5.079999 7.08 0)
			(layer "F.Fab")
			(effects
				(font
					(size 0.7 0.7)
					(thickness 0.15)
				)
				(justify right top)
			)
		)
		(fp_text user "License: Apache-2.0"
			(at -5.08 9.48 0)
			(layer "F.Fab")
			(effects
				(font
					(size 0.7 0.7)
					(thickness 0.15)
				)
				(justify right top)
			)
		)
		(fp_text user "${REFERENCE}"
			(at 0 -0.175 180)
			(layer "F.Fab")
			(effects
				(font
					(size 0.7 0.7)
					(thickness 0.15)
				)
				(justify left bottom)
			)
		)
		(pad "1" smd trapezoid
			(at -3.4 0 180)
			(size 2.5 5.3)
			(layers "F.Cu" "F.Mask" "F.Paste")
			(net 87 "+12V")
			(pintype "passive")
		)
		(pad "2" smd trapezoid
			(at 3.4 0 180)
			(size 2.5 5.3)
			(layers "F.Cu" "F.Mask" "F.Paste")
			(net 66 "GND")
			(pintype "passive")
		)
	)
	(footprint "antmicro-footprints:C_0805_2012Metric"
		(layer "F.Cu")
		(at 134.5 93.5 -90)
		(descr "Capacitor SMD 0805")
		(tags "capacitor SMD 0805")
		(property "Reference" "C18"
			(at -2.5 3.9 90)
			(layer "F.SilkS")
			(effects
				(font
					(size 0.7 0.7)
					(thickness 0.15)
				)
				(justify right top)
			)
		)
		(property "Value" "C_22u_25V_0805"
			(at -2.055717 1.963153 90)
			(layer "F.Fab")
			(effects
				(font
					(size 0.7 0.7)
					(thickness 0.15)
				)
				(justify right top)
			)
		)
		(property "Datasheet" "https://product.samsungsem.com/mlcc/CL21A226MAYNNN.do"
			(at 0 0 90)
			(layer "F.Fab")
			(hide yes)
			(effects
				(font
					(size 1.27 1.27)
					(thickness 0.15)
				)
			)
		)
		(property "Description" "SMT Multilayer Ceramic Capacitor, 22uF, +/-20%, 25V, X5R, 0805 [2012 Metric]"
			(at 0 0 90)
			(layer "F.Fab")
			(hide yes)
			(effects
				(font
					(size 1.27 1.27)
					(thickness 0.15)
				)
			)
		)
		(property "MPN" "CL21A226MAYNNNE"
			(at 0 0 270)
			(unlocked yes)
			(layer "F.Fab")
			(hide yes)
			(effects
				(font
					(size 1 1)
					(thickness 0.15)
				)
			)
		)
		(property "Manufacturer" "Samsung Electro-Mechanics"
			(at 0 0 270)
			(unlocked yes)
			(layer "F.Fab")
			(hide yes)
			(effects
				(font
					(size 1 1)
					(thickness 0.15)
				)
			)
		)
		(property "License" "Apache-2.0"
			(at 0 0 270)
			(unlocked yes)
			(layer "F.Fab")
			(hide yes)
			(effects
				(font
					(size 1 1)
					(thickness 0.15)
				)
			)
		)
		(property "Author" "Antmicro"
			(at 0 0 270)
			(unlocked yes)
			(layer "F.Fab")
			(hide yes)
			(effects
				(font
					(size 1 1)
					(thickness 0.15)
				)
			)
		)
		(property "Val" "22u"
			(at 0 0 270)
			(unlocked yes)
			(layer "F.Fab")
			(hide yes)
			(effects
				(font
					(size 1 1)
					(thickness 0.15)
				)
			)
		)
		(property "Voltage" "25V"
			(at 0 0 270)
			(unlocked yes)
			(layer "F.Fab")
			(hide yes)
			(effects
				(font
					(size 1 1)
					(thickness 0.15)
				)
			)
		)
		(property "Dielectric" "X5R"
			(at 0 0 270)
			(unlocked yes)
			(layer "F.Fab")
			(hide yes)
			(effects
				(font
					(size 1 1)
					(thickness 0.15)
				)
			)
		)
		(property "Public" "False"
			(at 0 0 270)
			(unlocked yes)
			(layer "F.Fab")
			(hide yes)
			(effects
				(font
					(size 1 1)
					(thickness 0.15)
				)
			)
		)
		(sheetname "/USB-PD/")
		(sheetfile "usb-pd.kicad_sch")
		(attr smd)
		(fp_line
			(start -0.3 0.7)
			(end 0.3 0.7)
			(stroke
				(width 0.15)
				(type solid)
			)
			(layer "F.SilkS")
		)
		(fp_line
			(start -0.3 -0.7)
			(end 0.3 -0.7)
			(stroke
				(width 0.15)
				(type solid)
			)
			(layer "F.SilkS")
		)
		(fp_rect
			(start 1.95 -0.9)
			(end -1.95 0.9)
			(stroke
				(width 0.05)
				(type default)
			)
			(fill no)
			(layer "F.CrtYd")
		)
		(fp_rect
			(start -0.95 -0.675)
			(end 0.95 0.675)
			(stroke
				(width 0.15)
				(type solid)
			)
			(fill no)
			(layer "F.Fab")
		)
		(fp_text user "${REFERENCE}"
			(at 0 0 90)
			(layer "F.Fab")
			(effects
				(font
					(size 0.7 0.7)
					(thickness 0.15)
				)
				(justify right top)
			)
		)
		(fp_text user "Author: Antmicro"
			(at -1.9 5.947 90)
			(layer "F.Fab")
			(effects
				(font
					(size 0.7 0.7)
					(thickness 0.15)
				)
				(justify right top)
			)
		)
		(fp_text user "License: Apache-2.0"
			(at -1.9 4.947 90)
			(layer "F.Fab")
			(effects
				(font
					(size 0.7 0.7)
					(thickness 0.15)
				)
				(justify right top)
			)
		)
		(pad "1" smd roundrect
			(at -1.1 0 270)
			(size 1.2 1.3)
			(layers "F.Cu" "F.Mask" "F.Paste")
			(roundrect_rratio 0.25)
			(net 66 "GND")
			(pintype "passive")
		)
		(pad "2" smd roundrect
			(at 1.1 0 270)
			(size 1.2 1.3)
			(layers "F.Cu" "F.Mask" "F.Paste")
			(roundrect_rratio 0.25)
			(net 187 "/USB-PD/12V_CONV")
			(pintype "passive")
		)
	)
	(footprint "antmicro-footprints:R_0402_1005Metric"
		(layer "F.Cu")
		(at 119.55 48.2 90)
		(descr "Resistor SMD 0402")
		(tags "resistor SMD 0402")
		(property "Reference" "R43"
			(at -3.2 0.45 90)
			(layer "F.SilkS")
			(effects
				(font
					(size 0.7 0.7)
					(thickness 0.15)
				)
				(justify left bottom)
			)
		)
		(property "Value" "R_0R_0402"
			(at -1.011843 1.772046 90)
			(layer "F.Fab")
			(effects
				(font
					(size 0.7 0.7)
					(thickness 0.15)
				)
				(justify left bottom)
			)
		)
		(property "Datasheet" "https://industrial.panasonic.com/cdbs/www-data/pdf/RDA0000/AOA0000C301.pdf"
			(at 0 0 90)
			(layer "F.Fab")
			(hide yes)
			(effects
				(font
					(size 1.27 1.27)
					(thickness 0.15)
				)
			)
		)
		(property "Description" "SMD Chip Resistor, Jumper, 0 ohm, 100 mW, 0402 [1005 Metric], Thick Film, General Purpose"
			(at 0 0 90)
			(layer "F.Fab")
			(hide yes)
			(effects
				(font
					(size 1.27 1.27)
					(thickness 0.15)
				)
			)
		)
		(property "MPN" "ERJ2GE0R00X"
			(at 0 0 90)
			(unlocked yes)
			(layer "F.Fab")
			(hide yes)
			(effects
				(font
					(size 1 1)
					(thickness 0.15)
				)
			)
		)
		(property "Manufacturer" "Panasonic"
			(at 0 0 90)
			(unlocked yes)
			(layer "F.Fab")
			(hide yes)
			(effects
				(font
					(size 1 1)
					(thickness 0.15)
				)
			)
		)
		(property "License" "Apache-2.0"
			(at 0 0 90)
			(unlocked yes)
			(layer "F.Fab")
			(hide yes)
			(effects
				(font
					(size 1 1)
					(thickness 0.15)
				)
			)
		)
		(property "Author" "Antmicro"
			(at 0 0 90)
			(unlocked yes)
			(layer "F.Fab")
			(hide yes)
			(effects
				(font
					(size 1 1)
					(thickness 0.15)
				)
			)
		)
		(property "Val" "0R"
			(at 0 0 90)
			(unlocked yes)
			(layer "F.Fab")
			(hide yes)
			(effects
				(font
					(size 1 1)
					(thickness 0.15)
				)
			)
		)
		(property "Tolerance" ""
			(at 0 0 90)
			(unlocked yes)
			(layer "F.Fab")
			(hide yes)
			(effects
				(font
					(size 1 1)
					(thickness 0.15)
				)
			)
		)
		(property "Current" "1A"
			(at 0 0 90)
			(unlocked yes)
			(layer "F.Fab")
			(hide yes)
			(effects
				(font
					(size 1 1)
					(thickness 0.15)
				)
			)
		)
		(sheetname "/PCIe-clock-generator/")
		(sheetfile "pcie-clock-generator.kicad_sch")
		(attr smd exclude_from_bom dnp)
		(fp_poly
			(pts
				(xy -0.925 -0.47) (xy 0.925 -0.47) (xy 0.925 0.47) (xy -0.925 0.47)
			)
			(stroke
				(width 0.05)
				(type default)
			)
			(fill no)
			(layer "F.CrtYd")
		)
		(fp_poly
			(pts
				(xy -0.5 -0.25) (xy 0.5 -0.25) (xy 0.5 0.25) (xy -0.5 0.25)
			)
			(stroke
				(width 0.15)
				(type solid)
			)
			(fill no)
			(layer "F.Fab")
		)
		(fp_text user "${REFERENCE}"
			(at -0.95 3.168 90)
			(layer "F.Fab")
			(effects
				(font
					(size 0.7 0.7)
					(thickness 0.15)
				)
				(justify left bottom)
			)
		)
		(fp_text user "License: Apache-2.0"
			(at -0.949999 5.169 90)
			(layer "F.Fab")
			(effects
				(font
					(size 0.7 0.7)
					(thickness 0.15)
				)
				(justify left bottom)
			)
		)
		(fp_text user "Author: Antmicro"
			(at -0.95 4.169 90)
			(layer "F.Fab")
			(effects
				(font
					(size 0.7 0.7)
					(thickness 0.15)
				)
				(justify left bottom)
			)
		)
		(pad "1" smd roundrect
			(at -0.48 0 90)
			(size 0.59 0.64)
			(layers "F.Cu" "F.Mask" "F.Paste")
			(roundrect_rratio 0.25)
			(net 178 "/PCIe-clock-generator/PCIe_{REF1}_R.CK+")
			(pintype "passive")
		)
		(pad "2" smd roundrect
			(at 0.48 0 90)
			(size 0.59 0.64)
			(layers "F.Cu" "F.Mask" "F.Paste")
			(roundrect_rratio 0.25)
			(net 96 "/OCuLink/PCIe_{REF0}.CK+")
			(pintype "passive")
		)
	)
	(footprint "antmicro-footprints:C_0805_2012Metric"
		(layer "F.Cu")
		(at 103.8 119.4 90)
		(descr "Capacitor SMD 0805")
		(tags "capacitor SMD 0805")
		(property "Reference" "C6"
			(at 0.2 -1 90)
			(layer "F.SilkS")
			(effects
				(font
					(size 0.7 0.7)
					(thickness 0.15)
				)
				(justify left bottom)
			)
		)
		(property "Value" "C_10u_0805_35V"
			(at -2.055717 1.963153 90)
			(layer "F.Fab")
			(effects
				(font
					(size 0.7 0.7)
					(thickness 0.15)
				)
				(justify left bottom)
			)
		)
		(property "Datasheet" "https://www.murata.com/products/productdetail?partno=GRM21BR6YA106KE43%23"
			(at 0 0 90)
			(layer "F.Fab")
			(hide yes)
			(effects
				(font
					(size 1.27 1.27)
					(thickness 0.15)
				)
			)
		)
		(property "Description" "SMD Multilayer Ceramic Capacitor, 10 µF, 35 V, 0805 [2012 Metric], ± 10%, X5R, GRM Series"
			(at 0 0 90)
			(layer "F.Fab")
			(hide yes)
			(effects
				(font
					(size 1.27 1.27)
					(thickness 0.15)
				)
			)
		)
		(property "MPN" "GRM21BR6YA106KE43L"
			(at 0 0 90)
			(unlocked yes)
			(layer "F.Fab")
			(hide yes)
			(effects
				(font
					(size 1 1)
					(thickness 0.15)
				)
			)
		)
		(property "Manufacturer" "Murata"
			(at 0 0 90)
			(unlocked yes)
			(layer "F.Fab")
			(hide yes)
			(effects
				(font
					(size 1 1)
					(thickness 0.15)
				)
			)
		)
		(property "License" "Apache-2.0"
			(at 0 0 90)
			(unlocked yes)
			(layer "F.Fab")
			(hide yes)
			(effects
				(font
					(size 1 1)
					(thickness 0.15)
				)
			)
		)
		(property "Author" "Antmicro"
			(at 0 0 90)
			(unlocked yes)
			(layer "F.Fab")
			(hide yes)
			(effects
				(font
					(size 1 1)
					(thickness 0.15)
				)
			)
		)
		(property "Val" "10u"
			(at 0 0 90)
			(unlocked yes)
			(layer "F.Fab")
			(hide yes)
			(effects
				(font
					(size 1 1)
					(thickness 0.15)
				)
			)
		)
		(property "Voltage" "35V"
			(at 0 0 90)
			(unlocked yes)
			(layer "F.Fab")
			(hide yes)
			(effects
				(font
					(size 1 1)
					(thickness 0.15)
				)
			)
		)
		(property "Dielectric" ""
			(at 0 0 90)
			(unlocked yes)
			(layer "F.Fab")
			(hide yes)
			(effects
				(font
					(size 1 1)
					(thickness 0.15)
				)
			)
		)
		(property "Public" "False"
			(at 0 0 90)
			(unlocked yes)
			(layer "F.Fab")
			(hide yes)
			(effects
				(font
					(size 1 1)
					(thickness 0.15)
				)
			)
		)
		(sheetname "/PCIe-connector/")
		(sheetfile "pcie-connector.kicad_sch")
		(attr smd)
		(fp_line
			(start -0.3 -0.7)
			(end 0.3 -0.7)
			(stroke
				(width 0.15)
				(type solid)
			)
			(layer "F.SilkS")
		)
		(fp_line
			(start -0.3 0.7)
			(end 0.3 0.7)
			(stroke
				(width 0.15)
				(type solid)
			)
			(layer "F.SilkS")
		)
		(fp_rect
			(start 1.95 -0.9)
			(end -1.95 0.9)
			(stroke
				(width 0.05)
				(type default)
			)
			(fill no)
			(layer "F.CrtYd")
		)
		(fp_rect
			(start -0.95 -0.675)
			(end 0.95 0.675)
			(stroke
				(width 0.15)
				(type solid)
			)
			(fill no)
			(layer "F.Fab")
		)
		(fp_text user "License: Apache-2.0"
			(at -1.9 4.947 90)
			(layer "F.Fab")
			(effects
				(font
					(size 0.7 0.7)
					(thickness 0.15)
				)
				(justify left bottom)
			)
		)
		(fp_text user "${REFERENCE}"
			(at 0 0 90)
			(layer "F.Fab")
			(effects
				(font
					(size 0.7 0.7)
					(thickness 0.15)
				)
				(justify left bottom)
			)
		)
		(fp_text user "Author: Antmicro"
			(at -1.9 5.947 90)
			(layer "F.Fab")
			(effects
				(font
					(size 0.7 0.7)
					(thickness 0.15)
				)
				(justify left bottom)
			)
		)
		(pad "1" smd roundrect
			(at -1.1 0 90)
			(size 1.2 1.3)
			(layers "F.Cu" "F.Mask" "F.Paste")
			(roundrect_rratio 0.25)
			(net 87 "+12V")
			(pintype "passive")
		)
		(pad "2" smd roundrect
			(at 1.1 0 90)
			(size 1.2 1.3)
			(layers "F.Cu" "F.Mask" "F.Paste")
			(roundrect_rratio 0.25)
			(net 66 "GND")
			(pintype "passive")
		)
	)
	(footprint "antmicro-footprints:R_0402_1005Metric"
		(layer "F.Cu")
		(at 128.332998 152.076999 -90)
		(descr "Resistor SMD 0402")
		(tags "resistor SMD 0402")
		(property "Reference" "R7"
			(at 0.923001 0.332998 270)
			(layer "F.SilkS")
			(effects
				(font
					(size 0.7 0.7)
					(thickness 0.15)
				)
				(justify right top)
			)
		)
		(property "Value" "R_100k_0402"
			(at -1.011843 1.772046 90)
			(layer "F.Fab")
			(effects
				(font
					(size 0.7 0.7)
					(thickness 0.15)
				)
				(justify right top)
			)
		)
		(property "Datasheet" "https://www.bourns.com/docs/product-datasheets/cr.pdf"
			(at 0 0 90)
			(layer "F.Fab")
			(hide yes)
			(effects
				(font
					(size 1.27 1.27)
					(thickness 0.15)
				)
			)
		)
		(property "Description" "SMD Chip Resistor, 100 kohm, ± 1%, 62.5 mW, 0402 [1005 Metric], Thick Film, General Purpose"
			(at 0 0 90)
			(layer "F.Fab")
			(hide yes)
			(effects
				(font
					(size 1.27 1.27)
					(thickness 0.15)
				)
			)
		)
		(property "MPN" "CR0402-FX-1003GLF"
			(at 0 0 270)
			(unlocked yes)
			(layer "F.Fab")
			(hide yes)
			(effects
				(font
					(size 1 1)
					(thickness 0.15)
				)
			)
		)
		(property "Manufacturer" "Bourns"
			(at 0 0 270)
			(unlocked yes)
			(layer "F.Fab")
			(hide yes)
			(effects
				(font
					(size 1 1)
					(thickness 0.15)
				)
			)
		)
		(property "License" "Apache-2.0"
			(at 0 0 270)
			(unlocked yes)
			(layer "F.Fab")
			(hide yes)
			(effects
				(font
					(size 1 1)
					(thickness 0.15)
				)
			)
		)
		(property "Author" "Antmicro"
			(at 0 0 270)
			(unlocked yes)
			(layer "F.Fab")
			(hide yes)
			(effects
				(font
					(size 1 1)
					(thickness 0.15)
				)
			)
		)
		(property "Val" "100k"
			(at 0 0 270)
			(unlocked yes)
			(layer "F.Fab")
			(hide yes)
			(effects
				(font
					(size 1 1)
					(thickness 0.15)
				)
			)
		)
		(property "Tolerance" "1%"
			(at 0 0 270)
			(unlocked yes)
			(layer "F.Fab")
			(hide yes)
			(effects
				(font
					(size 1 1)
					(thickness 0.15)
				)
			)
		)
		(sheetname "/Power/")
		(sheetfile "power.kicad_sch")
		(attr smd)
		(fp_rect
			(start -0.925 -0.47)
			(end 0.925 0.47)
			(stroke
				(width 0.05)
				(type default)
			)
			(fill no)
			(layer "F.CrtYd")
		)
		(fp_rect
			(start -0.5 -0.25)
			(end 0.5 0.25)
			(stroke
				(width 0.15)
				(type solid)
			)
			(fill no)
			(layer "F.Fab")
		)
		(fp_text user "${REFERENCE}"
			(at 0 0 90)
			(layer "F.Fab")
			(effects
				(font
					(size 0.7 0.7)
					(thickness 0.15)
				)
				(justify right top)
			)
		)
		(fp_text user "Author: Antmicro"
			(at -0.95 4.169 90)
			(layer "F.Fab")
			(effects
				(font
					(size 0.7 0.7)
					(thickness 0.15)
				)
				(justify right top)
			)
		)
		(fp_text user "License: Apache-2.0"
			(at -0.949999 5.169 90)
			(layer "F.Fab")
			(effects
				(font
					(size 0.7 0.7)
					(thickness 0.15)
				)
				(justify right top)
			)
		)
		(pad "1" smd roundrect
			(at -0.48 0 270)
			(size 0.59 0.64)
			(layers "F.Cu" "F.Mask" "F.Paste")
			(roundrect_rratio 0.25)
			(net 66 "GND")
			(pintype "passive")
		)
		(pad "2" smd roundrect
			(at 0.48 0 270)
			(size 0.59 0.64)
			(layers "F.Cu" "F.Mask" "F.Paste")
			(roundrect_rratio 0.25)
			(net 172 "/Power/~{PERST}")
			(pintype "passive")
		)
	)
	(footprint "antmicro-footprints:MP_Pad6mm_Drill3.2mm"
		(layer "F.Cu")
		(at 147.5 47 -90)
		(property "Reference" "MP2"
			(at 0 0 90)
			(layer "F.SilkS")
			(hide yes)
			(effects
				(font
					(size 0.7 0.7)
					(thickness 0.15)
				)
				(justify right top)
			)
		)
		(property "Value" "MP_Pad6mm_Drill3.2mm"
			(at 0 3.899999 90)
			(layer "F.Fab")
			(effects
				(font
					(size 0.7 0.7)
					(thickness 0.15)
				)
				(justify right top)
			)
		)
		(property "Description" "Mechanical part"
			(at 0 0 90)
			(layer "F.Fab")
			(hide yes)
			(effects
				(font
					(size 1.27 1.27)
					(thickness 0.15)
				)
			)
		)
		(property "Author" "Antmicro"
			(at 0 0 270)
			(unlocked yes)
			(layer "F.Fab")
			(hide yes)
			(effects
				(font
					(size 1 1)
					(thickness 0.15)
				)
			)
		)
		(property "License" "Apache-2.0"
			(at 0 0 270)
			(unlocked yes)
			(layer "F.Fab")
			(hide yes)
			(effects
				(font
					(size 1 1)
					(thickness 0.15)
				)
			)
		)
		(sheetname "/")
		(sheetfile "oculink-to-pcie-adapter.kicad_sch")
		(attr exclude_from_pos_files exclude_from_bom)
		(fp_circle
			(center 0 0)
			(end 3.25 0)
			(stroke
				(width 0.05)
				(type default)
			)
			(fill no)
			(layer "F.CrtYd")
		)
		(fp_text user "Author: Antmicro"
			(at -0.178001 7.225 90)
			(layer "F.Fab")
			(effects
				(font
					(size 0.7 0.7)
					(thickness 0.15)
				)
				(justify right top)
			)
		)
		(fp_text user "${REFERENCE}"
			(at 0 0 90)
			(layer "F.Fab")
			(effects
				(font
					(size 0.7 0.7)
					(thickness 0.15)
				)
				(justify right top)
			)
		)
		(fp_text user "License: Apache-2.0"
			(at -0.178 8.425001 90)
			(layer "F.Fab")
			(effects
				(font
					(size 0.7 0.7)
					(thickness 0.15)
				)
				(justify right top)
			)
		)
		(pad "1" thru_hole circle
			(at 0 0 270)
			(size 6 6)
			(drill 3.2)
			(layers "*.Cu" "*.Mask")
			(remove_unused_layers no)
			(net 66 "GND")
			(pintype "passive")
		)
	)
	(footprint "antmicro-footprints:TP_Pad0.75mm_Drill0.2mm"
		(layer "F.Cu")
		(at 155.75 150 -90)
		(property "Reference" "TP2"
			(at 0.5 -0.6 0)
			(layer "F.SilkS")
			(effects
				(font
					(size 0.7 0.7)
					(thickness 0.15)
				)
				(justify left bottom)
			)
		)
		(property "Value" "TP_Pad0.75mm_Drill0.2mm"
			(at 0 1.2 270)
			(layer "F.Fab")
			(effects
				(font
					(size 0.7 0.7)
					(thickness 0.15)
				)
				(justify left bottom)
			)
		)
		(property "Description" "SMT test point"
			(at 0 0 270)
			(layer "F.Fab")
			(hide yes)
			(effects
				(font
					(size 1.27 1.27)
					(thickness 0.15)
				)
			)
		)
		(property "MPN" ""
			(at 0 0 270)
			(unlocked yes)
			(layer "F.Fab")
			(hide yes)
			(effects
				(font
					(size 1 1)
					(thickness 0.15)
				)
			)
		)
		(property "Manufacturer" ""
			(at 0 0 270)
			(unlocked yes)
			(layer "F.Fab")
			(hide yes)
			(effects
				(font
					(size 1 1)
					(thickness 0.15)
				)
			)
		)
		(property "Author" "Antmicro"
			(at 0 0 270)
			(unlocked yes)
			(layer "F.Fab")
			(hide yes)
			(effects
				(font
					(size 1 1)
					(thickness 0.15)
				)
			)
		)
		(property "License" "Apache-2.0"
			(at 0 0 270)
			(unlocked yes)
			(layer "F.Fab")
			(hide yes)
			(effects
				(font
					(size 1 1)
					(thickness 0.15)
				)
			)
		)
		(sheetname "/Power/")
		(sheetfile "power.kicad_sch")
		(attr exclude_from_pos_files exclude_from_bom)
		(fp_circle
			(center 0 0)
			(end 0.475 0)
			(stroke
				(width 0.05)
				(type default)
			)
			(fill no)
			(layer "F.CrtYd")
		)
		(fp_text user "License: Apache-2.0"
			(at -0.4 5.101 270)
			(layer "F.Fab")
			(effects
				(font
					(size 0.7 0.7)
					(thickness 0.15)
				)
				(justify left bottom)
			)
		)
		(fp_text user "Author: Antmicro"
			(at -0.4 3.901 270)
			(layer "F.Fab")
			(effects
				(font
					(size 0.7 0.7)
					(thickness 0.15)
				)
				(justify left bottom)
			)
		)
		(fp_text user "${REFERENCE}"
			(at -0.4 2.7 270)
			(layer "F.Fab")
			(effects
				(font
					(size 0.7 0.7)
					(thickness 0.15)
				)
				(justify left bottom)
			)
		)
		(pad "1" thru_hole circle
			(at 0 0 270)
			(size 0.75 0.75)
			(drill 0.2)
			(layers "*.Cu" "*.Mask")
			(remove_unused_layers no)
			(net 134 "+3V3")
			(pinfunction "1")
			(pintype "passive")
		)
	)
	(footprint "antmicro-footprints:R_0402_1005Metric"
		(layer "F.Cu")
		(at 150.737 57.376 -90)
		(descr "Resistor SMD 0402")
		(tags "resistor SMD 0402")
		(property "Reference" "R25"
			(at 1.074 0.360999 90)
			(layer "F.SilkS")
			(effects
				(font
					(size 0.7 0.7)
					(thickness 0.15)
				)
				(justify right top)
			)
		)
		(property "Value" "R_1k_0402"
			(at -1.011843 1.772046 90)
			(layer "F.Fab")
			(effects
				(font
					(size 0.7 0.7)
					(thickness 0.15)
				)
				(justify right top)
			)
		)
		(property "Datasheet" "https://www.bourns.com/docs/product-datasheets/cr.pdf"
			(at 0 0 90)
			(layer "F.Fab")
			(hide yes)
			(effects
				(font
					(size 1.27 1.27)
					(thickness 0.15)
				)
			)
		)
		(property "Description" "SMD Chip Resistor, 1 kohm, ± 1%, 63 mW, 0402 [1005 Metric], Thick Film, General Purpose"
			(at 0 0 90)
			(layer "F.Fab")
			(hide yes)
			(effects
				(font
					(size 1.27 1.27)
					(thickness 0.15)
				)
			)
		)
		(property "MPN" "CR0402-FX-1001GLF"
			(at 0 0 270)
			(unlocked yes)
			(layer "F.Fab")
			(hide yes)
			(effects
				(font
					(size 1 1)
					(thickness 0.15)
				)
			)
		)
		(property "Manufacturer" "Bourns"
			(at 0 0 270)
			(unlocked yes)
			(layer "F.Fab")
			(hide yes)
			(effects
				(font
					(size 1 1)
					(thickness 0.15)
				)
			)
		)
		(property "License" "Apache-2.0"
			(at 0 0 270)
			(unlocked yes)
			(layer "F.Fab")
			(hide yes)
			(effects
				(font
					(size 1 1)
					(thickness 0.15)
				)
			)
		)
		(property "Author" "Antmicro"
			(at 0 0 270)
			(unlocked yes)
			(layer "F.Fab")
			(hide yes)
			(effects
				(font
					(size 1 1)
					(thickness 0.15)
				)
			)
		)
		(property "Val" "1k"
			(at 0 0 270)
			(unlocked yes)
			(layer "F.Fab")
			(hide yes)
			(effects
				(font
					(size 1 1)
					(thickness 0.15)
				)
			)
		)
		(property "Tolerance" "1%"
			(at 0 0 270)
			(unlocked yes)
			(layer "F.Fab")
			(hide yes)
			(effects
				(font
					(size 1 1)
					(thickness 0.15)
				)
			)
		)
		(sheetname "/USB-PD/")
		(sheetfile "usb-pd.kicad_sch")
		(attr smd)
		(fp_rect
			(start -0.925 -0.47)
			(end 0.925 0.47)
			(stroke
				(width 0.05)
				(type default)
			)
			(fill no)
			(layer "F.CrtYd")
		)
		(fp_rect
			(start -0.5 -0.25)
			(end 0.5 0.25)
			(stroke
				(width 0.15)
				(type solid)
			)
			(fill no)
			(layer "F.Fab")
		)
		(fp_text user "License: Apache-2.0"
			(at -0.949999 5.169 90)
			(layer "F.Fab")
			(effects
				(font
					(size 0.7 0.7)
					(thickness 0.15)
				)
				(justify right top)
			)
		)
		(fp_text user "${REFERENCE}"
			(at 0 0 90)
			(layer "F.Fab")
			(effects
				(font
					(size 0.7 0.7)
					(thickness 0.15)
				)
				(justify right top)
			)
		)
		(fp_text user "Author: Antmicro"
			(at -0.95 4.169 90)
			(layer "F.Fab")
			(effects
				(font
					(size 0.7 0.7)
					(thickness 0.15)
				)
				(justify right top)
			)
		)
		(pad "1" smd roundrect
			(at -0.48 0 270)
			(size 0.59 0.64)
			(layers "F.Cu" "F.Mask" "F.Paste")
			(roundrect_rratio 0.25)
			(net 138 "/USB-PD/ISNK_COARSE")
			(pintype "passive")
		)
		(pad "2" smd roundrect
			(at 0.48 0 270)
			(size 0.59 0.64)
			(layers "F.Cu" "F.Mask" "F.Paste")
			(roundrect_rratio 0.25)
			(net 117 "/USB-PD/VDDD_3V3")
			(pintype "passive")
		)
	)
	(footprint "antmicro-footprints:R_0402_1005Metric"
		(layer "F.Cu")
		(at 118.2 112.1 180)
		(descr "Resistor SMD 0402")
		(tags "resistor SMD 0402")
		(property "Reference" "R3"
			(at -0.8 1.5 180)
			(layer "F.SilkS")
			(effects
				(font
					(size 0.7 0.7)
					(thickness 0.15)
				)
				(justify right top)
			)
		)
		(property "Value" "R_0R_0402"
			(at -1.011843 1.772046 0)
			(layer "F.Fab")
			(effects
				(font
					(size 0.7 0.7)
					(thickness 0.15)
				)
				(justify right top)
			)
		)
		(property "Datasheet" "https://industrial.panasonic.com/cdbs/www-data/pdf/RDA0000/AOA0000C301.pdf"
			(at 0 0 0)
			(layer "F.Fab")
			(hide yes)
			(effects
				(font
					(size 1.27 1.27)
					(thickness 0.15)
				)
			)
		)
		(property "Description" "SMD Chip Resistor, Jumper, 0 ohm, 100 mW, 0402 [1005 Metric], Thick Film, General Purpose"
			(at 0 0 0)
			(layer "F.Fab")
			(hide yes)
			(effects
				(font
					(size 1.27 1.27)
					(thickness 0.15)
				)
			)
		)
		(property "MPN" "ERJ2GE0R00X"
			(at 0 0 180)
			(unlocked yes)
			(layer "F.Fab")
			(hide yes)
			(effects
				(font
					(size 1 1)
					(thickness 0.15)
				)
			)
		)
		(property "Manufacturer" "Panasonic"
			(at 0 0 180)
			(unlocked yes)
			(layer "F.Fab")
			(hide yes)
			(effects
				(font
					(size 1 1)
					(thickness 0.15)
				)
			)
		)
		(property "License" "Apache-2.0"
			(at 0 0 180)
			(unlocked yes)
			(layer "F.Fab")
			(hide yes)
			(effects
				(font
					(size 1 1)
					(thickness 0.15)
				)
			)
		)
		(property "Author" "Antmicro"
			(at 0 0 180)
			(unlocked yes)
			(layer "F.Fab")
			(hide yes)
			(effects
				(font
					(size 1 1)
					(thickness 0.15)
				)
			)
		)
		(property "Val" "0R"
			(at 0 0 180)
			(unlocked yes)
			(layer "F.Fab")
			(hide yes)
			(effects
				(font
					(size 1 1)
					(thickness 0.15)
				)
			)
		)
		(property "Tolerance" ""
			(at 0 0 180)
			(unlocked yes)
			(layer "F.Fab")
			(hide yes)
			(effects
				(font
					(size 1 1)
					(thickness 0.15)
				)
			)
		)
		(property "Current" "1A"
			(at 0 0 180)
			(unlocked yes)
			(layer "F.Fab")
			(hide yes)
			(effects
				(font
					(size 1 1)
					(thickness 0.15)
				)
			)
		)
		(sheetname "/PCIe-connector/")
		(sheetfile "pcie-connector.kicad_sch")
		(attr smd)
		(fp_rect
			(start -0.925 -0.47)
			(end 0.925 0.47)
			(stroke
				(width 0.05)
				(type default)
			)
			(fill no)
			(layer "F.CrtYd")
		)
		(fp_rect
			(start -0.5 -0.25)
			(end 0.5 0.25)
			(stroke
				(width 0.15)
				(type solid)
			)
			(fill no)
			(layer "F.Fab")
		)
		(fp_text user "Author: Antmicro"
			(at -0.95 4.169 0)
			(layer "F.Fab")
			(effects
				(font
					(size 0.7 0.7)
					(thickness 0.15)
				)
				(justify right top)
			)
		)
		(fp_text user "License: Apache-2.0"
			(at -0.949999 5.169 0)
			(layer "F.Fab")
			(effects
				(font
					(size 0.7 0.7)
					(thickness 0.15)
				)
				(justify right top)
			)
		)
		(fp_text user "${REFERENCE}"
			(at 0 0 0)
			(layer "F.Fab")
			(effects
				(font
					(size 0.7 0.7)
					(thickness 0.15)
				)
				(justify right top)
			)
		)
		(pad "1" smd roundrect
			(at -0.48 0 180)
			(size 0.59 0.64)
			(layers "F.Cu" "F.Mask" "F.Paste")
			(roundrect_rratio 0.25)
			(net 134 "+3V3")
			(pintype "passive")
		)
		(pad "2" smd roundrect
			(at 0.48 0 180)
			(size 0.59 0.64)
			(layers "F.Cu" "F.Mask" "F.Paste")
			(roundrect_rratio 0.25)
			(net 83 "/PCIe-connector/3V3_PCIe_AUX")
			(pintype "passive")
		)
	)
	(footprint "antmicro-footprints:R_0402_1005Metric"
		(layer "F.Cu")
		(at 120.5 130.8)
		(descr "Resistor SMD 0402")
		(tags "resistor SMD 0402")
		(property "Reference" "R10"
			(at -3.3 0.4 180)
			(layer "F.SilkS")
			(effects
				(font
					(size 0.7 0.7)
					(thickness 0.15)
				)
				(justify left bottom)
			)
		)
		(property "Value" "R_15k_0402"
			(at -1.011843 1.772046 0)
			(layer "F.Fab")
			(effects
				(font
					(size 0.7 0.7)
					(thickness 0.15)
				)
				(justify left bottom)
			)
		)
		(property "Datasheet" "https://www.bourns.com/docs/product-datasheets/cr.pdf"
			(at 0 0 0)
			(layer "F.Fab")
			(hide yes)
			(effects
				(font
					(size 1.27 1.27)
					(thickness 0.15)
				)
			)
		)
		(property "Description" "SMD Chip Resistor, 15 kohm, ± 1%, 62.5 mW, 0402 [1005 Metric], Thick Film, General Purpose"
			(at 0 0 0)
			(layer "F.Fab")
			(hide yes)
			(effects
				(font
					(size 1.27 1.27)
					(thickness 0.15)
				)
			)
		)
		(property "MPN" "CR0402-FX-1502GLF"
			(at 0 0 0)
			(unlocked yes)
			(layer "F.Fab")
			(hide yes)
			(effects
				(font
					(size 1 1)
					(thickness 0.15)
				)
			)
		)
		(property "Manufacturer" "Bourns"
			(at 0 0 0)
			(unlocked yes)
			(layer "F.Fab")
			(hide yes)
			(effects
				(font
					(size 1 1)
					(thickness 0.15)
				)
			)
		)
		(property "License" "Apache-2.0"
			(at 0 0 0)
			(unlocked yes)
			(layer "F.Fab")
			(hide yes)
			(effects
				(font
					(size 1 1)
					(thickness 0.15)
				)
			)
		)
		(property "Author" "Antmicro"
			(at 0 0 0)
			(unlocked yes)
			(layer "F.Fab")
			(hide yes)
			(effects
				(font
					(size 1 1)
					(thickness 0.15)
				)
			)
		)
		(property "Val" "15k"
			(at 0 0 0)
			(unlocked yes)
			(layer "F.Fab")
			(hide yes)
			(effects
				(font
					(size 1 1)
					(thickness 0.15)
				)
			)
		)
		(property "Tolerance" "1%"
			(at 0 0 0)
			(unlocked yes)
			(layer "F.Fab")
			(hide yes)
			(effects
				(font
					(size 1 1)
					(thickness 0.15)
				)
			)
		)
		(sheetname "/Power/")
		(sheetfile "power.kicad_sch")
		(attr smd)
		(fp_rect
			(start -0.925 -0.47)
			(end 0.925 0.47)
			(stroke
				(width 0.05)
				(type default)
			)
			(fill no)
			(layer "F.CrtYd")
		)
		(fp_rect
			(start -0.5 -0.25)
			(end 0.5 0.25)
			(stroke
				(width 0.15)
				(type solid)
			)
			(fill no)
			(layer "F.Fab")
		)
		(fp_text user "Author: Antmicro"
			(at -0.95 4.169 0)
			(layer "F.Fab")
			(effects
				(font
					(size 0.7 0.7)
					(thickness 0.15)
				)
				(justify left bottom)
			)
		)
		(fp_text user "License: Apache-2.0"
			(at -0.949999 5.169 0)
			(layer "F.Fab")
			(effects
				(font
					(size 0.7 0.7)
					(thickness 0.15)
				)
				(justify left bottom)
			)
		)
		(fp_text user "${REFERENCE}"
			(at 0 0 0)
			(layer "F.Fab")
			(effects
				(font
					(size 0.7 0.7)
					(thickness 0.15)
				)
				(justify left bottom)
			)
		)
		(pad "1" smd roundrect
			(at -0.48 0)
			(size 0.59 0.64)
			(layers "F.Cu" "F.Mask" "F.Paste")
			(roundrect_rratio 0.25)
			(net 66 "GND")
			(pintype "passive")
		)
		(pad "2" smd roundrect
			(at 0.48 0)
			(size 0.59 0.64)
			(layers "F.Cu" "F.Mask" "F.Paste")
			(roundrect_rratio 0.25)
			(net 108 "/Power/3V3_FB")
			(pintype "passive")
		)
	)
	(footprint "antmicro-footprints:QFN-2L_1.6x1x0.55mm"
		(layer "F.Cu")
		(at 140.5 43.2 90)
		(property "Reference" "D21"
			(at 0.8 0.9 90)
			(layer "F.SilkS")
			(effects
				(font
					(size 0.7 0.7)
					(thickness 0.15)
				)
				(justify right top)
			)
		)
		(property "Value" "ESDA25P35-1U1M"
			(at 0 1.700001 90)
			(layer "F.Fab")
			(effects
				(font
					(size 0.7 0.7)
					(thickness 0.15)
				)
				(justify left bottom)
			)
		)
		(property "Datasheet" "https://www.st.com/resource/en/datasheet/esda25p35-1u1m.pdf"
			(at 0 0 90)
			(layer "F.Fab")
			(hide yes)
			(effects
				(font
					(size 1.27 1.27)
					(thickness 0.15)
				)
			)
		)
		(property "Description" "Unidirectional TVS, 30 kV, QFN-2L, 22 V, 195 pF"
			(at 0 0 90)
			(layer "F.Fab")
			(hide yes)
			(effects
				(font
					(size 1.27 1.27)
					(thickness 0.15)
				)
			)
		)
		(property "MPN" "ESDA25P35-1U1M"
			(at 0 0 90)
			(unlocked yes)
			(layer "F.Fab")
			(hide yes)
			(effects
				(font
					(size 1 1)
					(thickness 0.15)
				)
			)
		)
		(property "Manufacturer" "STMicroelectronics"
			(at 0 0 90)
			(unlocked yes)
			(layer "F.Fab")
			(hide yes)
			(effects
				(font
					(size 1 1)
					(thickness 0.15)
				)
			)
		)
		(property "Author" "Antmicro"
			(at 0 0 90)
			(unlocked yes)
			(layer "F.Fab")
			(hide yes)
			(effects
				(font
					(size 1 1)
					(thickness 0.15)
				)
			)
		)
		(property "License" "Apache-2.0"
			(at 0 0 90)
			(unlocked yes)
			(layer "F.Fab")
			(hide yes)
			(effects
				(font
					(size 1 1)
					(thickness 0.15)
				)
			)
		)
		(sheetname "/USB-PD/")
		(sheetfile "usb-pd.kicad_sch")
		(attr smd)
		(fp_line
			(start 0.23 -0.45)
			(end -0.23 -0.45)
			(stroke
				(width 0.15)
				(type solid)
			)
			(layer "F.SilkS")
		)
		(fp_line
			(start -1.2 -0.4)
			(end -1.2 0.4)
			(stroke
				(width 0.15)
				(type solid)
			)
			(layer "F.SilkS")
		)
		(fp_line
			(start 0.23 0.45)
			(end -0.23 0.45)
			(stroke
				(width 0.15)
				(type solid)
			)
			(layer "F.SilkS")
		)
		(fp_rect
			(start 1.25 0.65)
			(end -1.25 -0.65)
			(stroke
				(width 0.05)
				(type solid)
			)
			(fill no)
			(layer "F.CrtYd")
		)
		(fp_line
			(start 0.201 -0.202)
			(end -0.101 0)
			(stroke
				(width 0.15)
				(type solid)
			)
			(layer "F.Fab")
		)
		(fp_line
			(start -0.199 -0.202)
			(end -0.199 0.1)
			(stroke
				(width 0.15)
				(type solid)
			)
			(layer "F.Fab")
		)
		(fp_line
			(start 0.599 0)
			(end 0.201 0)
			(stroke
				(width 0.15)
				(type solid)
			)
			(layer "F.Fab")
		)
		(fp_line
			(start 0.201 0)
			(end 0.201 -0.202)
			(stroke
				(width 0.15)
				(type solid)
			)
			(layer "F.Fab")
		)
		(fp_line
			(start -0.101 0)
			(end 0.201 0.2)
			(stroke
				(width 0.15)
				(type solid)
			)
			(layer "F.Fab")
		)
		(fp_line
			(start -0.199 0)
			(end -0.597 0)
			(stroke
				(width 0.15)
				(type solid)
			)
			(layer "F.Fab")
		)
		(fp_line
			(start 0.201 0.2)
			(end 0.201 0)
			(stroke
				(width 0.15)
				(type solid)
			)
			(layer "F.Fab")
		)
		(fp_line
			(start -0.199 0.2)
			(end -0.199 0.1)
			(stroke
				(width 0.15)
				(type solid)
			)
			(layer "F.Fab")
		)
		(fp_rect
			(start 0.848 0.4)
			(end -0.85 -0.402)
			(stroke
				(width 0.15)
				(type solid)
			)
			(fill no)
			(layer "F.Fab")
		)
		(fp_text user "${REFERENCE}"
			(at 0 0 90)
			(layer "F.Fab")
			(effects
				(font
					(size 0.7 0.7)
					(thickness 0.15)
				)
				(justify left bottom)
			)
		)
		(fp_text user "Author: Antmicro"
			(at -1.31 4.769 90)
			(layer "F.Fab")
			(effects
				(font
					(size 0.7 0.7)
					(thickness 0.15)
				)
				(justify left bottom)
			)
		)
		(fp_text user "License: Apache-2.0"
			(at -1.31 5.769 90)
			(layer "F.Fab")
			(effects
				(font
					(size 0.7 0.7)
					(thickness 0.15)
				)
				(justify left bottom)
			)
		)
		(pad "1" smd roundrect
			(at -0.7 0 270)
			(size 0.8 1)
			(layers "F.Cu" "F.Mask" "F.Paste")
			(roundrect_rratio 0.2)
			(net 113 "VBUS")
			(pinfunction "C")
			(pintype "passive")
		)
		(pad "2" smd roundrect
			(at 0.7 0 270)
			(size 0.8 1)
			(layers "F.Cu" "F.Mask" "F.Paste")
			(roundrect_rratio 0.2)
			(net 66 "GND")
			(pinfunction "A")
			(pintype "passive")
		)
	)
	(footprint "antmicro-footprints:C_0805_2012Metric"
		(layer "F.Cu")
		(at 134.5 89.5 90)
		(descr "Capacitor SMD 0805")
		(tags "capacitor SMD 0805")
		(property "Reference" "C22"
			(at 0.3 -3.1 90)
			(layer "F.SilkS")
			(effects
				(font
					(size 0.7 0.7)
					(thickness 0.15)
				)
				(justify left bottom)
			)
		)
		(property "Value" "C_10u_0805_35V"
			(at -2.055717 1.963153 90)
			(layer "F.Fab")
			(effects
				(font
					(size 0.7 0.7)
					(thickness 0.15)
				)
				(justify left bottom)
			)
		)
		(property "Datasheet" "https://www.murata.com/products/productdetail?partno=GRM21BR6YA106KE43%23"
			(at 0 0 90)
			(layer "F.Fab")
			(hide yes)
			(effects
				(font
					(size 1.27 1.27)
					(thickness 0.15)
				)
			)
		)
		(property "Description" "SMD Multilayer Ceramic Capacitor, 10 µF, 35 V, 0805 [2012 Metric], ± 10%, X5R, GRM Series"
			(at 0 0 90)
			(layer "F.Fab")
			(hide yes)
			(effects
				(font
					(size 1.27 1.27)
					(thickness 0.15)
				)
			)
		)
		(property "MPN" "GRM21BR6YA106KE43L"
			(at 0 0 90)
			(unlocked yes)
			(layer "F.Fab")
			(hide yes)
			(effects
				(font
					(size 1 1)
					(thickness 0.15)
				)
			)
		)
		(property "Manufacturer" "Murata"
			(at 0 0 90)
			(unlocked yes)
			(layer "F.Fab")
			(hide yes)
			(effects
				(font
					(size 1 1)
					(thickness 0.15)
				)
			)
		)
		(property "License" "Apache-2.0"
			(at 0 0 90)
			(unlocked yes)
			(layer "F.Fab")
			(hide yes)
			(effects
				(font
					(size 1 1)
					(thickness 0.15)
				)
			)
		)
		(property "Author" "Antmicro"
			(at 0 0 90)
			(unlocked yes)
			(layer "F.Fab")
			(hide yes)
			(effects
				(font
					(size 1 1)
					(thickness 0.15)
				)
			)
		)
		(property "Val" "10u"
			(at 0 0 90)
			(unlocked yes)
			(layer "F.Fab")
			(hide yes)
			(effects
				(font
					(size 1 1)
					(thickness 0.15)
				)
			)
		)
		(property "Voltage" "35V"
			(at 0 0 90)
			(unlocked yes)
			(layer "F.Fab")
			(hide yes)
			(effects
				(font
					(size 1 1)
					(thickness 0.15)
				)
			)
		)
		(property "Dielectric" ""
			(at 0 0 90)
			(unlocked yes)
			(layer "F.Fab")
			(hide yes)
			(effects
				(font
					(size 1 1)
					(thickness 0.15)
				)
			)
		)
		(property "Public" "False"
			(at 0 0 90)
			(unlocked yes)
			(layer "F.Fab")
			(hide yes)
			(effects
				(font
					(size 1 1)
					(thickness 0.15)
				)
			)
		)
		(sheetname "/USB-PD/")
		(sheetfile "usb-pd.kicad_sch")
		(attr smd)
		(fp_line
			(start -0.3 -0.7)
			(end 0.3 -0.7)
			(stroke
				(width 0.15)
				(type solid)
			)
			(layer "F.SilkS")
		)
		(fp_line
			(start -0.3 0.7)
			(end 0.3 0.7)
			(stroke
				(width 0.15)
				(type solid)
			)
			(layer "F.SilkS")
		)
		(fp_rect
			(start 1.95 -0.9)
			(end -1.95 0.9)
			(stroke
				(width 0.05)
				(type default)
			)
			(fill no)
			(layer "F.CrtYd")
		)
		(fp_rect
			(start -0.95 -0.675)
			(end 0.95 0.675)
			(stroke
				(width 0.15)
				(type solid)
			)
			(fill no)
			(layer "F.Fab")
		)
		(fp_text user "Author: Antmicro"
			(at -1.9 5.947 90)
			(layer "F.Fab")
			(effects
				(font
					(size 0.7 0.7)
					(thickness 0.15)
				)
				(justify left bottom)
			)
		)
		(fp_text user "License: Apache-2.0"
			(at -1.9 4.947 90)
			(layer "F.Fab")
			(effects
				(font
					(size 0.7 0.7)
					(thickness 0.15)
				)
				(justify left bottom)
			)
		)
		(fp_text user "${REFERENCE}"
			(at 0 0 90)
			(layer "F.Fab")
			(effects
				(font
					(size 0.7 0.7)
					(thickness 0.15)
				)
				(justify left bottom)
			)
		)
		(pad "1" smd roundrect
			(at -1.1 0 90)
			(size 1.2 1.3)
			(layers "F.Cu" "F.Mask" "F.Paste")
			(roundrect_rratio 0.25)
			(net 66 "GND")
			(pintype "passive")
		)
		(pad "2" smd roundrect
			(at 1.1 0 90)
			(size 1.2 1.3)
			(layers "F.Cu" "F.Mask" "F.Paste")
			(roundrect_rratio 0.25)
			(net 115 "/USB-PD/VCC")
			(pintype "passive")
		)
	)
	(footprint "antmicro-footprints:R_0402_1005Metric"
		(layer "F.Cu")
		(at 134.651 68.05 -90)
		(descr "Resistor SMD 0402")
		(tags "resistor SMD 0402")
		(property "Reference" "R38"
			(at 0.900001 4.6005 90)
			(layer "F.SilkS")
			(effects
				(font
					(size 0.7 0.7)
					(thickness 0.15)
				)
				(justify left bottom)
			)
		)
		(property "Value" "R_10k_0402"
			(at -1.011843 1.772046 90)
			(layer "F.Fab")
			(effects
				(font
					(size 0.7 0.7)
					(thickness 0.15)
				)
				(justify right top)
			)
		)
		(property "Datasheet" "https://www.bourns.com/docs/product-datasheets/cr.pdf"
			(at 0 0 90)
			(layer "F.Fab")
			(hide yes)
			(effects
				(font
					(size 1.27 1.27)
					(thickness 0.15)
				)
			)
		)
		(property "Description" "SMD Chip Resistor, 10 kohm, ± 1%, 62.5 mW, 0402 [1005 Metric], Thick Film, General Purpose"
			(at 0 0 90)
			(layer "F.Fab")
			(hide yes)
			(effects
				(font
					(size 1.27 1.27)
					(thickness 0.15)
				)
			)
		)
		(property "MPN" "CR0402-FX-1002GLF"
			(at 0 0 270)
			(unlocked yes)
			(layer "F.Fab")
			(hide yes)
			(effects
				(font
					(size 1 1)
					(thickness 0.15)
				)
			)
		)
		(property "Manufacturer" "Bourns"
			(at 0 0 270)
			(unlocked yes)
			(layer "F.Fab")
			(hide yes)
			(effects
				(font
					(size 1 1)
					(thickness 0.15)
				)
			)
		)
		(property "License" "Apache-2.0"
			(at 0 0 270)
			(unlocked yes)
			(layer "F.Fab")
			(hide yes)
			(effects
				(font
					(size 1 1)
					(thickness 0.15)
				)
			)
		)
		(property "Author" "Antmicro"
			(at 0 0 270)
			(unlocked yes)
			(layer "F.Fab")
			(hide yes)
			(effects
				(font
					(size 1 1)
					(thickness 0.15)
				)
			)
		)
		(property "Val" "10k"
			(at 0 0 270)
			(unlocked yes)
			(layer "F.Fab")
			(hide yes)
			(effects
				(font
					(size 1 1)
					(thickness 0.15)
				)
			)
		)
		(property "Tolerance" "1%"
			(at 0 0 270)
			(unlocked yes)
			(layer "F.Fab")
			(hide yes)
			(effects
				(font
					(size 1 1)
					(thickness 0.15)
				)
			)
		)
		(sheetname "/USB-PD/")
		(sheetfile "usb-pd.kicad_sch")
		(attr smd)
		(fp_rect
			(start -0.925 -0.47)
			(end 0.925 0.47)
			(stroke
				(width 0.05)
				(type default)
			)
			(fill no)
			(layer "F.CrtYd")
		)
		(fp_rect
			(start -0.5 -0.25)
			(end 0.5 0.25)
			(stroke
				(width 0.15)
				(type solid)
			)
			(fill no)
			(layer "F.Fab")
		)
		(fp_text user "License: Apache-2.0"
			(at -0.949999 5.169 90)
			(layer "F.Fab")
			(effects
				(font
					(size 0.7 0.7)
					(thickness 0.15)
				)
				(justify right top)
			)
		)
		(fp_text user "${REFERENCE}"
			(at 0 0 270)
			(layer "F.Fab")
			(effects
				(font
					(size 0.7 0.7)
					(thickness 0.15)
				)
				(justify left bottom)
			)
		)
		(fp_text user "Author: Antmicro"
			(at -0.95 4.169 90)
			(layer "F.Fab")
			(effects
				(font
					(size 0.7 0.7)
					(thickness 0.15)
				)
				(justify right top)
			)
		)
		(pad "1" smd roundrect
			(at -0.48 0 270)
			(size 0.59 0.64)
			(layers "F.Cu" "F.Mask" "F.Paste")
			(roundrect_rratio 0.25)
			(net 66 "GND")
			(pintype "passive")
		)
		(pad "2" smd roundrect
			(at 0.48 0 270)
			(size 0.59 0.64)
			(layers "F.Cu" "F.Mask" "F.Paste")
			(roundrect_rratio 0.25)
			(net 124 "/USB-PD/FAULT")
			(pintype "passive")
		)
	)
	(footprint "antmicro-footprints:R_0603_1608Metric"
		(layer "F.Cu")
		(at 132.4 100.8)
		(descr "Resistor SMD 0603")
		(tags "resistor SMD 0603")
		(property "Reference" "R26"
			(at -3.6 0.4 180)
			(layer "F.SilkS")
			(effects
				(font
					(size 0.7 0.7)
					(thickness 0.15)
				)
				(justify left bottom)
			)
		)
		(property "Value" "R_0R_22.4A_0603"
			(at 0 1.6 0)
			(layer "F.Fab")
			(effects
				(font
					(size 0.7 0.7)
					(thickness 0.15)
				)
				(justify left bottom)
			)
		)
		(property "Datasheet" "https://fscdn.rohm.com/en/products/databook/datasheet/passive/resistor/chip_resistor/pmr-jpw-e.pdf"
			(at 0 0 0)
			(layer "F.Fab")
			(hide yes)
			(effects
				(font
					(size 1.27 1.27)
					(thickness 0.15)
				)
			)
		)
		(property "Description" "SMD Chip Resistor"
			(at 0 0 0)
			(layer "F.Fab")
			(hide yes)
			(effects
				(font
					(size 1.27 1.27)
					(thickness 0.15)
				)
			)
		)
		(property "MPN" "PMR03EZPJ000"
			(at 0 0 0)
			(unlocked yes)
			(layer "F.Fab")
			(hide yes)
			(effects
				(font
					(size 1 1)
					(thickness 0.15)
				)
			)
		)
		(property "Manufacturer" "ROHM Semiconductor"
			(at 0 0 0)
			(unlocked yes)
			(layer "F.Fab")
			(hide yes)
			(effects
				(font
					(size 1 1)
					(thickness 0.15)
				)
			)
		)
		(property "Val" "0R"
			(at 0 0 0)
			(unlocked yes)
			(layer "F.Fab")
			(hide yes)
			(effects
				(font
					(size 1 1)
					(thickness 0.15)
				)
			)
		)
		(property "Max. Curr." "22.4A"
			(at 0 0 0)
			(unlocked yes)
			(layer "F.Fab")
			(hide yes)
			(effects
				(font
					(size 1 1)
					(thickness 0.15)
				)
			)
		)
		(property "Author" "Antmicro"
			(at 0 0 0)
			(unlocked yes)
			(layer "F.Fab")
			(hide yes)
			(effects
				(font
					(size 1 1)
					(thickness 0.15)
				)
			)
		)
		(property "License" "Apache-2.0"
			(at 0 0 0)
			(unlocked yes)
			(layer "F.Fab")
			(hide yes)
			(effects
				(font
					(size 1 1)
					(thickness 0.15)
				)
			)
		)
		(property "Tolerance" "template_tolerance"
			(at 0 0 0)
			(unlocked yes)
			(layer "F.Fab")
			(hide yes)
			(effects
				(font
					(size 1 1)
					(thickness 0.15)
				)
			)
		)
		(sheetname "/USB-PD/")
		(sheetfile "usb-pd.kicad_sch")
		(attr smd exclude_from_bom)
		(fp_line
			(start -0.15 -0.4)
			(end 0.15 -0.4)
			(stroke
				(width 0.15)
				(type solid)
			)
			(layer "F.SilkS")
		)
		(fp_line
			(start -0.15 0.4)
			(end 0.15 0.4)
			(stroke
				(width 0.15)
				(type solid)
			)
			(layer "F.SilkS")
		)
		(fp_rect
			(start -1.25 -0.65)
			(end 1.25 0.65)
			(stroke
				(width 0.05)
				(type solid)
			)
			(fill no)
			(layer "F.CrtYd")
		)
		(fp_rect
			(start -0.8 -0.4)
			(end 0.8 0.4)
			(stroke
				(width 0.15)
				(type solid)
			)
			(fill no)
			(layer "F.Fab")
		)
		(fp_text user "${REFERENCE}"
			(at -1.25 3.898 0)
			(layer "F.Fab")
			(effects
				(font
					(size 0.7 0.7)
					(thickness 0.15)
				)
				(justify left bottom)
			)
		)
		(fp_text user "License: Apache-2.0"
			(at -1.25 5.9 0)
			(layer "F.Fab")
			(effects
				(font
					(size 0.7 0.7)
					(thickness 0.15)
				)
				(justify left bottom)
			)
		)
		(fp_text user "Author: Antmicro"
			(at -1.25 4.9 0)
			(layer "F.Fab")
			(effects
				(font
					(size 0.7 0.7)
					(thickness 0.15)
				)
				(justify left bottom)
			)
		)
		(pad "1" smd roundrect
			(at -0.7 0)
			(size 0.8 1)
			(layers "F.Cu" "F.Mask" "F.Paste")
			(roundrect_rratio 0.2)
			(net 119 "/Power/VCC_PD")
			(pintype "passive")
		)
		(pad "2" smd roundrect
			(at 0.7 0)
			(size 0.8 1)
			(layers "F.Cu" "F.Mask" "F.Paste")
			(roundrect_rratio 0.2)
			(net 187 "/USB-PD/12V_CONV")
			(pintype "passive")
		)
	)
	(footprint "antmicro-footprints:C_0402_1005Metric"
		(layer "F.Cu")
		(at 148.152 96)
		(descr "Capacitor SMD 0402")
		(tags "capacitor SMD 0402")
		(property "Reference" "C31"
			(at 1.248 0.4 180)
			(layer "F.SilkS")
			(effects
				(font
					(size 0.7 0.7)
					(thickness 0.15)
				)
				(justify left bottom)
			)
		)
		(property "Value" "C_100n_0402"
			(at -1.022927 2.155213 0)
			(layer "F.Fab")
			(effects
				(font
					(size 0.7 0.7)
					(thickness 0.15)
				)
				(justify left bottom)
			)
		)
		(property "Datasheet" "https://www.murata.com/products/productdetail?partno=GRM155R61H104KE14%23"
			(at 0 0 0)
			(layer "F.Fab")
			(hide yes)
			(effects
				(font
					(size 1.27 1.27)
					(thickness 0.15)
				)
			)
		)
		(property "Description" "SMD Multilayer Ceramic Capacitor, 0.1 µF, 50 V, 0402 [1005 Metric], ± 10%, X5R, GRM Series"
			(at 0 0 0)
			(layer "F.Fab")
			(hide yes)
			(effects
				(font
					(size 1.27 1.27)
					(thickness 0.15)
				)
			)
		)
		(property "MPN" "GRM155R61H104KE14D"
			(at 0 0 0)
			(unlocked yes)
			(layer "F.Fab")
			(hide yes)
			(effects
				(font
					(size 1 1)
					(thickness 0.15)
				)
			)
		)
		(property "Val" "100n"
			(at 0 0 0)
			(unlocked yes)
			(layer "F.Fab")
			(hide yes)
			(effects
				(font
					(size 1 1)
					(thickness 0.15)
				)
			)
		)
		(property "Voltage" "50V"
			(at 0 0 0)
			(unlocked yes)
			(layer "F.Fab")
			(hide yes)
			(effects
				(font
					(size 1 1)
					(thickness 0.15)
				)
			)
		)
		(property "Dielectric" "X5R"
			(at 0 0 0)
			(unlocked yes)
			(layer "F.Fab")
			(hide yes)
			(effects
				(font
					(size 1 1)
					(thickness 0.15)
				)
			)
		)
		(property "Manufacturer" "Murata"
			(at 0 0 0)
			(unlocked yes)
			(layer "F.Fab")
			(hide yes)
			(effects
				(font
					(size 1 1)
					(thickness 0.15)
				)
			)
		)
		(property "License" "Apache-2.0"
			(at 0 0 0)
			(unlocked yes)
			(layer "F.Fab")
			(hide yes)
			(effects
				(font
					(size 1 1)
					(thickness 0.15)
				)
			)
		)
		(property "Author" "Antmicro"
			(at 0 0 0)
			(unlocked yes)
			(layer "F.Fab")
			(hide yes)
			(effects
				(font
					(size 1 1)
					(thickness 0.15)
				)
			)
		)
		(sheetname "/USB-PD/")
		(sheetfile "usb-pd.kicad_sch")
		(attr smd)
		(fp_rect
			(start -0.925 -0.47)
			(end 0.925 0.47)
			(stroke
				(width 0.05)
				(type default)
			)
			(fill no)
			(layer "F.CrtYd")
		)
		(fp_line
			(start -0.494 -0.25)
			(end 0.504 -0.25)
			(stroke
				(width 0.15)
				(type solid)
			)
			(layer "F.Fab")
		)
		(fp_line
			(start -0.494 0.248)
			(end -0.494 -0.25)
			(stroke
				(width 0.15)
				(type solid)
			)
			(layer "F.Fab")
		)
		(fp_line
			(start 0.504 -0.25)
			(end 0.504 0.248)
			(stroke
				(width 0.15)
				(type solid)
			)
			(layer "F.Fab")
		)
		(fp_line
			(start 0.504 0.248)
			(end -0.494 0.248)
			(stroke
				(width 0.15)
				(type solid)
			)
			(layer "F.Fab")
		)
		(fp_text user "License: Apache-2.0"
			(at -0.939 5.799 0)
			(layer "F.Fab")
			(effects
				(font
					(size 0.7 0.7)
					(thickness 0.15)
				)
				(justify left bottom)
			)
		)
		(fp_text user "${REFERENCE}"
			(at 0 0 0)
			(layer "F.Fab")
			(effects
				(font
					(size 0.7 0.7)
					(thickness 0.15)
				)
				(justify left bottom)
			)
		)
		(fp_text user "Author: Antmicro"
			(at -0.939 3.399 0)
			(layer "F.Fab")
			(effects
				(font
					(size 0.7 0.7)
					(thickness 0.15)
				)
				(justify left bottom)
			)
		)
		(pad "1" smd roundrect
			(at -0.48 0)
			(size 0.59 0.64)
			(layers "F.Cu" "F.Mask" "F.Paste")
			(roundrect_rratio 0.25)
			(net 66 "GND")
			(pintype "passive")
		)
		(pad "2" smd roundrect
			(at 0.48 0)
			(size 0.59 0.64)
			(layers "F.Cu" "F.Mask" "F.Paste")
			(roundrect_rratio 0.25)
			(net 187 "/USB-PD/12V_CONV")
			(pintype "passive")
		)
	)
	(footprint "antmicro-footprints:PLCC4_3.2x2.8mm"
		(layer "F.Cu")
		(at 137.2 36 90)
		(property "Reference" "D4"
			(at 2.4 -0.75 90)
			(layer "F.SilkS")
			(effects
				(font
					(size 0.7 0.7)
					(thickness 0.15)
				)
				(justify left bottom)
			)
		)
		(property "Value" "LED_RGB_PLCC4_ASMB_MTB1_0A3A2"
			(at 0 2.7 90)
			(unlocked yes)
			(layer "F.Fab")
			(effects
				(font
					(size 0.7 0.7)
					(thickness 0.15)
				)
				(justify left bottom)
			)
		)
		(property "Datasheet" "https://docs.broadcom.com/doc/AV02-4194EN"
			(at 0 0 90)
			(layer "F.Fab")
			(hide yes)
			(effects
				(font
					(size 1.27 1.27)
					(thickness 0.15)
				)
			)
		)
		(property "Description" "LED, RGB, SMD, PLCC-4, R 20 mA, G 20 mA, B 20 mA, R 2.1 V, G 3.1 V, B 3.1 V, Common Anode"
			(at 0 0 90)
			(layer "F.Fab")
			(hide yes)
			(effects
				(font
					(size 1.27 1.27)
					(thickness 0.15)
				)
			)
		)
		(property "MPN" "ASMB-MTB1-0A3A2"
			(at 0 0 90)
			(unlocked yes)
			(layer "F.Fab")
			(hide yes)
			(effects
				(font
					(size 1 1)
					(thickness 0.15)
				)
			)
		)
		(property "Manufacturer" "Avago Technologies"
			(at 0 0 90)
			(unlocked yes)
			(layer "F.Fab")
			(hide yes)
			(effects
				(font
					(size 1 1)
					(thickness 0.15)
				)
			)
		)
		(property "Color" "R, G, B"
			(at 0 0 90)
			(unlocked yes)
			(layer "F.Fab")
			(hide yes)
			(effects
				(font
					(size 1 1)
					(thickness 0.15)
				)
			)
		)
		(property "Author" "Antmicro"
			(at 0 0 90)
			(unlocked yes)
			(layer "F.Fab")
			(hide yes)
			(effects
				(font
					(size 1 1)
					(thickness 0.15)
				)
			)
		)
		(property "License" "Apache-2.0"
			(at 0 0 90)
			(unlocked yes)
			(layer "F.Fab")
			(hide yes)
			(effects
				(font
					(size 1 1)
					(thickness 0.15)
				)
			)
		)
		(sheetname "/USB-PD/")
		(sheetfile "usb-pd.kicad_sch")
		(attr smd)
		(fp_line
			(start -1.75 -1.491)
			(end 1.947 -1.491)
			(stroke
				(width 0.15)
				(type solid)
			)
			(layer "F.SilkS")
		)
		(fp_line
			(start -1.953 1.509)
			(end 1.947 1.509)
			(stroke
				(width 0.15)
				(type solid)
			)
			(layer "F.SilkS")
		)
		(fp_circle
			(center -2 -1.45)
			(end -1.95 -1.45)
			(stroke
				(width 0.15)
				(type solid)
			)
			(fill yes)
			(layer "F.SilkS")
		)
		(fp_rect
			(start -2.25 -1.65)
			(end 2.24 1.65)
			(stroke
				(width 0.05)
				(type solid)
			)
			(fill no)
			(layer "F.CrtYd")
		)
		(fp_line
			(start 1.597 -1.391)
			(end -1.603 -1.391)
			(stroke
				(width 0.15)
				(type solid)
			)
			(layer "F.Fab")
		)
		(fp_line
			(start -0.603 -1.391)
			(end -1.603 -0.391)
			(stroke
				(width 0.15)
				(type solid)
			)
			(layer "F.Fab")
		)
		(fp_line
			(start -1.603 -1.391)
			(end -1.603 1.409)
			(stroke
				(width 0.15)
				(type solid)
			)
			(layer "F.Fab")
		)
		(fp_line
			(start 1.597 1.409)
			(end 1.597 -1.391)
			(stroke
				(width 0.15)
				(type solid)
			)
			(layer "F.Fab")
		)
		(fp_line
			(start -1.603 1.409)
			(end 1.597 1.409)
			(stroke
				(width 0.15)
				(type solid)
			)
			(layer "F.Fab")
		)
		(fp_circle
			(center -0.003 0.009)
			(end 1.117 0.009)
			(stroke
				(width 0.15)
				(type solid)
			)
			(fill no)
			(layer "F.Fab")
		)
		(fp_text user "Author: Antmicro"
			(at -2.6 7.709 90)
			(layer "F.Fab")
			(effects
				(font
					(size 0.7 0.7)
					(thickness 0.15)
				)
				(justify left bottom)
			)
		)
		(fp_text user "License: Apache-2.0"
			(at -2.600001 6.509 90)
			(layer "F.Fab")
			(effects
				(font
					(size 0.7 0.7)
					(thickness 0.15)
				)
				(justify left bottom)
			)
		)
		(fp_text user "${REFERENCE}"
			(at -0.005001 0 90)
			(layer "F.Fab")
			(effects
				(font
					(size 0.7 0.7)
					(thickness 0.15)
				)
				(justify left bottom)
			)
		)
		(pad "1" smd rect
			(at -1.255 -0.74 90)
			(size 1.5 1.1)
			(layers "F.Cu" "F.Mask" "F.Paste")
			(net 167 "Net-(D4-C_{R})")
			(pinfunction "C_{R}")
			(pintype "passive")
		)
		(pad "2" smd rect
			(at 1.245 -0.74 90)
			(size 1.5 1.1)
			(layers "F.Cu" "F.Mask" "F.Paste")
			(net 165 "Net-(D4-C_{G})")
			(pinfunction "C_{G}")
			(pintype "passive")
		)
		(pad "3" smd rect
			(at 1.245 0.76 90)
			(size 1.5 1.1)
			(layers "F.Cu" "F.Mask" "F.Paste")
			(net 166 "unconnected-(D4-C_{B}-Pad3)")
			(pinfunction "C_{B}")
			(pintype "passive+no_connect")
		)
		(pad "4" smd rect
			(at -1.255 0.76 90)
			(size 1.5 1.1)
			(layers "F.Cu" "F.Mask" "F.Paste")
			(net 113 "VBUS")
			(pinfunction "A")
			(pintype "passive")
		)
	)
	(footprint "antmicro-footprints:R_0402_1005Metric"
		(layer "F.Cu")
		(at 118.55 45.75 -90)
		(descr "Resistor SMD 0402")
		(tags "resistor SMD 0402")
		(property "Reference" "R47"
			(at -3.15 0.35 270)
			(layer "F.SilkS")
			(effects
				(font
					(size 0.7 0.7)
					(thickness 0.15)
				)
				(justify right top)
			)
		)
		(property "Value" "R_0R_0402"
			(at -1.011843 1.772046 90)
			(layer "F.Fab")
			(effects
				(font
					(size 0.7 0.7)
					(thickness 0.15)
				)
				(justify right top)
			)
		)
		(property "Datasheet" "https://industrial.panasonic.com/cdbs/www-data/pdf/RDA0000/AOA0000C301.pdf"
			(at 0 0 90)
			(layer "F.Fab")
			(hide yes)
			(effects
				(font
					(size 1.27 1.27)
					(thickness 0.15)
				)
			)
		)
		(property "Description" "SMD Chip Resistor, Jumper, 0 ohm, 100 mW, 0402 [1005 Metric], Thick Film, General Purpose"
			(at 0 0 90)
			(layer "F.Fab")
			(hide yes)
			(effects
				(font
					(size 1.27 1.27)
					(thickness 0.15)
				)
			)
		)
		(property "MPN" "ERJ2GE0R00X"
			(at 0 0 270)
			(unlocked yes)
			(layer "F.Fab")
			(hide yes)
			(effects
				(font
					(size 1 1)
					(thickness 0.15)
				)
			)
		)
		(property "Manufacturer" "Panasonic"
			(at 0 0 270)
			(unlocked yes)
			(layer "F.Fab")
			(hide yes)
			(effects
				(font
					(size 1 1)
					(thickness 0.15)
				)
			)
		)
		(property "License" "Apache-2.0"
			(at 0 0 270)
			(unlocked yes)
			(layer "F.Fab")
			(hide yes)
			(effects
				(font
					(size 1 1)
					(thickness 0.15)
				)
			)
		)
		(property "Author" "Antmicro"
			(at 0 0 270)
			(unlocked yes)
			(layer "F.Fab")
			(hide yes)
			(effects
				(font
					(size 1 1)
					(thickness 0.15)
				)
			)
		)
		(property "Val" "0R"
			(at 0 0 270)
			(unlocked yes)
			(layer "F.Fab")
			(hide yes)
			(effects
				(font
					(size 1 1)
					(thickness 0.15)
				)
			)
		)
		(property "Tolerance" ""
			(at 0 0 270)
			(unlocked yes)
			(layer "F.Fab")
			(hide yes)
			(effects
				(font
					(size 1 1)
					(thickness 0.15)
				)
			)
		)
		(property "Current" "1A"
			(at 0 0 270)
			(unlocked yes)
			(layer "F.Fab")
			(hide yes)
			(effects
				(font
					(size 1 1)
					(thickness 0.15)
				)
			)
		)
		(sheetname "/OCuLink/")
		(sheetfile "oculink.kicad_sch")
		(attr smd)
		(fp_rect
			(start -0.925 -0.47)
			(end 0.925 0.47)
			(stroke
				(width 0.05)
				(type default)
			)
			(fill no)
			(layer "F.CrtYd")
		)
		(fp_rect
			(start -0.5 -0.25)
			(end 0.5 0.25)
			(stroke
				(width 0.15)
				(type solid)
			)
			(fill no)
			(layer "F.Fab")
		)
		(fp_text user "License: Apache-2.0"
			(at -0.949999 5.169 90)
			(layer "F.Fab")
			(effects
				(font
					(size 0.7 0.7)
					(thickness 0.15)
				)
				(justify right top)
			)
		)
		(fp_text user "${REFERENCE}"
			(at 0 0 90)
			(layer "F.Fab")
			(effects
				(font
					(size 0.7 0.7)
					(thickness 0.15)
				)
				(justify right top)
			)
		)
		(fp_text user "Author: Antmicro"
			(at -0.95 4.169 90)
			(layer "F.Fab")
			(effects
				(font
					(size 0.7 0.7)
					(thickness 0.15)
				)
				(justify right top)
			)
		)
		(pad "1" smd roundrect
			(at -0.48 0 270)
			(size 0.59 0.64)
			(layers "F.Cu" "F.Mask" "F.Paste")
			(roundrect_rratio 0.25)
			(net 171 "/OCuLink/PCIe_{REF0}_R.CK-")
			(pintype "passive")
		)
		(pad "2" smd roundrect
			(at 0.48 0 270)
			(size 0.59 0.64)
			(layers "F.Cu" "F.Mask" "F.Paste")
			(roundrect_rratio 0.25)
			(net 97 "/OCuLink/PCIe_{REF0}.CK-")
			(pintype "passive")
		)
	)
	(footprint "antmicro-footprints:TP_Pad0.75mm_Drill0.2mm"
		(layer "F.Cu")
		(at 153.912001 54.476 180)
		(property "Reference" "TP6"
			(at -0.438 -0.274 180)
			(layer "F.SilkS")
			(effects
				(font
					(size 0.7 0.7)
					(thickness 0.15)
				)
				(justify left bottom)
			)
		)
		(property "Value" "TP_Pad0.75mm_Drill0.2mm"
			(at 0 1.2 180)
			(layer "F.Fab")
			(effects
				(font
					(size 0.7 0.7)
					(thickness 0.15)
				)
				(justify left bottom)
			)
		)
		(property "Description" "SMT test point"
			(at 0 0 180)
			(layer "F.Fab")
			(hide yes)
			(effects
				(font
					(size 1.27 1.27)
					(thickness 0.15)
				)
			)
		)
		(property "MPN" ""
			(at 0 0 180)
			(unlocked yes)
			(layer "F.Fab")
			(hide yes)
			(effects
				(font
					(size 1 1)
					(thickness 0.15)
				)
			)
		)
		(property "Manufacturer" ""
			(at 0 0 180)
			(unlocked yes)
			(layer "F.Fab")
			(hide yes)
			(effects
				(font
					(size 1 1)
					(thickness 0.15)
				)
			)
		)
		(property "Author" "Antmicro"
			(at 0 0 180)
			(unlocked yes)
			(layer "F.Fab")
			(hide yes)
			(effects
				(font
					(size 1 1)
					(thickness 0.15)
				)
			)
		)
		(property "License" "Apache-2.0"
			(at 0 0 180)
			(unlocked yes)
			(layer "F.Fab")
			(hide yes)
			(effects
				(font
					(size 1 1)
					(thickness 0.15)
				)
			)
		)
		(sheetname "/USB-PD/")
		(sheetfile "usb-pd.kicad_sch")
		(attr exclude_from_pos_files exclude_from_bom)
		(fp_circle
			(center 0 0)
			(end 0.475 0)
			(stroke
				(width 0.05)
				(type default)
			)
			(fill no)
			(layer "F.CrtYd")
		)
		(fp_text user "License: Apache-2.0"
			(at -0.4 5.101 180)
			(layer "F.Fab")
			(effects
				(font
					(size 0.7 0.7)
					(thickness 0.15)
				)
				(justify left bottom)
			)
		)
		(fp_text user "${REFERENCE}"
			(at -0.4 2.7 180)
			(layer "F.Fab")
			(effects
				(font
					(size 0.7 0.7)
					(thickness 0.15)
				)
				(justify left bottom)
			)
		)
		(fp_text user "Author: Antmicro"
			(at -0.4 3.901 180)
			(layer "F.Fab")
			(effects
				(font
					(size 0.7 0.7)
					(thickness 0.15)
				)
				(justify left bottom)
			)
		)
		(pad "1" thru_hole circle
			(at 0 0 180)
			(size 0.75 0.75)
			(drill 0.2)
			(layers "*.Cu" "*.Mask")
			(remove_unused_layers no)
			(net 145 "/USB-PD/GPIO_1")
			(pinfunction "1")
			(pintype "passive")
		)
	)
	(footprint "antmicro-footprints:C_0805_2012Metric"
		(layer "F.Cu")
		(at 128.900001 131.05 -90)
		(descr "Capacitor SMD 0805")
		(tags "capacitor SMD 0805")
		(property "Reference" "C15"
			(at -5.05 0.400001 90)
			(layer "F.SilkS")
			(effects
				(font
					(size 0.7 0.7)
					(thickness 0.15)
				)
				(justify right top)
			)
		)
		(property "Value" "C_22u_25V_0805"
			(at -2.055717 1.963153 90)
			(layer "F.Fab")
			(effects
				(font
					(size 0.7 0.7)
					(thickness 0.15)
				)
				(justify right top)
			)
		)
		(property "Datasheet" "https://product.samsungsem.com/mlcc/CL21A226MAYNNN.do"
			(at 0 0 90)
			(layer "F.Fab")
			(hide yes)
			(effects
				(font
					(size 1.27 1.27)
					(thickness 0.15)
				)
			)
		)
		(property "Description" "SMT Multilayer Ceramic Capacitor, 22uF, +/-20%, 25V, X5R, 0805 [2012 Metric]"
			(at 0 0 90)
			(layer "F.Fab")
			(hide yes)
			(effects
				(font
					(size 1.27 1.27)
					(thickness 0.15)
				)
			)
		)
		(property "MPN" "CL21A226MAYNNNE"
			(at 0 0 270)
			(unlocked yes)
			(layer "F.Fab")
			(hide yes)
			(effects
				(font
					(size 1 1)
					(thickness 0.15)
				)
			)
		)
		(property "Manufacturer" "Samsung Electro-Mechanics"
			(at 0 0 270)
			(unlocked yes)
			(layer "F.Fab")
			(hide yes)
			(effects
				(font
					(size 1 1)
					(thickness 0.15)
				)
			)
		)
		(property "License" "Apache-2.0"
			(at 0 0 270)
			(unlocked yes)
			(layer "F.Fab")
			(hide yes)
			(effects
				(font
					(size 1 1)
					(thickness 0.15)
				)
			)
		)
		(property "Author" "Antmicro"
			(at 0 0 270)
			(unlocked yes)
			(layer "F.Fab")
			(hide yes)
			(effects
				(font
					(size 1 1)
					(thickness 0.15)
				)
			)
		)
		(property "Val" "22u"
			(at 0 0 270)
			(unlocked yes)
			(layer "F.Fab")
			(hide yes)
			(effects
				(font
					(size 1 1)
					(thickness 0.15)
				)
			)
		)
		(property "Voltage" "25V"
			(at 0 0 270)
			(unlocked yes)
			(layer "F.Fab")
			(hide yes)
			(effects
				(font
					(size 1 1)
					(thickness 0.15)
				)
			)
		)
		(property "Dielectric" "X5R"
			(at 0 0 270)
			(unlocked yes)
			(layer "F.Fab")
			(hide yes)
			(effects
				(font
					(size 1 1)
					(thickness 0.15)
				)
			)
		)
		(property "Public" "False"
			(at 0 0 270)
			(unlocked yes)
			(layer "F.Fab")
			(hide yes)
			(effects
				(font
					(size 1 1)
					(thickness 0.15)
				)
			)
		)
		(sheetname "/Power/")
		(sheetfile "power.kicad_sch")
		(attr smd)
		(fp_line
			(start -0.3 0.7)
			(end 0.3 0.7)
			(stroke
				(width 0.15)
				(type solid)
			)
			(layer "F.SilkS")
		)
		(fp_line
			(start -0.3 -0.7)
			(end 0.3 -0.7)
			(stroke
				(width 0.15)
				(type solid)
			)
			(layer "F.SilkS")
		)
		(fp_rect
			(start 1.95 -0.9)
			(end -1.95 0.9)
			(stroke
				(width 0.05)
				(type default)
			)
			(fill no)
			(layer "F.CrtYd")
		)
		(fp_rect
			(start -0.95 -0.675)
			(end 0.95 0.675)
			(stroke
				(width 0.15)
				(type solid)
			)
			(fill no)
			(layer "F.Fab")
		)
		(fp_text user "Author: Antmicro"
			(at -1.9 5.947 90)
			(layer "F.Fab")
			(effects
				(font
					(size 0.7 0.7)
					(thickness 0.15)
				)
				(justify right top)
			)
		)
		(fp_text user "${REFERENCE}"
			(at -1.899999 3.947 90)
			(layer "F.Fab")
			(effects
				(font
					(size 0.7 0.7)
					(thickness 0.15)
				)
				(justify right top)
			)
		)
		(fp_text user "License: Apache-2.0"
			(at -1.9 4.947 90)
			(layer "F.Fab")
			(effects
				(font
					(size 0.7 0.7)
					(thickness 0.15)
				)
				(justify right top)
			)
		)
		(pad "1" smd roundrect
			(at -1.1 0 270)
			(size 1.2 1.3)
			(layers "F.Cu" "F.Mask" "F.Paste")
			(roundrect_rratio 0.25)
			(net 66 "GND")
			(pintype "passive")
		)
		(pad "2" smd roundrect
			(at 1.1 0 270)
			(size 1.2 1.3)
			(layers "F.Cu" "F.Mask" "F.Paste")
			(roundrect_rratio 0.25)
			(net 87 "+12V")
			(pintype "passive")
		)
	)
	(footprint "antmicro-footprints:R_0402_1005Metric"
		(layer "F.Cu")
		(at 146.737 57.376 -90)
		(descr "Resistor SMD 0402")
		(tags "resistor SMD 0402")
		(property "Reference" "R29"
			(at 1.074 0.360999 90)
			(layer "F.SilkS")
			(effects
				(font
					(size 0.7 0.7)
					(thickness 0.15)
				)
				(justify right top)
			)
		)
		(property "Value" "R_1k_0402"
			(at -1.011843 1.772046 90)
			(layer "F.Fab")
			(effects
				(font
					(size 0.7 0.7)
					(thickness 0.15)
				)
				(justify right top)
			)
		)
		(property "Datasheet" "https://www.bourns.com/docs/product-datasheets/cr.pdf"
			(at 0 0 90)
			(layer "F.Fab")
			(hide yes)
			(effects
				(font
					(size 1.27 1.27)
					(thickness 0.15)
				)
			)
		)
		(property "Description" "SMD Chip Resistor, 1 kohm, ± 1%, 63 mW, 0402 [1005 Metric], Thick Film, General Purpose"
			(at 0 0 90)
			(layer "F.Fab")
			(hide yes)
			(effects
				(font
					(size 1.27 1.27)
					(thickness 0.15)
				)
			)
		)
		(property "MPN" "CR0402-FX-1001GLF"
			(at 0 0 270)
			(unlocked yes)
			(layer "F.Fab")
			(hide yes)
			(effects
				(font
					(size 1 1)
					(thickness 0.15)
				)
			)
		)
		(property "Manufacturer" "Bourns"
			(at 0 0 270)
			(unlocked yes)
			(layer "F.Fab")
			(hide yes)
			(effects
				(font
					(size 1 1)
					(thickness 0.15)
				)
			)
		)
		(property "License" "Apache-2.0"
			(at 0 0 270)
			(unlocked yes)
			(layer "F.Fab")
			(hide yes)
			(effects
				(font
					(size 1 1)
					(thickness 0.15)
				)
			)
		)
		(property "Author" "Antmicro"
			(at 0 0 270)
			(unlocked yes)
			(layer "F.Fab")
			(hide yes)
			(effects
				(font
					(size 1 1)
					(thickness 0.15)
				)
			)
		)
		(property "Val" "1k"
			(at 0 0 270)
			(unlocked yes)
			(layer "F.Fab")
			(hide yes)
			(effects
				(font
					(size 1 1)
					(thickness 0.15)
				)
			)
		)
		(property "Tolerance" "1%"
			(at 0 0 270)
			(unlocked yes)
			(layer "F.Fab")
			(hide yes)
			(effects
				(font
					(size 1 1)
					(thickness 0.15)
				)
			)
		)
		(sheetname "/USB-PD/")
		(sheetfile "usb-pd.kicad_sch")
		(attr smd)
		(fp_rect
			(start -0.925 -0.47)
			(end 0.925 0.47)
			(stroke
				(width 0.05)
				(type default)
			)
			(fill no)
			(layer "F.CrtYd")
		)
		(fp_rect
			(start -0.5 -0.25)
			(end 0.5 0.25)
			(stroke
				(width 0.15)
				(type solid)
			)
			(fill no)
			(layer "F.Fab")
		)
		(fp_text user "${REFERENCE}"
			(at 0 0 90)
			(layer "F.Fab")
			(effects
				(font
					(size 0.7 0.7)
					(thickness 0.15)
				)
				(justify right top)
			)
		)
		(fp_text user "Author: Antmicro"
			(at -0.95 4.169 90)
			(layer "F.Fab")
			(effects
				(font
					(size 0.7 0.7)
					(thickness 0.15)
				)
				(justify right top)
			)
		)
		(fp_text user "License: Apache-2.0"
			(at -0.949999 5.169 90)
			(layer "F.Fab")
			(effects
				(font
					(size 0.7 0.7)
					(thickness 0.15)
				)
				(justify right top)
			)
		)
		(pad "1" smd roundrect
			(at -0.48 0 270)
			(size 0.59 0.64)
			(layers "F.Cu" "F.Mask" "F.Paste")
			(roundrect_rratio 0.25)
			(net 133 "/USB-PD/VBUS_MIN")
			(pintype "passive")
		)
		(pad "2" smd roundrect
			(at 0.48 0 270)
			(size 0.59 0.64)
			(layers "F.Cu" "F.Mask" "F.Paste")
			(roundrect_rratio 0.25)
			(net 117 "/USB-PD/VDDD_3V3")
			(pintype "passive")
		)
	)
	(footprint "antmicro-footprints:C_Pol_Vishay-T59-EE"
		(layer "F.Cu")
		(at 138.5 77 180)
		(property "Reference" "C43"
			(at -5.1 -0.4 180)
			(layer "F.SilkS")
			(effects
				(font
					(size 0.7 0.7)
					(thickness 0.15)
				)
				(justify left bottom)
			)
		)
		(property "Value" "C_Pol_150u_30V_Vishay-T59-EE"
			(at -5.08 5.08 180)
			(unlocked yes)
			(layer "F.Fab")
			(effects
				(font
					(size 0.7 0.7)
					(thickness 0.15)
				)
				(justify left bottom)
			)
		)
		(property "Datasheet" "https://www.vishay.com/docs/40191/t59.pdf"
			(at 0 0 0)
			(layer "F.Fab")
			(hide yes)
			(effects
				(font
					(size 1.27 1.27)
					(thickness 0.15)
				)
			)
		)
		(property "Description" "Tantalum Capacitors - Polymer 150uF 30volts 20% 75mohms maxESR"
			(at 0 0 0)
			(layer "F.Fab")
			(hide yes)
			(effects
				(font
					(size 1.27 1.27)
					(thickness 0.15)
				)
			)
		)
		(property "MPN" "T59EE157M030C0075"
			(at 0 0 180)
			(unlocked yes)
			(layer "F.Fab")
			(hide yes)
			(effects
				(font
					(size 1 1)
					(thickness 0.15)
				)
			)
		)
		(property "Manufacturer" "Vishay"
			(at 0 0 180)
			(unlocked yes)
			(layer "F.Fab")
			(hide yes)
			(effects
				(font
					(size 1 1)
					(thickness 0.15)
				)
			)
		)
		(property "Voltage" "30V"
			(at 0 0 180)
			(unlocked yes)
			(layer "F.Fab")
			(hide yes)
			(effects
				(font
					(size 1 1)
					(thickness 0.15)
				)
			)
		)
		(property "Val" "150u"
			(at 0 0 180)
			(unlocked yes)
			(layer "F.Fab")
			(hide yes)
			(effects
				(font
					(size 1 1)
					(thickness 0.15)
				)
			)
		)
		(property "Author" "Antmicro"
			(at 0 0 180)
			(unlocked yes)
			(layer "F.Fab")
			(hide yes)
			(effects
				(font
					(size 1 1)
					(thickness 0.15)
				)
			)
		)
		(property "License" "Apache-2.0"
			(at 0 0 180)
			(unlocked yes)
			(layer "F.Fab")
			(hide yes)
			(effects
				(font
					(size 1 1)
					(thickness 0.15)
				)
			)
		)
		(property "Dielectric" "template_dielectric"
			(at 0 0 180)
			(unlocked yes)
			(layer "F.Fab")
			(hide yes)
			(effects
				(font
					(size 1 1)
					(thickness 0.15)
				)
			)
		)
		(sheetname "/USB-PD/")
		(sheetfile "usb-pd.kicad_sch")
		(attr smd)
		(fp_line
			(start -2 2.25)
			(end 2 2.25)
			(stroke
				(width 0.15)
				(type solid)
			)
			(layer "F.SilkS")
		)
		(fp_line
			(start -2 -2.25)
			(end 2 -2.25)
			(stroke
				(width 0.15)
				(type solid)
			)
			(layer "F.SilkS")
		)
		(fp_line
			(start -3.5 -2.8)
			(end -3.5 -3.2)
			(stroke
				(width 0.15)
				(type solid)
			)
			(layer "F.SilkS")
		)
		(fp_line
			(start -3.7 -3)
			(end -3.3 -3)
			(stroke
				(width 0.15)
				(type solid)
			)
			(layer "F.SilkS")
		)
		(fp_rect
			(start -4.9 -2.9)
			(end 4.9 2.9)
			(stroke
				(width 0.05)
				(type solid)
			)
			(fill no)
			(layer "F.CrtYd")
		)
		(fp_rect
			(start -3.75 -2.25)
			(end 3.75 2.25)
			(stroke
				(width 0.15)
				(type solid)
			)
			(fill no)
			(layer "F.Fab")
		)
		(fp_text user "Author: Antmicro"
			(at -5.079999 7.08 0)
			(layer "F.Fab")
			(effects
				(font
					(size 0.7 0.7)
					(thickness 0.15)
				)
				(justify right top)
			)
		)
		(fp_text user "${REFERENCE}"
			(at 0 -0.175 180)
			(layer "F.Fab")
			(effects
				(font
					(size 0.7 0.7)
					(thickness 0.15)
				)
				(justify left bottom)
			)
		)
		(fp_text user "License: Apache-2.0"
			(at -5.08 9.48 0)
			(layer "F.Fab")
			(effects
				(font
					(size 0.7 0.7)
					(thickness 0.15)
				)
				(justify right top)
			)
		)
		(pad "1" smd trapezoid
			(at -3.4 0 180)
			(size 2.5 5.3)
			(layers "F.Cu" "F.Mask" "F.Paste")
			(net 115 "/USB-PD/VCC")
			(pintype "passive")
		)
		(pad "2" smd trapezoid
			(at 3.4 0 180)
			(size 2.5 5.3)
			(layers "F.Cu" "F.Mask" "F.Paste")
			(net 66 "GND")
			(pintype "passive")
		)
	)
	(footprint "antmicro-footprints:R_0402_1005Metric"
		(layer "F.Cu")
		(at 154.312 53.000999)
		(descr "Resistor SMD 0402")
		(tags "resistor SMD 0402")
		(property "Reference" "R20"
			(at 1.088 0.399001 180)
			(layer "F.SilkS")
			(effects
				(font
					(size 0.7 0.7)
					(thickness 0.15)
				)
				(justify left bottom)
			)
		)
		(property "Value" "R_49k9_0402"
			(at -1.011843 1.772046 0)
			(layer "F.Fab")
			(effects
				(font
					(size 0.7 0.7)
					(thickness 0.15)
				)
				(justify left bottom)
			)
		)
		(property "Datasheet" "https://www.bourns.com/docs/product-datasheets/cr.pdf"
			(at 0 0 0)
			(layer "F.Fab")
			(hide yes)
			(effects
				(font
					(size 1.27 1.27)
					(thickness 0.15)
				)
			)
		)
		(property "Description" "SMD Chip Resistor, 49.9 kohm, ± 1%, 63 mW, 0402 [1005 Metric], Thick Film, General Purpose"
			(at 0 0 0)
			(layer "F.Fab")
			(hide yes)
			(effects
				(font
					(size 1.27 1.27)
					(thickness 0.15)
				)
			)
		)
		(property "MPN" "CR0402-FX-4992GLF"
			(at 0 0 0)
			(unlocked yes)
			(layer "F.Fab")
			(hide yes)
			(effects
				(font
					(size 1 1)
					(thickness 0.15)
				)
			)
		)
		(property "Manufacturer" "Bourns"
			(at 0 0 0)
			(unlocked yes)
			(layer "F.Fab")
			(hide yes)
			(effects
				(font
					(size 1 1)
					(thickness 0.15)
				)
			)
		)
		(property "License" "Apache-2.0"
			(at 0 0 0)
			(unlocked yes)
			(layer "F.Fab")
			(hide yes)
			(effects
				(font
					(size 1 1)
					(thickness 0.15)
				)
			)
		)
		(property "Author" "Antmicro"
			(at 0 0 0)
			(unlocked yes)
			(layer "F.Fab")
			(hide yes)
			(effects
				(font
					(size 1 1)
					(thickness 0.15)
				)
			)
		)
		(property "Val" "49k9"
			(at 0 0 0)
			(unlocked yes)
			(layer "F.Fab")
			(hide yes)
			(effects
				(font
					(size 1 1)
					(thickness 0.15)
				)
			)
		)
		(property "Tolerance" "1%"
			(at 0 0 0)
			(unlocked yes)
			(layer "F.Fab")
			(hide yes)
			(effects
				(font
					(size 1 1)
					(thickness 0.15)
				)
			)
		)
		(sheetname "/USB-PD/")
		(sheetfile "usb-pd.kicad_sch")
		(attr smd)
		(fp_rect
			(start -0.925 -0.47)
			(end 0.925 0.47)
			(stroke
				(width 0.05)
				(type default)
			)
			(fill no)
			(layer "F.CrtYd")
		)
		(fp_rect
			(start -0.5 -0.25)
			(end 0.5 0.25)
			(stroke
				(width 0.15)
				(type solid)
			)
			(fill no)
			(layer "F.Fab")
		)
		(fp_text user "License: Apache-2.0"
			(at -0.949999 5.169 0)
			(layer "F.Fab")
			(effects
				(font
					(size 0.7 0.7)
					(thickness 0.15)
				)
				(justify left bottom)
			)
		)
		(fp_text user "Author: Antmicro"
			(at -0.95 4.169 0)
			(layer "F.Fab")
			(effects
				(font
					(size 0.7 0.7)
					(thickness 0.15)
				)
				(justify left bottom)
			)
		)
		(fp_text user "${REFERENCE}"
			(at 0 0 0)
			(layer "F.Fab")
			(effects
				(font
					(size 0.7 0.7)
					(thickness 0.15)
				)
				(justify left bottom)
			)
		)
		(pad "1" smd roundrect
			(at -0.48 0)
			(size 0.59 0.64)
			(layers "F.Cu" "F.Mask" "F.Paste")
			(roundrect_rratio 0.25)
			(net 135 "/USB-PD/FLIP")
			(pintype "passive")
		)
		(pad "2" smd roundrect
			(at 0.48 0)
			(size 0.59 0.64)
			(layers "F.Cu" "F.Mask" "F.Paste")
			(roundrect_rratio 0.25)
			(net 117 "/USB-PD/VDDD_3V3")
			(pintype "passive")
		)
	)
	(footprint "antmicro-footprints:R_0402_1005Metric"
		(layer "F.Cu")
		(at 153.736999 57.376001 90)
		(descr "Resistor SMD 0402")
		(tags "resistor SMD 0402")
		(property "Reference" "R21"
			(at -3.273999 0.439002 90)
			(layer "F.SilkS")
			(effects
				(font
					(size 0.7 0.7)
					(thickness 0.15)
				)
				(justify left bottom)
			)
		)
		(property "Value" "R_1k_0402"
			(at -1.011843 1.772046 90)
			(layer "F.Fab")
			(effects
				(font
					(size 0.7 0.7)
					(thickness 0.15)
				)
				(justify left bottom)
			)
		)
		(property "Datasheet" "https://www.bourns.com/docs/product-datasheets/cr.pdf"
			(at 0 0 90)
			(layer "F.Fab")
			(hide yes)
			(effects
				(font
					(size 1.27 1.27)
					(thickness 0.15)
				)
			)
		)
		(property "Description" "SMD Chip Resistor, 1 kohm, ± 1%, 63 mW, 0402 [1005 Metric], Thick Film, General Purpose"
			(at 0 0 90)
			(layer "F.Fab")
			(hide yes)
			(effects
				(font
					(size 1.27 1.27)
					(thickness 0.15)
				)
			)
		)
		(property "MPN" "CR0402-FX-1001GLF"
			(at 0 0 90)
			(unlocked yes)
			(layer "F.Fab")
			(hide yes)
			(effects
				(font
					(size 1 1)
					(thickness 0.15)
				)
			)
		)
		(property "Manufacturer" "Bourns"
			(at 0 0 90)
			(unlocked yes)
			(layer "F.Fab")
			(hide yes)
			(effects
				(font
					(size 1 1)
					(thickness 0.15)
				)
			)
		)
		(property "License" "Apache-2.0"
			(at 0 0 90)
			(unlocked yes)
			(layer "F.Fab")
			(hide yes)
			(effects
				(font
					(size 1 1)
					(thickness 0.15)
				)
			)
		)
		(property "Author" "Antmicro"
			(at 0 0 90)
			(unlocked yes)
			(layer "F.Fab")
			(hide yes)
			(effects
				(font
					(size 1 1)
					(thickness 0.15)
				)
			)
		)
		(property "Val" "1k"
			(at 0 0 90)
			(unlocked yes)
			(layer "F.Fab")
			(hide yes)
			(effects
				(font
					(size 1 1)
					(thickness 0.15)
				)
			)
		)
		(property "Tolerance" "1%"
			(at 0 0 90)
			(unlocked yes)
			(layer "F.Fab")
			(hide yes)
			(effects
				(font
					(size 1 1)
					(thickness 0.15)
				)
			)
		)
		(sheetname "/USB-PD/")
		(sheetfile "usb-pd.kicad_sch")
		(attr smd)
		(fp_rect
			(start -0.925 -0.47)
			(end 0.925 0.47)
			(stroke
				(width 0.05)
				(type default)
			)
			(fill no)
			(layer "F.CrtYd")
		)
		(fp_rect
			(start -0.5 -0.25)
			(end 0.5 0.25)
			(stroke
				(width 0.15)
				(type solid)
			)
			(fill no)
			(layer "F.Fab")
		)
		(fp_text user "${REFERENCE}"
			(at 0 0 90)
			(layer "F.Fab")
			(effects
				(font
					(size 0.7 0.7)
					(thickness 0.15)
				)
				(justify left bottom)
			)
		)
		(fp_text user "License: Apache-2.0"
			(at -0.949999 5.169 90)
			(layer "F.Fab")
			(effects
				(font
					(size 0.7 0.7)
					(thickness 0.15)
				)
				(justify left bottom)
			)
		)
		(fp_text user "Author: Antmicro"
			(at -0.95 4.169 90)
			(layer "F.Fab")
			(effects
				(font
					(size 0.7 0.7)
					(thickness 0.15)
				)
				(justify left bottom)
			)
		)
		(pad "1" smd roundrect
			(at -0.48 0 90)
			(size 0.59 0.64)
			(layers "F.Cu" "F.Mask" "F.Paste")
			(roundrect_rratio 0.25)
			(net 66 "GND")
			(pintype "passive")
		)
		(pad "2" smd roundrect
			(at 0.48 0 90)
			(size 0.59 0.64)
			(layers "F.Cu" "F.Mask" "F.Paste")
			(roundrect_rratio 0.25)
			(net 137 "/USB-PD/ISNK_FINE")
			(pintype "passive")
		)
	)
	(footprint "antmicro-footprints:R_0402_1005Metric"
		(layer "F.Cu")
		(at 120.5 129.8)
		(descr "Resistor SMD 0402")
		(tags "resistor SMD 0402")
		(property "Reference" "R59"
			(at -3.3 0.4 0)
			(layer "F.SilkS")
			(effects
				(font
					(size 0.7 0.7)
					(thickness 0.15)
				)
				(justify left bottom)
			)
		)
		(property "Value" "R_1k5_0402"
			(at -1.011843 1.772047 0)
			(layer "F.Fab")
			(effects
				(font
					(size 0.7 0.7)
					(thickness 0.15)
				)
				(justify left bottom)
			)
		)
		(property "Datasheet" "https://www.bourns.com/docs/product-datasheets/cr.pdf"
			(at 0 0 0)
			(layer "F.Fab")
			(hide yes)
			(effects
				(font
					(size 1.27 1.27)
					(thickness 0.15)
				)
			)
		)
		(property "Description" "SMD Chip Resistor, 1.5 kohm, ± 1%, 62.5 mW, 0402 [1005 Metric], Thick Film, General Purpose"
			(at 0 0 0)
			(layer "F.Fab")
			(hide yes)
			(effects
				(font
					(size 1.27 1.27)
					(thickness 0.15)
				)
			)
		)
		(property "MPN" "CR0402-FX-1501GLF"
			(at 0 0 0)
			(unlocked yes)
			(layer "F.Fab")
			(hide yes)
			(effects
				(font
					(size 1 1)
					(thickness 0.15)
				)
			)
		)
		(property "Manufacturer" "Bourns"
			(at 0 0 0)
			(unlocked yes)
			(layer "F.Fab")
			(hide yes)
			(effects
				(font
					(size 1 1)
					(thickness 0.15)
				)
			)
		)
		(property "License" "Apache-2.0"
			(at 0 0 0)
			(unlocked yes)
			(layer "F.Fab")
			(hide yes)
			(effects
				(font
					(size 1 1)
					(thickness 0.15)
				)
			)
		)
		(property "Author" "Antmicro"
			(at 0 0 0)
			(unlocked yes)
			(layer "F.Fab")
			(hide yes)
			(effects
				(font
					(size 1 1)
					(thickness 0.15)
				)
			)
		)
		(property "Val" "1k5"
			(at 0 0 0)
			(unlocked yes)
			(layer "F.Fab")
			(hide yes)
			(effects
				(font
					(size 1 1)
					(thickness 0.15)
				)
			)
		)
		(property "Tolerance" "1%"
			(at 0 0 0)
			(unlocked yes)
			(layer "F.Fab")
			(hide yes)
			(effects
				(font
					(size 1 1)
					(thickness 0.15)
				)
			)
		)
		(sheetname "/Power/")
		(sheetfile "power.kicad_sch")
		(attr smd)
		(fp_rect
			(start -0.925 -0.47)
			(end 0.925 0.47)
			(stroke
				(width 0.05)
				(type default)
			)
			(fill no)
			(layer "F.CrtYd")
		)
		(fp_rect
			(start -0.5 -0.25)
			(end 0.5 0.25)
			(stroke
				(width 0.15)
				(type solid)
			)
			(fill no)
			(layer "F.Fab")
		)
		(fp_text user "Author: Antmicro"
			(at -0.95 4.169 0)
			(layer "F.Fab")
			(effects
				(font
					(size 0.7 0.7)
					(thickness 0.15)
				)
				(justify left bottom)
			)
		)
		(fp_text user "License: Apache-2.0"
			(at -0.95 5.169 0)
			(layer "F.Fab")
			(effects
				(font
					(size 0.7 0.7)
					(thickness 0.15)
				)
				(justify left bottom)
			)
		)
		(fp_text user "${REFERENCE}"
			(at -0.95 3.168 0)
			(layer "F.Fab")
			(effects
				(font
					(size 0.7 0.7)
					(thickness 0.15)
				)
				(justify left bottom)
			)
		)
		(pad "1" smd roundrect
			(at -0.48 0)
			(size 0.59 0.64)
			(layers "F.Cu" "F.Mask" "F.Paste")
			(roundrect_rratio 0.25)
			(net 66 "GND")
			(pintype "passive")
		)
		(pad "2" smd roundrect
			(at 0.48 0)
			(size 0.59 0.64)
			(layers "F.Cu" "F.Mask" "F.Paste")
			(roundrect_rratio 0.25)
			(net 106 "/Power/3V3_EN")
			(pintype "passive")
		)
	)
	(footprint "antmicro-footprints:VSSOP-8_2.3x2mm_P0.5mm"
		(layer "F.Cu")
		(at 126.824999 149.054999 90)
		(property "Reference" "U6"
			(at 1.95 1.6 270)
			(layer "F.SilkS")
			(effects
				(font
					(size 0.7 0.7)
					(thickness 0.15)
				)
				(justify left bottom)
			)
		)
		(property "Value" "74AUP2G132"
			(at 0 2.258 90)
			(layer "F.Fab")
			(effects
				(font
					(size 0.7 0.7)
					(thickness 0.15)
				)
				(justify left bottom)
			)
		)
		(property "Datasheet" "https://assets.nexperia.com/documents/data-sheet/74AUP2G132.pdf"
			(at 0 0 90)
			(layer "F.Fab")
			(hide yes)
			(effects
				(font
					(size 1.27 1.27)
					(thickness 0.15)
				)
			)
		)
		(property "Description" "Low-power dual 2-input NAND Schmitt trigger"
			(at 0 0 90)
			(layer "F.Fab")
			(hide yes)
			(effects
				(font
					(size 1.27 1.27)
					(thickness 0.15)
				)
			)
		)
		(property "Manufacturer" "Nexperia"
			(at 0 0 90)
			(unlocked yes)
			(layer "F.Fab")
			(hide yes)
			(effects
				(font
					(size 1 1)
					(thickness 0.15)
				)
			)
		)
		(property "MPN" "74AUP2G132"
			(at 0 0 90)
			(unlocked yes)
			(layer "F.Fab")
			(hide yes)
			(effects
				(font
					(size 1 1)
					(thickness 0.15)
				)
			)
		)
		(property "Author" "Antmicro"
			(at 0 0 90)
			(unlocked yes)
			(layer "F.Fab")
			(hide yes)
			(effects
				(font
					(size 1 1)
					(thickness 0.15)
				)
			)
		)
		(property "License" "Apache-2.0"
			(at 0 0 90)
			(unlocked yes)
			(layer "F.Fab")
			(hide yes)
			(effects
				(font
					(size 1 1)
					(thickness 0.15)
				)
			)
		)
		(sheetname "/Power/")
		(sheetfile "power.kicad_sch")
		(attr smd)
		(fp_line
			(start -0.82 -0.992)
			(end 0.825 -0.992)
			(stroke
				(width 0.15)
				(type solid)
			)
			(layer "F.SilkS")
		)
		(fp_line
			(start 0.825 1.007)
			(end -0.82 1.007)
			(stroke
				(width 0.15)
				(type solid)
			)
			(layer "F.SilkS")
		)
		(fp_circle
			(center -1.402 -1.192)
			(end -1.352 -1.192)
			(stroke
				(width 0.15)
				(type solid)
			)
			(fill yes)
			(layer "F.SilkS")
		)
		(fp_rect
			(start 1.8 1.35)
			(end -1.8 -1.35)
			(stroke
				(width 0.05)
				(type solid)
			)
			(fill no)
			(layer "F.CrtYd")
		)
		(fp_line
			(start -0.7 -0.99)
			(end -1.14 -0.55)
			(stroke
				(width 0.15)
				(type solid)
			)
			(layer "F.Fab")
		)
		(fp_rect
			(start -1.147 -0.992)
			(end 1.151 1.007)
			(stroke
				(width 0.15)
				(type solid)
			)
			(fill no)
			(layer "F.Fab")
		)
		(fp_text user "${REFERENCE}"
			(at 0 0 90)
			(layer "F.Fab")
			(effects
				(font
					(size 0.7 0.7)
					(thickness 0.15)
				)
				(justify left bottom)
			)
		)
		(fp_text user "Author: Antmicro"
			(at -1.8 5.208 90)
			(layer "F.Fab")
			(effects
				(font
					(size 0.7 0.7)
					(thickness 0.15)
				)
				(justify left bottom)
			)
		)
		(fp_text user "License: Apache-2.0"
			(at -1.8 6.408 90)
			(layer "F.Fab")
			(effects
				(font
					(size 0.7 0.7)
					(thickness 0.15)
				)
				(justify left bottom)
			)
		)
		(pad "1" smd rect
			(at -1.372 -0.742 90)
			(size 0.75 0.4)
			(layers "F.Cu" "F.Mask" "F.Paste")
			(net 185 "/Power/~{PERST_CONN}")
			(pinfunction "1A")
			(pintype "input")
		)
		(pad "2" smd rect
			(at -1.372 -0.244 90)
			(size 0.75 0.3)
			(layers "F.Cu" "F.Mask" "F.Paste")
			(net 105 "/Power/3V3_PG")
			(pinfunction "1B")
			(pintype "input")
		)
		(pad "3" smd rect
			(at -1.372 0.256 90)
			(size 0.75 0.3)
			(layers "F.Cu" "F.Mask" "F.Paste")
			(net 177 "Net-(U6-2Y)")
			(pinfunction "2Y")
			(pintype "output")
		)
		(pad "4" smd rect
			(at -1.372 0.757 90)
			(size 0.75 0.4)
			(layers "F.Cu" "F.Mask" "F.Paste")
			(net 66 "GND")
			(pinfunction "GND")
			(pintype "power_in")
		)
		(pad "5" smd rect
			(at 1.377 0.757 90)
			(size 0.75 0.4)
			(layers "F.Cu" "F.Mask" "F.Paste")
			(net 181 "/Power/PERST")
			(pinfunction "2A")
			(pintype "input")
		)
		(pad "6" smd rect
			(at 1.377 0.256 90)
			(size 0.75 0.3)
			(layers "F.Cu" "F.Mask" "F.Paste")
			(net 181 "/Power/PERST")
			(pinfunction "2B")
			(pintype "input")
		)
		(pad "7" smd rect
			(at 1.377 -0.244 90)
			(size 0.75 0.3)
			(layers "F.Cu" "F.Mask" "F.Paste")
			(net 181 "/Power/PERST")
			(pinfunction "1Y")
			(pintype "output")
		)
		(pad "8" smd rect
			(at 1.377 -0.742 90)
			(size 0.75 0.4)
			(layers "F.Cu" "F.Mask" "F.Paste")
			(net 134 "+3V3")
			(pinfunction "VCC")
			(pintype "power_in")
		)
	)
	(footprint "antmicro-footprints:R_0402_1005Metric"
		(layer "F.Cu")
		(at 120.5 133.8 180)
		(descr "Resistor SMD 0402")
		(tags "resistor SMD 0402")
		(property "Reference" "R16"
			(at 3.3 0.4 180)
			(layer "F.SilkS")
			(effects
				(font
					(size 0.7 0.7)
					(thickness 0.15)
				)
				(justify left top)
			)
		)
		(property "Value" "R_10k_0402"
			(at -1.011843 1.772046 0)
			(layer "F.Fab")
			(effects
				(font
					(size 0.7 0.7)
					(thickness 0.15)
				)
				(justify right top)
			)
		)
		(property "Datasheet" "https://www.bourns.com/docs/product-datasheets/cr.pdf"
			(at 0 0 0)
			(layer "F.Fab")
			(hide yes)
			(effects
				(font
					(size 1.27 1.27)
					(thickness 0.15)
				)
			)
		)
		(property "Description" "SMD Chip Resistor, 10 kohm, ± 1%, 62.5 mW, 0402 [1005 Metric], Thick Film, General Purpose"
			(at 0 0 0)
			(layer "F.Fab")
			(hide yes)
			(effects
				(font
					(size 1.27 1.27)
					(thickness 0.15)
				)
			)
		)
		(property "MPN" "CR0402-FX-1002GLF"
			(at 0 0 180)
			(unlocked yes)
			(layer "F.Fab")
			(hide yes)
			(effects
				(font
					(size 1 1)
					(thickness 0.15)
				)
			)
		)
		(property "Manufacturer" "Bourns"
			(at 0 0 180)
			(unlocked yes)
			(layer "F.Fab")
			(hide yes)
			(effects
				(font
					(size 1 1)
					(thickness 0.15)
				)
			)
		)
		(property "License" "Apache-2.0"
			(at 0 0 180)
			(unlocked yes)
			(layer "F.Fab")
			(hide yes)
			(effects
				(font
					(size 1 1)
					(thickness 0.15)
				)
			)
		)
		(property "Author" "Antmicro"
			(at 0 0 180)
			(unlocked yes)
			(layer "F.Fab")
			(hide yes)
			(effects
				(font
					(size 1 1)
					(thickness 0.15)
				)
			)
		)
		(property "Val" "10k"
			(at 0 0 180)
			(unlocked yes)
			(layer "F.Fab")
			(hide yes)
			(effects
				(font
					(size 1 1)
					(thickness 0.15)
				)
			)
		)
		(property "Tolerance" "1%"
			(at 0 0 180)
			(unlocked yes)
			(layer "F.Fab")
			(hide yes)
			(effects
				(font
					(size 1 1)
					(thickness 0.15)
				)
			)
		)
		(sheetname "/Power/")
		(sheetfile "power.kicad_sch")
		(attr smd)
		(fp_rect
			(start -0.925 -0.47)
			(end 0.925 0.47)
			(stroke
				(width 0.05)
				(type default)
			)
			(fill no)
			(layer "F.CrtYd")
		)
		(fp_rect
			(start -0.5 -0.25)
			(end 0.5 0.25)
			(stroke
				(width 0.15)
				(type solid)
			)
			(fill no)
			(layer "F.Fab")
		)
		(fp_text user "Author: Antmicro"
			(at -0.95 4.169 0)
			(layer "F.Fab")
			(effects
				(font
					(size 0.7 0.7)
					(thickness 0.15)
				)
				(justify right top)
			)
		)
		(fp_text user "License: Apache-2.0"
			(at -0.949999 5.169 0)
			(layer "F.Fab")
			(effects
				(font
					(size 0.7 0.7)
					(thickness 0.15)
				)
				(justify right top)
			)
		)
		(fp_text user "${REFERENCE}"
			(at 0 0 0)
			(layer "F.Fab")
			(effects
				(font
					(size 0.7 0.7)
					(thickness 0.15)
				)
				(justify right top)
			)
		)
		(pad "1" smd roundrect
			(at -0.48 0 180)
			(size 0.59 0.64)
			(layers "F.Cu" "F.Mask" "F.Paste")
			(roundrect_rratio 0.25)
			(net 107 "/Power/3V3_MODE")
			(pintype "passive")
		)
		(pad "2" smd roundrect
			(at 0.48 0 180)
			(size 0.59 0.64)
			(layers "F.Cu" "F.Mask" "F.Paste")
			(roundrect_rratio 0.25)
			(net 66 "GND")
			(pintype "passive")
		)
	)
	(footprint "antmicro-footprints:C_0402_1005Metric"
		(layer "F.Cu")
		(at 136.919998 106.35)
		(descr "Capacitor SMD 0402")
		(tags "capacitor SMD 0402")
		(property "Reference" "C32"
			(at 1.080002 0.45 180)
			(layer "F.SilkS")
			(effects
				(font
					(size 0.7 0.7)
					(thickness 0.15)
				)
				(justify left bottom)
			)
		)
		(property "Value" "C_100n_0402"
			(at -1.022927 2.155213 0)
			(layer "F.Fab")
			(effects
				(font
					(size 0.7 0.7)
					(thickness 0.15)
				)
				(justify left bottom)
			)
		)
		(property "Datasheet" "https://www.murata.com/products/productdetail?partno=GRM155R61H104KE14%23"
			(at 0 0 0)
			(layer "F.Fab")
			(hide yes)
			(effects
				(font
					(size 1.27 1.27)
					(thickness 0.15)
				)
			)
		)
		(property "Description" "SMD Multilayer Ceramic Capacitor, 0.1 µF, 50 V, 0402 [1005 Metric], ± 10%, X5R, GRM Series"
			(at 0 0 0)
			(layer "F.Fab")
			(hide yes)
			(effects
				(font
					(size 1.27 1.27)
					(thickness 0.15)
				)
			)
		)
		(property "MPN" "GRM155R61H104KE14D"
			(at 0 0 0)
			(unlocked yes)
			(layer "F.Fab")
			(hide yes)
			(effects
				(font
					(size 1 1)
					(thickness 0.15)
				)
			)
		)
		(property "Manufacturer" "Murata"
			(at 0 0 0)
			(unlocked yes)
			(layer "F.Fab")
			(hide yes)
			(effects
				(font
					(size 1 1)
					(thickness 0.15)
				)
			)
		)
		(property "License" "Apache-2.0"
			(at 0 0 0)
			(unlocked yes)
			(layer "F.Fab")
			(hide yes)
			(effects
				(font
					(size 1 1)
					(thickness 0.15)
				)
			)
		)
		(property "Author" "Antmicro"
			(at 0 0 0)
			(unlocked yes)
			(layer "F.Fab")
			(hide yes)
			(effects
				(font
					(size 1 1)
					(thickness 0.15)
				)
			)
		)
		(property "Val" "100n"
			(at 0 0 0)
			(unlocked yes)
			(layer "F.Fab")
			(hide yes)
			(effects
				(font
					(size 1 1)
					(thickness 0.15)
				)
			)
		)
		(property "Voltage" "50V"
			(at 0 0 0)
			(unlocked yes)
			(layer "F.Fab")
			(hide yes)
			(effects
				(font
					(size 1 1)
					(thickness 0.15)
				)
			)
		)
		(property "Dielectric" "X5R"
			(at 0 0 0)
			(unlocked yes)
			(layer "F.Fab")
			(hide yes)
			(effects
				(font
					(size 1 1)
					(thickness 0.15)
				)
			)
		)
		(sheetname "/Power/Ideal-diode-0/")
		(sheetfile "ideal-diode.kicad_sch")
		(attr smd)
		(fp_rect
			(start -0.925 -0.47)
			(end 0.925 0.47)
			(stroke
				(width 0.05)
				(type default)
			)
			(fill no)
			(layer "F.CrtYd")
		)
		(fp_line
			(start -0.494 -0.25)
			(end 0.504 -0.25)
			(stroke
				(width 0.15)
				(type solid)
			)
			(layer "F.Fab")
		)
		(fp_line
			(start -0.494 0.248)
			(end -0.494 -0.25)
			(stroke
				(width 0.15)
				(type solid)
			)
			(layer "F.Fab")
		)
		(fp_line
			(start 0.504 -0.25)
			(end 0.504 0.248)
			(stroke
				(width 0.15)
				(type solid)
			)
			(layer "F.Fab")
		)
		(fp_line
			(start 0.504 0.248)
			(end -0.494 0.248)
			(stroke
				(width 0.15)
				(type solid)
			)
			(layer "F.Fab")
		)
		(fp_text user "Author: Antmicro"
			(at -0.939 3.399 0)
			(layer "F.Fab")
			(effects
				(font
					(size 0.7 0.7)
					(thickness 0.15)
				)
				(justify left bottom)
			)
		)
		(fp_text user "License: Apache-2.0"
			(at -0.939 5.799 0)
			(layer "F.Fab")
			(effects
				(font
					(size 0.7 0.7)
					(thickness 0.15)
				)
				(justify left bottom)
			)
		)
		(fp_text user "${REFERENCE}"
			(at 0 0 0)
			(layer "F.Fab")
			(effects
				(font
					(size 0.7 0.7)
					(thickness 0.15)
				)
				(justify left bottom)
			)
		)
		(pad "1" smd roundrect
			(at -0.48 0)
			(size 0.59 0.64)
			(layers "F.Cu" "F.Mask" "F.Paste")
			(roundrect_rratio 0.25)
			(net 66 "GND")
			(pintype "passive")
		)
		(pad "2" smd roundrect
			(at 0.48 0)
			(size 0.59 0.64)
			(layers "F.Cu" "F.Mask" "F.Paste")
			(roundrect_rratio 0.25)
			(net 119 "/Power/VCC_PD")
			(pintype "passive")
		)
	)
	(footprint "antmicro-footprints:C_Pol_EIA-B"
		(layer "F.Cu")
		(at 120.4 137.8 90)
		(property "Reference" "C3"
			(at -3.4 -0.8 180)
			(layer "F.SilkS")
			(effects
				(font
					(size 0.7 0.7)
					(thickness 0.15)
				)
				(justify left bottom)
			)
		)
		(property "Value" "C_Pol_100u_10V_KEMET-T520-B"
			(at 0 2.85 90)
			(layer "F.Fab")
			(effects
				(font
					(size 0.7 0.7)
					(thickness 0.15)
				)
				(justify left bottom)
			)
		)
		(property "Datasheet" "https://www.kemet.com/en/us/capacitors/product/T520B107M010ATE070.html"
			(at 0 0 90)
			(layer "F.Fab")
			(hide yes)
			(effects
				(font
					(size 1.27 1.27)
					(thickness 0.15)
				)
			)
		)
		(property "Description" "Tantalum Capacitors - Polymer 10V 100uF 1311 20% ESR=70mOhms"
			(at 0 0 90)
			(layer "F.Fab")
			(hide yes)
			(effects
				(font
					(size 1.27 1.27)
					(thickness 0.15)
				)
			)
		)
		(property "Val" "100u"
			(at 0 0 90)
			(unlocked yes)
			(layer "F.Fab")
			(hide yes)
			(effects
				(font
					(size 1 1)
					(thickness 0.15)
				)
			)
		)
		(property "MPN" "T520B107M010ATE070"
			(at 0 0 90)
			(unlocked yes)
			(layer "F.Fab")
			(hide yes)
			(effects
				(font
					(size 1 1)
					(thickness 0.15)
				)
			)
		)
		(property "Manufacturer" "KEMET"
			(at 0 0 90)
			(unlocked yes)
			(layer "F.Fab")
			(hide yes)
			(effects
				(font
					(size 1 1)
					(thickness 0.15)
				)
			)
		)
		(property "License" "Apache-2.0"
			(at 0 0 90)
			(unlocked yes)
			(layer "F.Fab")
			(hide yes)
			(effects
				(font
					(size 1 1)
					(thickness 0.15)
				)
			)
		)
		(property "Author" "Antmicro"
			(at 0 0 90)
			(unlocked yes)
			(layer "F.Fab")
			(hide yes)
			(effects
				(font
					(size 1 1)
					(thickness 0.15)
				)
			)
		)
		(property "Voltage" "10V"
			(at 0 0 90)
			(unlocked yes)
			(layer "F.Fab")
			(hide yes)
			(effects
				(font
					(size 1 1)
					(thickness 0.15)
				)
			)
		)
		(property "Dielectric" "template_dielectric"
			(at 0 0 90)
			(unlocked yes)
			(layer "F.Fab")
			(hide yes)
			(effects
				(font
					(size 1 1)
					(thickness 0.15)
				)
			)
		)
		(sheetname "/Power/")
		(sheetfile "power.kicad_sch")
		(attr smd)
		(fp_line
			(start -2.521 -1.676)
			(end -2.123 -1.676)
			(stroke
				(width 0.15)
				(type solid)
			)
			(layer "F.SilkS")
		)
		(fp_line
			(start -1.8 -1.6)
			(end 1.8 -1.6)
			(stroke
				(width 0.15)
				(type solid)
			)
			(layer "F.SilkS")
		)
		(fp_line
			(start -2.325 -1.475)
			(end -2.325 -1.878)
			(stroke
				(width 0.15)
				(type solid)
			)
			(layer "F.SilkS")
		)
		(fp_line
			(start 1.8 -1.3)
			(end 1.8 -1.6)
			(stroke
				(width 0.15)
				(type solid)
			)
			(layer "F.SilkS")
		)
		(fp_line
			(start -1.8 -1.3)
			(end -1.8 -1.6)
			(stroke
				(width 0.15)
				(type solid)
			)
			(layer "F.SilkS")
		)
		(fp_line
			(start 1.8 1.3)
			(end 1.8 1.6)
			(stroke
				(width 0.15)
				(type solid)
			)
			(layer "F.SilkS")
		)
		(fp_line
			(start -1.8 1.3)
			(end -1.8 1.6)
			(stroke
				(width 0.15)
				(type solid)
			)
			(layer "F.SilkS")
		)
		(fp_line
			(start 1.8 1.6)
			(end -1.8 1.6)
			(stroke
				(width 0.15)
				(type solid)
			)
			(layer "F.SilkS")
		)
		(fp_line
			(start 1.959 -1.75)
			(end -1.97 -1.75)
			(stroke
				(width 0.05)
				(type solid)
			)
			(layer "F.CrtYd")
		)
		(fp_line
			(start 1.959 -1.75)
			(end 1.959 -1.35)
			(stroke
				(width 0.05)
				(type solid)
			)
			(layer "F.CrtYd")
		)
		(fp_line
			(start -1.97 -1.75)
			(end -1.97 -1.35)
			(stroke
				(width 0.05)
				(type solid)
			)
			(layer "F.CrtYd")
		)
		(fp_line
			(start 2.399 -1.35)
			(end 1.959 -1.35)
			(stroke
				(width 0.05)
				(type solid)
			)
			(layer "F.CrtYd")
		)
		(fp_line
			(start 2.399 -1.35)
			(end 2.4 1.35)
			(stroke
				(width 0.05)
				(type solid)
			)
			(layer "F.CrtYd")
		)
		(fp_line
			(start -1.97 -1.35)
			(end -2.41 -1.35)
			(stroke
				(width 0.05)
				(type solid)
			)
			(layer "F.CrtYd")
		)
		(fp_line
			(start -2.411 -1.35)
			(end -2.41 1.35)
			(stroke
				(width 0.05)
				(type solid)
			)
			(layer "F.CrtYd")
		)
		(fp_line
			(start 2.4 1.35)
			(end 1.96 1.35)
			(stroke
				(width 0.05)
				(type solid)
			)
			(layer "F.CrtYd")
		)
		(fp_line
			(start 1.96 1.35)
			(end 1.96 1.75)
			(stroke
				(width 0.05)
				(type solid)
			)
			(layer "F.CrtYd")
		)
		(fp_line
			(start -1.97 1.35)
			(end -2.41 1.35)
			(stroke
				(width 0.05)
				(type solid)
			)
			(layer "F.CrtYd")
		)
		(fp_line
			(start -1.97 1.35)
			(end -1.97 1.75)
			(stroke
				(width 0.05)
				(type solid)
			)
			(layer "F.CrtYd")
		)
		(fp_line
			(start 1.96 1.75)
			(end -1.97 1.75)
			(stroke
				(width 0.05)
				(type solid)
			)
			(layer "F.CrtYd")
		)
		(fp_line
			(start -1.7 1.324)
			(end -1.551 1.475)
			(stroke
				(width 0.15)
				(type solid)
			)
			(layer "F.Fab")
		)
		(fp_rect
			(start -1.72 -1.5)
			(end 1.719 1.499)
			(stroke
				(width 0.15)
				(type solid)
			)
			(fill no)
			(layer "F.Fab")
		)
		(fp_text user "Author: Antmicro"
			(at -2.665 6.85 90)
			(layer "F.Fab")
			(effects
				(font
					(size 0.7 0.7)
					(thickness 0.15)
				)
				(justify left bottom)
			)
		)
		(fp_text user "License: Apache-2.0"
			(at -2.665 5.65 90)
			(layer "F.Fab")
			(effects
				(font
					(size 0.7 0.7)
					(thickness 0.15)
				)
				(justify left bottom)
			)
		)
		(fp_text user "${REFERENCE}"
			(at -0.0855 -0.089 90)
			(layer "F.Fab")
			(effects
				(font
					(size 0.7 0.7)
					(thickness 0.15)
				)
				(justify left bottom)
			)
		)
		(pad "1" smd roundrect
			(at -1.551 0 90)
			(size 1.2 2.2)
			(layers "F.Cu" "F.Mask" "F.Paste")
			(roundrect_rratio 0.1)
			(net 186 "/Power/3V3_CONV")
			(pintype "passive")
		)
		(pad "2" smd roundrect
			(at 1.55 0 90)
			(size 1.2 2.2)
			(layers "F.Cu" "F.Mask" "F.Paste")
			(roundrect_rratio 0.1)
			(net 66 "GND")
			(pintype "passive")
		)
	)
	(footprint "antmicro-footprints:C_0805_2012Metric"
		(layer "F.Cu")
		(at 119.8 117.4)
		(descr "Capacitor SMD 0805")
		(tags "capacitor SMD 0805")
		(property "Reference" "C8"
			(at -0.4 -1.2 180)
			(layer "F.SilkS")
			(effects
				(font
					(size 0.7 0.7)
					(thickness 0.15)
				)
				(justify left bottom)
			)
		)
		(property "Value" "C_10u_0805_35V"
			(at -2.055717 1.963153 0)
			(layer "F.Fab")
			(effects
				(font
					(size 0.7 0.7)
					(thickness 0.15)
				)
				(justify left bottom)
			)
		)
		(property "Datasheet" "https://www.murata.com/products/productdetail?partno=GRM21BR6YA106KE43%23"
			(at 0 0 0)
			(layer "F.Fab")
			(hide yes)
			(effects
				(font
					(size 1.27 1.27)
					(thickness 0.15)
				)
			)
		)
		(property "Description" "SMD Multilayer Ceramic Capacitor, 10 µF, 35 V, 0805 [2012 Metric], ± 10%, X5R, GRM Series"
			(at 0 0 0)
			(layer "F.Fab")
			(hide yes)
			(effects
				(font
					(size 1.27 1.27)
					(thickness 0.15)
				)
			)
		)
		(property "MPN" "GRM21BR6YA106KE43L"
			(at 0 0 0)
			(unlocked yes)
			(layer "F.Fab")
			(hide yes)
			(effects
				(font
					(size 1 1)
					(thickness 0.15)
				)
			)
		)
		(property "Manufacturer" "Murata"
			(at 0 0 0)
			(unlocked yes)
			(layer "F.Fab")
			(hide yes)
			(effects
				(font
					(size 1 1)
					(thickness 0.15)
				)
			)
		)
		(property "License" "Apache-2.0"
			(at 0 0 0)
			(unlocked yes)
			(layer "F.Fab")
			(hide yes)
			(effects
				(font
					(size 1 1)
					(thickness 0.15)
				)
			)
		)
		(property "Author" "Antmicro"
			(at 0 0 0)
			(unlocked yes)
			(layer "F.Fab")
			(hide yes)
			(effects
				(font
					(size 1 1)
					(thickness 0.15)
				)
			)
		)
		(property "Val" "10u"
			(at 0 0 0)
			(unlocked yes)
			(layer "F.Fab")
			(hide yes)
			(effects
				(font
					(size 1 1)
					(thickness 0.15)
				)
			)
		)
		(property "Voltage" "35V"
			(at 0 0 0)
			(unlocked yes)
			(layer "F.Fab")
			(hide yes)
			(effects
				(font
					(size 1 1)
					(thickness 0.15)
				)
			)
		)
		(property "Dielectric" ""
			(at 0 0 0)
			(unlocked yes)
			(layer "F.Fab")
			(hide yes)
			(effects
				(font
					(size 1 1)
					(thickness 0.15)
				)
			)
		)
		(property "Public" "False"
			(at 0 0 0)
			(unlocked yes)
			(layer "F.Fab")
			(hide yes)
			(effects
				(font
					(size 1 1)
					(thickness 0.15)
				)
			)
		)
		(sheetname "/PCIe-connector/")
		(sheetfile "pcie-connector.kicad_sch")
		(attr smd)
		(fp_line
			(start -0.3 -0.7)
			(end 0.3 -0.7)
			(stroke
				(width 0.15)
				(type solid)
			)
			(layer "F.SilkS")
		)
		(fp_line
			(start -0.3 0.7)
			(end 0.3 0.7)
			(stroke
				(width 0.15)
				(type solid)
			)
			(layer "F.SilkS")
		)
		(fp_rect
			(start 1.95 -0.9)
			(end -1.95 0.9)
			(stroke
				(width 0.05)
				(type default)
			)
			(fill no)
			(layer "F.CrtYd")
		)
		(fp_rect
			(start -0.95 -0.675)
			(end 0.95 0.675)
			(stroke
				(width 0.15)
				(type solid)
			)
			(fill no)
			(layer "F.Fab")
		)
		(fp_text user "Author: Antmicro"
			(at -1.9 5.947 0)
			(layer "F.Fab")
			(effects
				(font
					(size 0.7 0.7)
					(thickness 0.15)
				)
				(justify left bottom)
			)
		)
		(fp_text user "${REFERENCE}"
			(at 0 0 0)
			(layer "F.Fab")
			(effects
				(font
					(size 0.7 0.7)
					(thickness 0.15)
				)
				(justify left bottom)
			)
		)
		(fp_text user "License: Apache-2.0"
			(at -1.9 4.947 0)
			(layer "F.Fab")
			(effects
				(font
					(size 0.7 0.7)
					(thickness 0.15)
				)
				(justify left bottom)
			)
		)
		(pad "1" smd roundrect
			(at -1.1 0)
			(size 1.2 1.3)
			(layers "F.Cu" "F.Mask" "F.Paste")
			(roundrect_rratio 0.25)
			(net 87 "+12V")
			(pintype "passive")
		)
		(pad "2" smd roundrect
			(at 1.1 0)
			(size 1.2 1.3)
			(layers "F.Cu" "F.Mask" "F.Paste")
			(roundrect_rratio 0.25)
			(net 66 "GND")
			(pintype "passive")
		)
	)
	(footprint "antmicro-footprints:F_1206_3216Metric"
		(layer "F.Cu")
		(at 143 113 180)
		(property "Reference" "F1"
			(at 4 0.4 180)
			(layer "F.SilkS")
			(effects
				(font
					(size 0.7 0.7)
					(thickness 0.15)
				)
				(justify left top)
			)
		)
		(property "Value" "F_7A_1206"
			(at 0 2.000001 0)
			(layer "F.Fab")
			(effects
				(font
					(size 0.7 0.7)
					(thickness 0.15)
				)
				(justify right top)
			)
		)
		(property "Datasheet" "https://us.schurter.com/pdf/english/typ_UST_1206.pdf"
			(at 0 0 0)
			(layer "F.Fab")
			(hide yes)
			(effects
				(font
					(size 1.27 1.27)
					(thickness 0.15)
				)
			)
		)
		(property "Description" "7 A 32 V AC 63 V DC Fuse Board Mount (Cartridge Style Excluded) Surface Mount 1206 (3216 Metric)"
			(at 0 0 0)
			(layer "F.Fab")
			(hide yes)
			(effects
				(font
					(size 1.27 1.27)
					(thickness 0.15)
				)
			)
		)
		(property "Manufacturer" "Schurter"
			(at 0 0 180)
			(unlocked yes)
			(layer "F.Fab")
			(hide yes)
			(effects
				(font
					(size 1 1)
					(thickness 0.15)
				)
			)
		)
		(property "MPN" "3413.0326.11"
			(at 0 0 180)
			(unlocked yes)
			(layer "F.Fab")
			(hide yes)
			(effects
				(font
					(size 1 1)
					(thickness 0.15)
				)
			)
		)
		(property "Author" "Antmicro"
			(at 0 0 180)
			(unlocked yes)
			(layer "F.Fab")
			(hide yes)
			(effects
				(font
					(size 1 1)
					(thickness 0.15)
				)
			)
		)
		(property "License" "Apache-2.0"
			(at 0 0 180)
			(unlocked yes)
			(layer "F.Fab")
			(hide yes)
			(effects
				(font
					(size 1 1)
					(thickness 0.15)
				)
			)
		)
		(sheetname "/Power/")
		(sheetfile "power.kicad_sch")
		(attr smd)
		(fp_line
			(start 0.8 0.901)
			(end -0.8 0.901)
			(stroke
				(width 0.15)
				(type solid)
			)
			(layer "F.SilkS")
		)
		(fp_line
			(start 0.8 -0.899)
			(end -0.8 -0.899)
			(stroke
				(width 0.15)
				(type solid)
			)
			(layer "F.SilkS")
		)
		(fp_rect
			(start -2.325 -1.15)
			(end 2.325 1.15)
			(stroke
				(width 0.05)
				(type default)
			)
			(fill no)
			(layer "F.CrtYd")
		)
		(fp_line
			(start 1.624 0.792)
			(end -1.677 0.792)
			(stroke
				(width 0.15)
				(type solid)
			)
			(layer "F.Fab")
		)
		(fp_line
			(start 1.624 -0.861)
			(end 1.624 0.792)
			(stroke
				(width 0.15)
				(type solid)
			)
			(layer "F.Fab")
		)
		(fp_line
			(start -1.677 0.792)
			(end -1.677 -0.861)
			(stroke
				(width 0.15)
				(type solid)
			)
			(layer "F.Fab")
		)
		(fp_line
			(start -1.677 -0.861)
			(end 1.624 -0.861)
			(stroke
				(width 0.15)
				(type solid)
			)
			(layer "F.Fab")
		)
		(fp_text user "Author: Antmicro"
			(at -1.95 6.4 0)
			(layer "F.Fab")
			(effects
				(font
					(size 0.7 0.7)
					(thickness 0.15)
				)
				(justify right top)
			)
		)
		(fp_text user "${REFERENCE}"
			(at 0 0 0)
			(layer "F.Fab")
			(effects
				(font
					(size 0.7 0.7)
					(thickness 0.15)
				)
				(justify right top)
			)
		)
		(fp_text user "License: Apache-2.0"
			(at -1.95 5.2 0)
			(layer "F.Fab")
			(effects
				(font
					(size 0.7 0.7)
					(thickness 0.15)
				)
				(justify right top)
			)
		)
		(pad "1" smd roundrect
			(at -1.5 0.001 180)
			(size 1.15 1.8)
			(layers "F.Cu" "F.Mask" "F.Paste")
			(roundrect_rratio 0.25)
			(net 168 "/Power/VCC_DC_CONN_1")
			(pintype "passive")
		)
		(pad "2" smd roundrect
			(at 1.5 0.001 180)
			(size 1.15 1.8)
			(layers "F.Cu" "F.Mask" "F.Paste")
			(roundrect_rratio 0.25)
			(net 118 "/Power/Ideal-diode-1/VIN")
			(pintype "passive")
		)
	)
	(footprint "antmicro-footprints:C_0805_2012Metric"
		(layer "F.Cu")
		(at 126.9 131.05 -90)
		(descr "Capacitor SMD 0805")
		(tags "capacitor SMD 0805")
		(property "Reference" "C4"
			(at -4.35 0.4 90)
			(layer "F.SilkS")
			(effects
				(font
					(size 0.7 0.7)
					(thickness 0.15)
				)
				(justify right top)
			)
		)
		(property "Value" "C_22u_25V_0805"
			(at -2.055717 1.963153 90)
			(layer "F.Fab")
			(effects
				(font
					(size 0.7 0.7)
					(thickness 0.15)
				)
				(justify right top)
			)
		)
		(property "Datasheet" "https://product.samsungsem.com/mlcc/CL21A226MAYNNN.do"
			(at 0 0 90)
			(layer "F.Fab")
			(hide yes)
			(effects
				(font
					(size 1.27 1.27)
					(thickness 0.15)
				)
			)
		)
		(property "Description" "SMT Multilayer Ceramic Capacitor, 22uF, +/-20%, 25V, X5R, 0805 [2012 Metric]"
			(at 0 0 90)
			(layer "F.Fab")
			(hide yes)
			(effects
				(font
					(size 1.27 1.27)
					(thickness 0.15)
				)
			)
		)
		(property "MPN" "CL21A226MAYNNNE"
			(at 0 0 270)
			(unlocked yes)
			(layer "F.Fab")
			(hide yes)
			(effects
				(font
					(size 1 1)
					(thickness 0.15)
				)
			)
		)
		(property "Manufacturer" "Samsung Electro-Mechanics"
			(at 0 0 270)
			(unlocked yes)
			(layer "F.Fab")
			(hide yes)
			(effects
				(font
					(size 1 1)
					(thickness 0.15)
				)
			)
		)
		(property "License" "Apache-2.0"
			(at 0 0 270)
			(unlocked yes)
			(layer "F.Fab")
			(hide yes)
			(effects
				(font
					(size 1 1)
					(thickness 0.15)
				)
			)
		)
		(property "Author" "Antmicro"
			(at 0 0 270)
			(unlocked yes)
			(layer "F.Fab")
			(hide yes)
			(effects
				(font
					(size 1 1)
					(thickness 0.15)
				)
			)
		)
		(property "Val" "22u"
			(at 0 0 270)
			(unlocked yes)
			(layer "F.Fab")
			(hide yes)
			(effects
				(font
					(size 1 1)
					(thickness 0.15)
				)
			)
		)
		(property "Voltage" "25V"
			(at 0 0 270)
			(unlocked yes)
			(layer "F.Fab")
			(hide yes)
			(effects
				(font
					(size 1 1)
					(thickness 0.15)
				)
			)
		)
		(property "Dielectric" "X5R"
			(at 0 0 270)
			(unlocked yes)
			(layer "F.Fab")
			(hide yes)
			(effects
				(font
					(size 1 1)
					(thickness 0.15)
				)
			)
		)
		(property "Public" "False"
			(at 0 0 270)
			(unlocked yes)
			(layer "F.Fab")
			(hide yes)
			(effects
				(font
					(size 1 1)
					(thickness 0.15)
				)
			)
		)
		(sheetname "/Power/")
		(sheetfile "power.kicad_sch")
		(attr smd)
		(fp_line
			(start -0.3 0.7)
			(end 0.3 0.7)
			(stroke
				(width 0.15)
				(type solid)
			)
			(layer "F.SilkS")
		)
		(fp_line
			(start -0.3 -0.7)
			(end 0.3 -0.7)
			(stroke
				(width 0.15)
				(type solid)
			)
			(layer "F.SilkS")
		)
		(fp_rect
			(start 1.95 -0.9)
			(end -1.95 0.9)
			(stroke
				(width 0.05)
				(type default)
			)
			(fill no)
			(layer "F.CrtYd")
		)
		(fp_rect
			(start -0.95 -0.675)
			(end 0.95 0.675)
			(stroke
				(width 0.15)
				(type solid)
			)
			(fill no)
			(layer "F.Fab")
		)
		(fp_text user "Author: Antmicro"
			(at -1.9 5.947 90)
			(layer "F.Fab")
			(effects
				(font
					(size 0.7 0.7)
					(thickness 0.15)
				)
				(justify right top)
			)
		)
		(fp_text user "License: Apache-2.0"
			(at -1.9 4.947 90)
			(layer "F.Fab")
			(effects
				(font
					(size 0.7 0.7)
					(thickness 0.15)
				)
				(justify right top)
			)
		)
		(fp_text user "${REFERENCE}"
			(at 0 0 90)
			(layer "F.Fab")
			(effects
				(font
					(size 0.7 0.7)
					(thickness 0.15)
				)
				(justify right top)
			)
		)
		(pad "1" smd roundrect
			(at -1.1 0 270)
			(size 1.2 1.3)
			(layers "F.Cu" "F.Mask" "F.Paste")
			(roundrect_rratio 0.25)
			(net 66 "GND")
			(pintype "passive")
		)
		(pad "2" smd roundrect
			(at 1.1 0 270)
			(size 1.2 1.3)
			(layers "F.Cu" "F.Mask" "F.Paste")
			(roundrect_rratio 0.25)
			(net 87 "+12V")
			(pintype "passive")
		)
	)
	(footprint "antmicro-footprints:R_0402_1005Metric"
		(layer "F.Cu")
		(at 127.332999 152.076998 -90)
		(descr "Resistor SMD 0402")
		(tags "resistor SMD 0402")
		(property "Reference" "R13"
			(at 0.923002 0.332999 270)
			(layer "F.SilkS")
			(effects
				(font
					(size 0.7 0.7)
					(thickness 0.15)
				)
				(justify right top)
			)
		)
		(property "Value" "R_0R_0402"
			(at -1.011843 1.772046 90)
			(layer "F.Fab")
			(effects
				(font
					(size 0.7 0.7)
					(thickness 0.15)
				)
				(justify right top)
			)
		)
		(property "Datasheet" "https://industrial.panasonic.com/cdbs/www-data/pdf/RDA0000/AOA0000C301.pdf"
			(at 0 0 90)
			(layer "F.Fab")
			(hide yes)
			(effects
				(font
					(size 1.27 1.27)
					(thickness 0.15)
				)
			)
		)
		(property "Description" "SMD Chip Resistor, Jumper, 0 ohm, 100 mW, 0402 [1005 Metric], Thick Film, General Purpose"
			(at 0 0 90)
			(layer "F.Fab")
			(hide yes)
			(effects
				(font
					(size 1.27 1.27)
					(thickness 0.15)
				)
			)
		)
		(property "MPN" "ERJ2GE0R00X"
			(at 0 0 270)
			(unlocked yes)
			(layer "F.Fab")
			(hide yes)
			(effects
				(font
					(size 1 1)
					(thickness 0.15)
				)
			)
		)
		(property "Manufacturer" "Panasonic"
			(at 0 0 270)
			(unlocked yes)
			(layer "F.Fab")
			(hide yes)
			(effects
				(font
					(size 1 1)
					(thickness 0.15)
				)
			)
		)
		(property "License" "Apache-2.0"
			(at 0 0 270)
			(unlocked yes)
			(layer "F.Fab")
			(hide yes)
			(effects
				(font
					(size 1 1)
					(thickness 0.15)
				)
			)
		)
		(property "Author" "Antmicro"
			(at 0 0 270)
			(unlocked yes)
			(layer "F.Fab")
			(hide yes)
			(effects
				(font
					(size 1 1)
					(thickness 0.15)
				)
			)
		)
		(property "Val" "0R"
			(at 0 0 270)
			(unlocked yes)
			(layer "F.Fab")
			(hide yes)
			(effects
				(font
					(size 1 1)
					(thickness 0.15)
				)
			)
		)
		(property "Tolerance" ""
			(at 0 0 270)
			(unlocked yes)
			(layer "F.Fab")
			(hide yes)
			(effects
				(font
					(size 1 1)
					(thickness 0.15)
				)
			)
		)
		(property "Current" "1A"
			(at 0 0 270)
			(unlocked yes)
			(layer "F.Fab")
			(hide yes)
			(effects
				(font
					(size 1 1)
					(thickness 0.15)
				)
			)
		)
		(sheetname "/Power/")
		(sheetfile "power.kicad_sch")
		(attr smd)
		(fp_rect
			(start -0.925 -0.47)
			(end 0.925 0.47)
			(stroke
				(width 0.05)
				(type default)
			)
			(fill no)
			(layer "F.CrtYd")
		)
		(fp_rect
			(start -0.5 -0.25)
			(end 0.5 0.25)
			(stroke
				(width 0.15)
				(type solid)
			)
			(fill no)
			(layer "F.Fab")
		)
		(fp_text user "License: Apache-2.0"
			(at -0.949999 5.169 90)
			(layer "F.Fab")
			(effects
				(font
					(size 0.7 0.7)
					(thickness 0.15)
				)
				(justify right top)
			)
		)
		(fp_text user "${REFERENCE}"
			(at 0 0 90)
			(layer "F.Fab")
			(effects
				(font
					(size 0.7 0.7)
					(thickness 0.15)
				)
				(justify right top)
			)
		)
		(fp_text user "Author: Antmicro"
			(at -0.95 4.169 90)
			(layer "F.Fab")
			(effects
				(font
					(size 0.7 0.7)
					(thickness 0.15)
				)
				(justify right top)
			)
		)
		(pad "1" smd roundrect
			(at -0.48 0 270)
			(size 0.59 0.64)
			(layers "F.Cu" "F.Mask" "F.Paste")
			(roundrect_rratio 0.25)
			(net 177 "Net-(U6-2Y)")
			(pintype "passive")
		)
		(pad "2" smd roundrect
			(at 0.48 0 270)
			(size 0.59 0.64)
			(layers "F.Cu" "F.Mask" "F.Paste")
			(roundrect_rratio 0.25)
			(net 172 "/Power/~{PERST}")
			(pintype "passive")
		)
	)
	(footprint "antmicro-footprints:R_0402_1005Metric"
		(layer "F.Cu")
		(at 146 63 180)
		(descr "Resistor SMD 0402")
		(tags "resistor SMD 0402")
		(property "Reference" "R57"
			(at -1.2 1.4 0)
			(layer "F.SilkS")
			(effects
				(font
					(size 0.7 0.7)
					(thickness 0.15)
				)
				(justify right top)
			)
		)
		(property "Value" "R_50R_0402"
			(at -1.011843 1.772046 0)
			(layer "F.Fab")
			(effects
				(font
					(size 0.7 0.7)
					(thickness 0.15)
				)
				(justify right top)
			)
		)
		(property "Datasheet" "https://www.bourns.com/docs/product-datasheets/cr.pdf"
			(at 0 0 0)
			(layer "F.Fab")
			(hide yes)
			(effects
				(font
					(size 1.27 1.27)
					(thickness 0.15)
				)
			)
		)
		(property "Description" "SMD Chip Resistor"
			(at 0 0 0)
			(layer "F.Fab")
			(hide yes)
			(effects
				(font
					(size 1.27 1.27)
					(thickness 0.15)
				)
			)
		)
		(property "MPN" "CR0402-FX-50R0GLF"
			(at 0 0 180)
			(unlocked yes)
			(layer "F.Fab")
			(hide yes)
			(effects
				(font
					(size 1 1)
					(thickness 0.15)
				)
			)
		)
		(property "Manufacturer" "Bourns"
			(at 0 0 180)
			(unlocked yes)
			(layer "F.Fab")
			(hide yes)
			(effects
				(font
					(size 1 1)
					(thickness 0.15)
				)
			)
		)
		(property "License" "Apache-2.0"
			(at 0 0 180)
			(unlocked yes)
			(layer "F.Fab")
			(hide yes)
			(effects
				(font
					(size 1 1)
					(thickness 0.15)
				)
			)
		)
		(property "Author" "Antmicro"
			(at 0 0 180)
			(unlocked yes)
			(layer "F.Fab")
			(hide yes)
			(effects
				(font
					(size 1 1)
					(thickness 0.15)
				)
			)
		)
		(property "Val" "50R"
			(at 0 0 180)
			(unlocked yes)
			(layer "F.Fab")
			(hide yes)
			(effects
				(font
					(size 1 1)
					(thickness 0.15)
				)
			)
		)
		(property "Tolerance" "1%"
			(at 0 0 180)
			(unlocked yes)
			(layer "F.Fab")
			(hide yes)
			(effects
				(font
					(size 1 1)
					(thickness 0.15)
				)
			)
		)
		(sheetname "/PCIe-clock-generator/")
		(sheetfile "pcie-clock-generator.kicad_sch")
		(attr smd exclude_from_bom dnp)
		(fp_poly
			(pts
				(xy -0.925 -0.47) (xy 0.925 -0.47) (xy 0.925 0.47) (xy -0.925 0.47)
			)
			(stroke
				(width 0.05)
				(type default)
			)
			(fill no)
			(layer "F.CrtYd")
		)
		(fp_poly
			(pts
				(xy -0.5 -0.25) (xy 0.5 -0.25) (xy 0.5 0.25) (xy -0.5 0.25)
			)
			(stroke
				(width 0.15)
				(type solid)
			)
			(fill no)
			(layer "F.Fab")
		)
		(fp_text user "License: Apache-2.0"
			(at -0.949999 5.169 0)
			(layer "F.Fab")
			(effects
				(font
					(size 0.7 0.7)
					(thickness 0.15)
				)
				(justify right top)
			)
		)
		(fp_text user "Author: Antmicro"
			(at -0.95 4.169 0)
			(layer "F.Fab")
			(effects
				(font
					(size 0.7 0.7)
					(thickness 0.15)
				)
				(justify right top)
			)
		)
		(fp_text user "${REFERENCE}"
			(at -0.95 3.168 0)
			(layer "F.Fab")
			(effects
				(font
					(size 0.7 0.7)
					(thickness 0.15)
				)
				(justify right top)
			)
		)
		(pad "1" smd roundrect
			(at -0.48 0 180)
			(size 0.59 0.64)
			(layers "F.Cu" "F.Mask" "F.Paste")
			(roundrect_rratio 0.25)
			(net 66 "GND")
			(pintype "passive")
		)
		(pad "2" smd roundrect
			(at 0.48 0 180)
			(size 0.59 0.64)
			(layers "F.Cu" "F.Mask" "F.Paste")
			(roundrect_rratio 0.25)
			(net 179 "/PCIe-clock-generator/PCIe_{REF1}_R.CK-")
			(pintype "passive")
		)
	)
	(footprint "antmicro-footprints:R_0402_1005Metric"
		(layer "F.Cu")
		(at 125.332999 152.076998 90)
		(descr "Resistor SMD 0402")
		(tags "resistor SMD 0402")
		(property "Reference" "R8"
			(at -2.523002 0.467001 270)
			(layer "F.SilkS")
			(effects
				(font
					(size 0.7 0.7)
					(thickness 0.15)
				)
				(justify left bottom)
			)
		)
		(property "Value" "R_100k_0402"
			(at -1.011843 1.772046 90)
			(layer "F.Fab")
			(effects
				(font
					(size 0.7 0.7)
					(thickness 0.15)
				)
				(justify left bottom)
			)
		)
		(property "Datasheet" "https://www.bourns.com/docs/product-datasheets/cr.pdf"
			(at 0 0 90)
			(layer "F.Fab")
			(hide yes)
			(effects
				(font
					(size 1.27 1.27)
					(thickness 0.15)
				)
			)
		)
		(property "Description" "SMD Chip Resistor, 100 kohm, ± 1%, 62.5 mW, 0402 [1005 Metric], Thick Film, General Purpose"
			(at 0 0 90)
			(layer "F.Fab")
			(hide yes)
			(effects
				(font
					(size 1.27 1.27)
					(thickness 0.15)
				)
			)
		)
		(property "MPN" "CR0402-FX-1003GLF"
			(at 0 0 90)
			(unlocked yes)
			(layer "F.Fab")
			(hide yes)
			(effects
				(font
					(size 1 1)
					(thickness 0.15)
				)
			)
		)
		(property "Manufacturer" "Bourns"
			(at 0 0 90)
			(unlocked yes)
			(layer "F.Fab")
			(hide yes)
			(effects
				(font
					(size 1 1)
					(thickness 0.15)
				)
			)
		)
		(property "License" "Apache-2.0"
			(at 0 0 90)
			(unlocked yes)
			(layer "F.Fab")
			(hide yes)
			(effects
				(font
					(size 1 1)
					(thickness 0.15)
				)
			)
		)
		(property "Author" "Antmicro"
			(at 0 0 90)
			(unlocked yes)
			(layer "F.Fab")
			(hide yes)
			(effects
				(font
					(size 1 1)
					(thickness 0.15)
				)
			)
		)
		(property "Val" "100k"
			(at 0 0 90)
			(unlocked yes)
			(layer "F.Fab")
			(hide yes)
			(effects
				(font
					(size 1 1)
					(thickness 0.15)
				)
			)
		)
		(property "Tolerance" "1%"
			(at 0 0 90)
			(unlocked yes)
			(layer "F.Fab")
			(hide yes)
			(effects
				(font
					(size 1 1)
					(thickness 0.15)
				)
			)
		)
		(sheetname "/Power/")
		(sheetfile "power.kicad_sch")
		(attr smd)
		(fp_rect
			(start -0.925 -0.47)
			(end 0.925 0.47)
			(stroke
				(width 0.05)
				(type default)
			)
			(fill no)
			(layer "F.CrtYd")
		)
		(fp_rect
			(start -0.5 -0.25)
			(end 0.5 0.25)
			(stroke
				(width 0.15)
				(type solid)
			)
			(fill no)
			(layer "F.Fab")
		)
		(fp_text user "${REFERENCE}"
			(at 0 0 90)
			(layer "F.Fab")
			(effects
				(font
					(size 0.7 0.7)
					(thickness 0.15)
				)
				(justify left bottom)
			)
		)
		(fp_text user "License: Apache-2.0"
			(at -0.949999 5.169 90)
			(layer "F.Fab")
			(effects
				(font
					(size 0.7 0.7)
					(thickness 0.15)
				)
				(justify left bottom)
			)
		)
		(fp_text user "Author: Antmicro"
			(at -0.95 4.169 90)
			(layer "F.Fab")
			(effects
				(font
					(size 0.7 0.7)
					(thickness 0.15)
				)
				(justify left bottom)
			)
		)
		(pad "1" smd roundrect
			(at -0.48 0 90)
			(size 0.59 0.64)
			(layers "F.Cu" "F.Mask" "F.Paste")
			(roundrect_rratio 0.25)
			(net 66 "GND")
			(pintype "passive")
		)
		(pad "2" smd roundrect
			(at 0.48 0 90)
			(size 0.59 0.64)
			(layers "F.Cu" "F.Mask" "F.Paste")
			(roundrect_rratio 0.25)
			(net 185 "/Power/~{PERST_CONN}")
			(pintype "passive")
		)
	)
	(footprint "antmicro-footprints:C_0402_1005Metric"
		(layer "F.Cu")
		(at 140.1 60)
		(descr "Capacitor SMD 0402")
		(tags "capacitor SMD 0402")
		(property "Reference" "C42"
			(at -1 -0.699 0)
			(layer "F.SilkS")
			(effects
				(font
					(size 0.7 0.7)
					(thickness 0.15)
				)
				(justify left bottom)
			)
		)
		(property "Value" "C_100n_0402"
			(at -1.022927 2.155213 0)
			(layer "F.Fab")
			(effects
				(font
					(size 0.7 0.7)
					(thickness 0.15)
				)
				(justify left bottom)
			)
		)
		(property "Datasheet" "https://www.murata.com/products/productdetail?partno=GRM155R61H104KE14%23"
			(at 0 0 0)
			(layer "F.Fab")
			(hide yes)
			(effects
				(font
					(size 1.27 1.27)
					(thickness 0.15)
				)
			)
		)
		(property "Description" "SMD Multilayer Ceramic Capacitor, 0.1 µF, 50 V, 0402 [1005 Metric], ± 10%, X5R, GRM Series"
			(at 0 0 0)
			(layer "F.Fab")
			(hide yes)
			(effects
				(font
					(size 1.27 1.27)
					(thickness 0.15)
				)
			)
		)
		(property "MPN" "GRM155R61H104KE14D"
			(at 0 0 0)
			(unlocked yes)
			(layer "F.Fab")
			(hide yes)
			(effects
				(font
					(size 1 1)
					(thickness 0.15)
				)
			)
		)
		(property "Manufacturer" "Murata"
			(at 0 0 0)
			(unlocked yes)
			(layer "F.Fab")
			(hide yes)
			(effects
				(font
					(size 1 1)
					(thickness 0.15)
				)
			)
		)
		(property "License" "Apache-2.0"
			(at 0 0 0)
			(unlocked yes)
			(layer "F.Fab")
			(hide yes)
			(effects
				(font
					(size 1 1)
					(thickness 0.15)
				)
			)
		)
		(property "Author" "Antmicro"
			(at 0 0 0)
			(unlocked yes)
			(layer "F.Fab")
			(hide yes)
			(effects
				(font
					(size 1 1)
					(thickness 0.15)
				)
			)
		)
		(property "Val" "100n"
			(at 0 0 0)
			(unlocked yes)
			(layer "F.Fab")
			(hide yes)
			(effects
				(font
					(size 1 1)
					(thickness 0.15)
				)
			)
		)
		(property "Voltage" "50V"
			(at 0 0 0)
			(unlocked yes)
			(layer "F.Fab")
			(hide yes)
			(effects
				(font
					(size 1 1)
					(thickness 0.15)
				)
			)
		)
		(property "Dielectric" "X5R"
			(at 0 0 0)
			(unlocked yes)
			(layer "F.Fab")
			(hide yes)
			(effects
				(font
					(size 1 1)
					(thickness 0.15)
				)
			)
		)
		(sheetname "/PCIe-clock-generator/")
		(sheetfile "pcie-clock-generator.kicad_sch")
		(attr smd exclude_from_bom dnp)
		(fp_rect
			(start -0.925 -0.47)
			(end 0.925 0.47)
			(stroke
				(width 0.05)
				(type default)
			)
			(fill no)
			(layer "F.CrtYd")
		)
		(fp_line
			(start -0.494 -0.25)
			(end 0.504 -0.25)
			(stroke
				(width 0.15)
				(type solid)
			)
			(layer "F.Fab")
		)
		(fp_line
			(start -0.494 0.248)
			(end -0.494 -0.25)
			(stroke
				(width 0.15)
				(type solid)
			)
			(layer "F.Fab")
		)
		(fp_line
			(start 0.504 -0.25)
			(end 0.504 0.248)
			(stroke
				(width 0.15)
				(type solid)
			)
			(layer "F.Fab")
		)
		(fp_line
			(start 0.504 0.248)
			(end -0.494 0.248)
			(stroke
				(width 0.15)
				(type solid)
			)
			(layer "F.Fab")
		)
		(fp_text user "License: Apache-2.0"
			(at -0.939 5.799 0)
			(layer "F.Fab")
			(effects
				(font
					(size 0.7 0.7)
					(thickness 0.15)
				)
				(justify left bottom)
			)
		)
		(fp_text user "${REFERENCE}"
			(at -0.939 4.599 0)
			(layer "F.Fab")
			(effects
				(font
					(size 0.7 0.7)
					(thickness 0.15)
				)
				(justify left bottom)
			)
		)
		(fp_text user "Author: Antmicro"
			(at -0.939 3.399 0)
			(layer "F.Fab")
			(effects
				(font
					(size 0.7 0.7)
					(thickness 0.15)
				)
				(justify left bottom)
			)
		)
		(pad "1" smd roundrect
			(at -0.48 0)
			(size 0.59 0.64)
			(layers "F.Cu" "F.Mask" "F.Paste")
			(roundrect_rratio 0.25)
			(net 66 "GND")
			(pintype "passive")
		)
		(pad "2" smd roundrect
			(at 0.48 0)
			(size 0.59 0.64)
			(layers "F.Cu" "F.Mask" "F.Paste")
			(roundrect_rratio 0.25)
			(net 134 "+3V3")
			(pintype "passive")
		)
	)
	(footprint "antmicro-footprints:C_0402_1005Metric"
		(layer "F.Cu")
		(at 146.561999 55.001)
		(descr "Capacitor SMD 0402")
		(tags "capacitor SMD 0402")
		(property "Reference" "C11"
			(at -3.161999 2.999 180)
			(layer "F.SilkS")
			(effects
				(font
					(size 0.7 0.7)
					(thickness 0.15)
				)
				(justify left bottom)
			)
		)
		(property "Value" "C_1u_25V_0402"
			(at -1.022927 2.155213 0)
			(layer "F.Fab")
			(effects
				(font
					(size 0.7 0.7)
					(thickness 0.15)
				)
				(justify left bottom)
			)
		)
		(property "Datasheet" "https://www.murata.com/products/productdetail?partno=GRM155R61E105KE11%23"
			(at 0 0 0)
			(layer "F.Fab")
			(hide yes)
			(effects
				(font
					(size 1.27 1.27)
					(thickness 0.15)
				)
			)
		)
		(property "Description" "SMD Multilayer Ceramic Capacitor, 1 µF, 25 V, 0402 [1005 Metric], ± 10%, X5R, GRM Series"
			(at 0 0 0)
			(layer "F.Fab")
			(hide yes)
			(effects
				(font
					(size 1.27 1.27)
					(thickness 0.15)
				)
			)
		)
		(property "MPN" "GRM155R61E105KE11J"
			(at 0 0 0)
			(unlocked yes)
			(layer "F.Fab")
			(hide yes)
			(effects
				(font
					(size 1 1)
					(thickness 0.15)
				)
			)
		)
		(property "Val" "1u"
			(at 0 0 0)
			(unlocked yes)
			(layer "F.Fab")
			(hide yes)
			(effects
				(font
					(size 1 1)
					(thickness 0.15)
				)
			)
		)
		(property "Voltage" "25V"
			(at 0 0 0)
			(unlocked yes)
			(layer "F.Fab")
			(hide yes)
			(effects
				(font
					(size 1 1)
					(thickness 0.15)
				)
			)
		)
		(property "Dielectric" "X5R"
			(at 0 0 0)
			(unlocked yes)
			(layer "F.Fab")
			(hide yes)
			(effects
				(font
					(size 1 1)
					(thickness 0.15)
				)
			)
		)
		(property "Manufacturer" "Murata"
			(at 0 0 0)
			(unlocked yes)
			(layer "F.Fab")
			(hide yes)
			(effects
				(font
					(size 1 1)
					(thickness 0.15)
				)
			)
		)
		(property "License" "Apache-2.0"
			(at 0 0 0)
			(unlocked yes)
			(layer "F.Fab")
			(hide yes)
			(effects
				(font
					(size 1 1)
					(thickness 0.15)
				)
			)
		)
		(property "Author" "Antmicro"
			(at 0 0 0)
			(unlocked yes)
			(layer "F.Fab")
			(hide yes)
			(effects
				(font
					(size 1 1)
					(thickness 0.15)
				)
			)
		)
		(sheetname "/USB-PD/")
		(sheetfile "usb-pd.kicad_sch")
		(attr smd)
		(fp_rect
			(start -0.925 -0.47)
			(end 0.925 0.47)
			(stroke
				(width 0.05)
				(type default)
			)
			(fill no)
			(layer "F.CrtYd")
		)
		(fp_line
			(start -0.494 -0.25)
			(end 0.504 -0.25)
			(stroke
				(width 0.15)
				(type solid)
			)
			(layer "F.Fab")
		)
		(fp_line
			(start -0.494 0.248)
			(end -0.494 -0.25)
			(stroke
				(width 0.15)
				(type solid)
			)
			(layer "F.Fab")
		)
		(fp_line
			(start 0.504 -0.25)
			(end 0.504 0.248)
			(stroke
				(width 0.15)
				(type solid)
			)
			(layer "F.Fab")
		)
		(fp_line
			(start 0.504 0.248)
			(end -0.494 0.248)
			(stroke
				(width 0.15)
				(type solid)
			)
			(layer "F.Fab")
		)
		(fp_text user "License: Apache-2.0"
			(at -0.939 5.799 0)
			(layer "F.Fab")
			(effects
				(font
					(size 0.7 0.7)
					(thickness 0.15)
				)
				(justify left bottom)
			)
		)
		(fp_text user "Author: Antmicro"
			(at -0.939 3.399 0)
			(layer "F.Fab")
			(effects
				(font
					(size 0.7 0.7)
					(thickness 0.15)
				)
				(justify left bottom)
			)
		)
		(fp_text user "${REFERENCE}"
			(at 0 0 0)
			(layer "F.Fab")
			(effects
				(font
					(size 0.7 0.7)
					(thickness 0.15)
				)
				(justify left bottom)
			)
		)
		(pad "1" smd roundrect
			(at -0.48 0)
			(size 0.59 0.64)
			(layers "F.Cu" "F.Mask" "F.Paste")
			(roundrect_rratio 0.25)
			(net 66 "GND")
			(pintype "passive")
		)
		(pad "2" smd roundrect
			(at 0.48 0)
			(size 0.59 0.64)
			(layers "F.Cu" "F.Mask" "F.Paste")
			(roundrect_rratio 0.25)
			(net 114 "/USB-PD/VCCD_1V8")
			(pintype "passive")
		)
	)
	(footprint "antmicro-footprints:R_0402_1005Metric"
		(layer "F.Cu")
		(at 138.899999 68.05 90)
		(descr "Resistor SMD 0402")
		(tags "resistor SMD 0402")
		(property "Reference" "R35"
			(at 1.299999 -5.649499 90)
			(layer "F.SilkS")
			(effects
				(font
					(size 0.7 0.7)
					(thickness 0.15)
				)
				(justify right top)
			)
		)
		(property "Value" "R_68k_0402"
			(at -1.011843 1.772046 90)
			(layer "F.Fab")
			(effects
				(font
					(size 0.7 0.7)
					(thickness 0.15)
				)
				(justify left bottom)
			)
		)
		(property "Datasheet" "https://www.bourns.com/docs/product-datasheets/cr.pdf"
			(at 0 0 90)
			(layer "F.Fab")
			(hide yes)
			(effects
				(font
					(size 1.27 1.27)
					(thickness 0.15)
				)
			)
		)
		(property "Description" "SMD Chip Resistor"
			(at 0 0 90)
			(layer "F.Fab")
			(hide yes)
			(effects
				(font
					(size 1.27 1.27)
					(thickness 0.15)
				)
			)
		)
		(property "MPN" "CR0402-FX-6802GLF"
			(at 0 0 90)
			(unlocked yes)
			(layer "F.Fab")
			(hide yes)
			(effects
				(font
					(size 1 1)
					(thickness 0.15)
				)
			)
		)
		(property "Manufacturer" "Bourns"
			(at 0 0 90)
			(unlocked yes)
			(layer "F.Fab")
			(hide yes)
			(effects
				(font
					(size 1 1)
					(thickness 0.15)
				)
			)
		)
		(property "License" "Apache-2.0"
			(at 0 0 90)
			(unlocked yes)
			(layer "F.Fab")
			(hide yes)
			(effects
				(font
					(size 1 1)
					(thickness 0.15)
				)
			)
		)
		(property "Author" "Antmicro"
			(at 0 0 90)
			(unlocked yes)
			(layer "F.Fab")
			(hide yes)
			(effects
				(font
					(size 1 1)
					(thickness 0.15)
				)
			)
		)
		(property "Val" "68k"
			(at 0 0 90)
			(unlocked yes)
			(layer "F.Fab")
			(hide yes)
			(effects
				(font
					(size 1 1)
					(thickness 0.15)
				)
			)
		)
		(property "Tolerance" "1%"
			(at 0 0 90)
			(unlocked yes)
			(layer "F.Fab")
			(hide yes)
			(effects
				(font
					(size 1 1)
					(thickness 0.15)
				)
			)
		)
		(sheetname "/USB-PD/")
		(sheetfile "usb-pd.kicad_sch")
		(attr smd)
		(fp_rect
			(start -0.925 -0.47)
			(end 0.925 0.47)
			(stroke
				(width 0.05)
				(type default)
			)
			(fill no)
			(layer "F.CrtYd")
		)
		(fp_rect
			(start -0.5 -0.25)
			(end 0.5 0.25)
			(stroke
				(width 0.15)
				(type solid)
			)
			(fill no)
			(layer "F.Fab")
		)
		(fp_text user "Author: Antmicro"
			(at -0.95 4.169 90)
			(layer "F.Fab")
			(effects
				(font
					(size 0.7 0.7)
					(thickness 0.15)
				)
				(justify left bottom)
			)
		)
		(fp_text user "${REFERENCE}"
			(at 0 0 270)
			(layer "F.Fab")
			(effects
				(font
					(size 0.7 0.7)
					(thickness 0.15)
				)
				(justify right top)
			)
		)
		(fp_text user "License: Apache-2.0"
			(at -0.949999 5.169 90)
			(layer "F.Fab")
			(effects
				(font
					(size 0.7 0.7)
					(thickness 0.15)
				)
				(justify left bottom)
			)
		)
		(pad "1" smd roundrect
			(at -0.48 0 90)
			(size 0.59 0.64)
			(layers "F.Cu" "F.Mask" "F.Paste")
			(roundrect_rratio 0.25)
			(net 174 "Net-(Q4-D)")
			(pintype "passive")
		)
		(pad "2" smd roundrect
			(at 0.48 0 90)
			(size 0.59 0.64)
			(layers "F.Cu" "F.Mask" "F.Paste")
			(roundrect_rratio 0.25)
			(net 165 "Net-(D4-C_{G})")
			(pintype "passive")
		)
	)
	(footprint "antmicro-footprints:R_0402_1005Metric"
		(layer "F.Cu")
		(at 147.737 57.376001 90)
		(descr "Resistor SMD 0402")
		(tags "resistor SMD 0402")
		(property "Reference" "R17"
			(at -3.273999 0.439001 90)
			(layer "F.SilkS")
			(effects
				(font
					(size 0.7 0.7)
					(thickness 0.15)
				)
				(justify left bottom)
			)
		)
		(property "Value" "R_1k_0402"
			(at -1.011843 1.772046 90)
			(layer "F.Fab")
			(effects
				(font
					(size 0.7 0.7)
					(thickness 0.15)
				)
				(justify left bottom)
			)
		)
		(property "Datasheet" "https://www.bourns.com/docs/product-datasheets/cr.pdf"
			(at 0 0 90)
			(layer "F.Fab")
			(hide yes)
			(effects
				(font
					(size 1.27 1.27)
					(thickness 0.15)
				)
			)
		)
		(property "Description" "SMD Chip Resistor, 1 kohm, ± 1%, 63 mW, 0402 [1005 Metric], Thick Film, General Purpose"
			(at 0 0 90)
			(layer "F.Fab")
			(hide yes)
			(effects
				(font
					(size 1.27 1.27)
					(thickness 0.15)
				)
			)
		)
		(property "MPN" "CR0402-FX-1001GLF"
			(at 0 0 90)
			(unlocked yes)
			(layer "F.Fab")
			(hide yes)
			(effects
				(font
					(size 1 1)
					(thickness 0.15)
				)
			)
		)
		(property "Manufacturer" "Bourns"
			(at 0 0 90)
			(unlocked yes)
			(layer "F.Fab")
			(hide yes)
			(effects
				(font
					(size 1 1)
					(thickness 0.15)
				)
			)
		)
		(property "License" "Apache-2.0"
			(at 0 0 90)
			(unlocked yes)
			(layer "F.Fab")
			(hide yes)
			(effects
				(font
					(size 1 1)
					(thickness 0.15)
				)
			)
		)
		(property "Author" "Antmicro"
			(at 0 0 90)
			(unlocked yes)
			(layer "F.Fab")
			(hide yes)
			(effects
				(font
					(size 1 1)
					(thickness 0.15)
				)
			)
		)
		(property "Val" "1k"
			(at 0 0 90)
			(unlocked yes)
			(layer "F.Fab")
			(hide yes)
			(effects
				(font
					(size 1 1)
					(thickness 0.15)
				)
			)
		)
		(property "Tolerance" "1%"
			(at 0 0 90)
			(unlocked yes)
			(layer "F.Fab")
			(hide yes)
			(effects
				(font
					(size 1 1)
					(thickness 0.15)
				)
			)
		)
		(sheetname "/USB-PD/")
		(sheetfile "usb-pd.kicad_sch")
		(attr smd exclude_from_bom dnp)
		(fp_rect
			(start -0.925 -0.47)
			(end 0.925 0.47)
			(stroke
				(width 0.05)
				(type default)
			)
			(fill no)
			(layer "F.CrtYd")
		)
		(fp_rect
			(start -0.5 -0.25)
			(end 0.5 0.25)
			(stroke
				(width 0.15)
				(type solid)
			)
			(fill no)
			(layer "F.Fab")
		)
		(fp_text user "License: Apache-2.0"
			(at -0.949999 5.169 90)
			(layer "F.Fab")
			(effects
				(font
					(size 0.7 0.7)
					(thickness 0.15)
				)
				(justify left bottom)
			)
		)
		(fp_text user "${REFERENCE}"
			(at 0 0 90)
			(layer "F.Fab")
			(effects
				(font
					(size 0.7 0.7)
					(thickness 0.15)
				)
				(justify left bottom)
			)
		)
		(fp_text user "Author: Antmicro"
			(at -0.95 4.169 90)
			(layer "F.Fab")
			(effects
				(font
					(size 0.7 0.7)
					(thickness 0.15)
				)
				(justify left bottom)
			)
		)
		(pad "1" smd roundrect
			(at -0.48 0 90)
			(size 0.59 0.64)
			(layers "F.Cu" "F.Mask" "F.Paste")
			(roundrect_rratio 0.25)
			(net 66 "GND")
			(pintype "passive")
		)
		(pad "2" smd roundrect
			(at 0.48 0 90)
			(size 0.59 0.64)
			(layers "F.Cu" "F.Mask" "F.Paste")
			(roundrect_rratio 0.25)
			(net 133 "/USB-PD/VBUS_MIN")
			(pintype "passive")
		)
	)
	(footprint "antmicro-footprints:R_0402_1005Metric"
		(layer "F.Cu")
		(at 154.312 52.001)
		(descr "Resistor SMD 0402")
		(tags "resistor SMD 0402")
		(property "Reference" "R19"
			(at 1.088 0.399 180)
			(layer "F.SilkS")
			(effects
				(font
					(size 0.7 0.7)
					(thickness 0.15)
				)
				(justify left bottom)
			)
		)
		(property "Value" "R_2k_0402"
			(at -1.011843 1.772046 0)
			(layer "F.Fab")
			(effects
				(font
					(size 0.7 0.7)
					(thickness 0.15)
				)
				(justify left bottom)
			)
		)
		(property "Datasheet" "https://www.bourns.com/docs/product-datasheets/cr.pdf"
			(at 0 0 0)
			(layer "F.Fab")
			(hide yes)
			(effects
				(font
					(size 1.27 1.27)
					(thickness 0.15)
				)
			)
		)
		(property "Description" "SMD Chip Resistor, 2 kohm, ± 1%, 62.5 mW, 0402 [1005 Metric], Thick Film, General Purpose"
			(at 0 0 0)
			(layer "F.Fab")
			(hide yes)
			(effects
				(font
					(size 1.27 1.27)
					(thickness 0.15)
				)
			)
		)
		(property "MPN" "CR0402-FX-2001GLF"
			(at 0 0 0)
			(unlocked yes)
			(layer "F.Fab")
			(hide yes)
			(effects
				(font
					(size 1 1)
					(thickness 0.15)
				)
			)
		)
		(property "Manufacturer" "Bourns"
			(at 0 0 0)
			(unlocked yes)
			(layer "F.Fab")
			(hide yes)
			(effects
				(font
					(size 1 1)
					(thickness 0.15)
				)
			)
		)
		(property "License" "Apache-2.0"
			(at 0 0 0)
			(unlocked yes)
			(layer "F.Fab")
			(hide yes)
			(effects
				(font
					(size 1 1)
					(thickness 0.15)
				)
			)
		)
		(property "Author" "Antmicro"
			(at 0 0 0)
			(unlocked yes)
			(layer "F.Fab")
			(hide yes)
			(effects
				(font
					(size 1 1)
					(thickness 0.15)
				)
			)
		)
		(property "Val" "2k"
			(at 0 0 0)
			(unlocked yes)
			(layer "F.Fab")
			(hide yes)
			(effects
				(font
					(size 1 1)
					(thickness 0.15)
				)
			)
		)
		(property "Tolerance" "1%"
			(at 0 0 0)
			(unlocked yes)
			(layer "F.Fab")
			(hide yes)
			(effects
				(font
					(size 1 1)
					(thickness 0.15)
				)
			)
		)
		(sheetname "/USB-PD/")
		(sheetfile "usb-pd.kicad_sch")
		(attr smd)
		(fp_rect
			(start -0.925 -0.47)
			(end 0.925 0.47)
			(stroke
				(width 0.05)
				(type default)
			)
			(fill no)
			(layer "F.CrtYd")
		)
		(fp_rect
			(start -0.5 -0.25)
			(end 0.5 0.25)
			(stroke
				(width 0.15)
				(type solid)
			)
			(fill no)
			(layer "F.Fab")
		)
		(fp_text user "Author: Antmicro"
			(at -0.95 4.169 0)
			(layer "F.Fab")
			(effects
				(font
					(size 0.7 0.7)
					(thickness 0.15)
				)
				(justify left bottom)
			)
		)
		(fp_text user "${REFERENCE}"
			(at 0 0 0)
			(layer "F.Fab")
			(effects
				(font
					(size 0.7 0.7)
					(thickness 0.15)
				)
				(justify left bottom)
			)
		)
		(fp_text user "License: Apache-2.0"
			(at -0.949999 5.169 0)
			(layer "F.Fab")
			(effects
				(font
					(size 0.7 0.7)
					(thickness 0.15)
				)
				(justify left bottom)
			)
		)
		(pad "1" smd roundrect
			(at -0.48 0)
			(size 0.59 0.64)
			(layers "F.Cu" "F.Mask" "F.Paste")
			(roundrect_rratio 0.25)
			(net 141 "/USB-PD/SDA")
			(pintype "passive")
		)
		(pad "2" smd roundrect
			(at 0.48 0)
			(size 0.59 0.64)
			(layers "F.Cu" "F.Mask" "F.Paste")
			(roundrect_rratio 0.25)
			(net 117 "/USB-PD/VDDD_3V3")
			(pintype "passive")
		)
	)
	(footprint "antmicro-footprints:MP_Pad6mm_Drill3.2mm"
		(layer "F.Cu")
		(at 109 131 -90)
		(property "Reference" "MP5"
			(at 0 0 90)
			(layer "F.SilkS")
			(hide yes)
			(effects
				(font
					(size 0.7 0.7)
					(thickness 0.15)
				)
				(justify right top)
			)
		)
		(property "Value" "MP_Pad6mm_Drill3.2mm"
			(at 0 3.899999 90)
			(layer "F.Fab")
			(effects
				(font
					(size 0.7 0.7)
					(thickness 0.15)
				)
				(justify right top)
			)
		)
		(property "Description" "Mechanical part"
			(at 0 0 90)
			(layer "F.Fab")
			(hide yes)
			(effects
				(font
					(size 1.27 1.27)
					(thickness 0.15)
				)
			)
		)
		(property "Author" "Antmicro"
			(at 0 0 270)
			(unlocked yes)
			(layer "F.Fab")
			(hide yes)
			(effects
				(font
					(size 1 1)
					(thickness 0.15)
				)
			)
		)
		(property "License" "Apache-2.0"
			(at 0 0 270)
			(unlocked yes)
			(layer "F.Fab")
			(hide yes)
			(effects
				(font
					(size 1 1)
					(thickness 0.15)
				)
			)
		)
		(sheetname "/")
		(sheetfile "oculink-to-pcie-adapter.kicad_sch")
		(attr board_only exclude_from_pos_files exclude_from_bom)
		(fp_circle
			(center 0 0)
			(end 3.25 0)
			(stroke
				(width 0.05)
				(type default)
			)
			(fill no)
			(layer "F.CrtYd")
		)
		(fp_text user "${REFERENCE}"
			(at 0 0 90)
			(layer "F.Fab")
			(effects
				(font
					(size 0.7 0.7)
					(thickness 0.15)
				)
				(justify right top)
			)
		)
		(fp_text user "License: Apache-2.0"
			(at -0.178 8.425001 90)
			(layer "F.Fab")
			(effects
				(font
					(size 0.7 0.7)
					(thickness 0.15)
				)
				(justify right top)
			)
		)
		(fp_text user "Author: Antmicro"
			(at -0.178001 7.225 90)
			(layer "F.Fab")
			(effects
				(font
					(size 0.7 0.7)
					(thickness 0.15)
				)
				(justify right top)
			)
		)
		(pad "1" thru_hole circle
			(at 0 0 270)
			(size 6 6)
			(drill 3.2)
			(layers "*.Cu" "*.Mask")
			(remove_unused_layers no)
			(net 66 "GND")
			(pintype "passive")
		)
	)
	(footprint "antmicro-footprints:VQFN-14-1EP_3.2x2.5mm_P0.5mm_Layout4x3"
		(layer "F.Cu")
		(at 140.3 63)
		(property "Reference" "U7"
			(at 0.8 -2.4 0)
			(unlocked yes)
			(layer "F.SilkS")
			(effects
				(font
					(size 0.7 0.7)
					(thickness 0.15)
				)
				(justify left bottom)
			)
		)
		(property "Value" "DSC557-0343FI1"
			(at 0 3.1 0)
			(unlocked yes)
			(layer "F.Fab")
			(effects
				(font
					(size 0.7 0.7)
					(thickness 0.15)
				)
				(justify left bottom)
			)
		)
		(property "Datasheet" "https://ww1.microchip.com/downloads/aemDocuments/documents/TCG/ProductDocuments/DataSheets/DSC557-03-04-05-Multiple-Output-MEMS-PCIe-Gen1-2-3-4-Clock-Generators-DS20006691.pdf"
			(at 0 0 0)
			(layer "F.Fab")
			(hide yes)
			(effects
				(font
					(size 1.27 1.27)
					(thickness 0.15)
				)
			)
		)
		(property "Description" "Two output PCIe Clock Generator"
			(at 0 0 0)
			(layer "F.Fab")
			(hide yes)
			(effects
				(font
					(size 1.27 1.27)
					(thickness 0.15)
				)
			)
		)
		(property "Manufacturer" "Microchip Technology"
			(at 0 0 0)
			(unlocked yes)
			(layer "F.Fab")
			(hide yes)
			(effects
				(font
					(size 1 1)
					(thickness 0.15)
				)
			)
		)
		(property "MPN" "DSC557-0343FI1"
			(at 0 0 0)
			(unlocked yes)
			(layer "F.Fab")
			(hide yes)
			(effects
				(font
					(size 1 1)
					(thickness 0.15)
				)
			)
		)
		(property "Val" "100 MHz"
			(at 0 0 0)
			(unlocked yes)
			(layer "F.Fab")
			(hide yes)
			(effects
				(font
					(size 1 1)
					(thickness 0.15)
				)
			)
		)
		(property "Author" "Antmicro"
			(at 0 0 0)
			(unlocked yes)
			(layer "F.Fab")
			(hide yes)
			(effects
				(font
					(size 1 1)
					(thickness 0.15)
				)
			)
		)
		(property "License" "Apache-2.0"
			(at 0 0 0)
			(unlocked yes)
			(layer "F.Fab")
			(hide yes)
			(effects
				(font
					(size 1 1)
					(thickness 0.15)
				)
			)
		)
		(sheetname "/PCIe-clock-generator/")
		(sheetfile "pcie-clock-generator.kicad_sch")
		(attr smd exclude_from_bom dnp)
		(fp_circle
			(center -1.5 -1.075)
			(end -1.45 -1.075)
			(stroke
				(width 0.15)
				(type solid)
			)
			(fill yes)
			(layer "F.SilkS")
		)
		(fp_rect
			(start -1.746 -2.101)
			(end 1.745 2.1)
			(stroke
				(width 0.05)
				(type solid)
			)
			(fill no)
			(layer "F.CrtYd")
		)
		(fp_line
			(start -1.266 -1.067)
			(end -0.758 -1.625)
			(stroke
				(width 0.15)
				(type solid)
			)
			(layer "F.Fab")
		)
		(fp_line
			(start -1.266 1.677)
			(end -1.266 -1.067)
			(stroke
				(width 0.15)
				(type solid)
			)
			(layer "F.Fab")
		)
		(fp_line
			(start -1.266 1.677)
			(end 1.269 1.677)
			(stroke
				(width 0.15)
				(type solid)
			)
			(layer "F.Fab")
		)
		(fp_line
			(start 1.269 -1.625)
			(end -0.758 -1.625)
			(stroke
				(width 0.15)
				(type solid)
			)
			(layer "F.Fab")
		)
		(fp_line
			(start 1.269 1.677)
			(end 1.269 -1.625)
			(stroke
				(width 0.15)
				(type solid)
			)
			(layer "F.Fab")
		)
		(fp_text user "${REFERENCE}"
			(at -1.746 5.099 0)
			(unlocked yes)
			(layer "F.Fab")
			(effects
				(font
					(size 0.7 0.7)
					(thickness 0.15)
				)
				(justify left bottom)
			)
		)
		(fp_text user "Author: Antmicro"
			(at -1.746 6.299 0)
			(layer "F.Fab")
			(effects
				(font
					(size 0.7 0.7)
					(thickness 0.15)
				)
				(justify left bottom)
			)
		)
		(fp_text user "License: Apache-2.0"
			(at -1.746 7.499 0)
			(layer "F.Fab")
			(effects
				(font
					(size 0.7 0.7)
					(thickness 0.15)
				)
				(justify left bottom)
			)
		)
		(pad "1" smd rect
			(at -1.3 -0.762 90)
			(size 0.3 0.7)
			(layers "F.Cu" "F.Mask" "F.Paste")
			(net 134 "+3V3")
			(pinfunction "OE")
			(pintype "input")
		)
		(pad "2" smd rect
			(at -1.3 -0.25 90)
			(size 0.3 0.7)
			(layers "F.Cu" "F.Mask" "F.Paste")
			(net 195 "unconnected-(U7-NC-Pad2)")
			(pinfunction "NC")
			(pintype "no_connect")
		)
		(pad "3" smd rect
			(at -1.3 0.25 90)
			(size 0.3 0.7)
			(layers "F.Cu" "F.Mask" "F.Paste")
			(net 189 "unconnected-(U7-NC-Pad3)")
			(pinfunction "NC")
			(pintype "no_connect")
		)
		(pad "4" smd rect
			(at -1.3 0.75 90)
			(size 0.3 0.7)
			(layers "F.Cu" "F.Mask" "F.Paste")
			(net 66 "GND")
			(pinfunction "VSS")
			(pintype "power_in")
		)
		(pad "5" smd rect
			(at -0.5 1.65)
			(size 0.3 0.7)
			(layers "F.Cu" "F.Mask" "F.Paste")
			(net 190 "unconnected-(U7-NC-Pad5)")
			(pinfunction "NC")
			(pintype "no_connect")
		)
		(pad "6" smd rect
			(at 0 1.65)
			(size 0.3 0.7)
			(layers "F.Cu" "F.Mask" "F.Paste")
			(net 192 "unconnected-(U7-NC-Pad6)")
			(pinfunction "NC")
			(pintype "no_connect")
		)
		(pad "7" smd rect
			(at 0.5 1.65)
			(size 0.3 0.7)
			(layers "F.Cu" "F.Mask" "F.Paste")
			(net 196 "unconnected-(U7-NC-Pad7)")
			(pinfunction "NC")
			(pintype "no_connect")
		)
		(pad "8" smd rect
			(at 1.3 0.75 270)
			(size 0.3 0.7)
			(layers "F.Cu" "F.Mask" "F.Paste")
			(net 197 "/PCIe-clock-generator/PCIe_{REF1}_R2.CK+")
			(pinfunction "CLK1+")
			(pintype "output")
		)
		(pad "9" smd rect
			(at 1.3 0.25 270)
			(size 0.3 0.7)
			(layers "F.Cu" "F.Mask" "F.Paste")
			(net 198 "/PCIe-clock-generator/PCIe_{REF1}_R2.CK-")
			(pinfunction "CLK1-")
			(pintype "output")
		)
		(pad "10" smd rect
			(at 1.3 -0.25 270)
			(size 0.3 0.7)
			(layers "F.Cu" "F.Mask" "F.Paste")
			(net 194 "unconnected-(U7-CLK0--Pad10)")
			(pinfunction "CLK0-")
			(pintype "output+no_connect")
		)
		(pad "11" smd rect
			(at 1.3 -0.75 270)
			(size 0.3 0.7)
			(layers "F.Cu" "F.Mask" "F.Paste")
			(net 191 "unconnected-(U7-CLK0+-Pad11)")
			(pinfunction "CLK0+")
			(pintype "output+no_connect")
		)
		(pad "12" smd rect
			(at 0.5 -1.65 180)
			(size 0.3 0.7)
			(layers "F.Cu" "F.Mask" "F.Paste")
			(net 134 "+3V3")
			(pinfunction "VDD1")
			(pintype "power_in")
		)
		(pad "13" smd rect
			(at 0 -1.65 180)
			(size 0.3 0.7)
			(layers "F.Cu" "F.Mask" "F.Paste")
			(net 134 "+3V3")
			(pinfunction "VDD0")
			(pintype "power_in")
		)
		(pad "14" smd rect
			(at -0.5 -1.65 180)
			(size 0.3 0.7)
			(layers "F.Cu" "F.Mask" "F.Paste")
			(net 193 "unconnected-(U7-NC-Pad14)")
			(pinfunction "NC")
			(pintype "no_connect")
		)
		(pad "15" smd roundrect
			(at 0.003 0 90)
			(size 2.1 1.4)
			(layers "F.Cu" "F.Mask" "F.Paste")
			(roundrect_rratio 0)
			(chamfer_ratio 0.2)
			(chamfer top_right)
			(net 66 "GND")
			(pinfunction "EPAD")
			(pintype "passive")
		)
	)
	(footprint "antmicro-footprints:SC70-3"
		(layer "F.Cu")
		(at 144 41 -90)
		(property "Reference" "D6"
			(at -0.4 1.4 0)
			(layer "F.SilkS")
			(effects
				(font
					(size 0.7 0.7)
					(thickness 0.15)
				)
				(justify right top)
			)
		)
		(property "Value" "TPD2E2U06_SC70"
			(at 0 2.300001 90)
			(layer "F.Fab")
			(effects
				(font
					(size 0.7 0.7)
					(thickness 0.15)
				)
				(justify right top)
			)
		)
		(property "Datasheet" "https://www.ti.com/lit/ds/symlink/tpd2e2u06.pdf?ts=1706006131823&ref_url=https%253A%252F%252Fwww.ti.com%252Finterface%252Fdiodes%252Fesd-protection-diodes%252Fproducts.html"
			(at 0 0 90)
			(layer "F.Fab")
			(hide yes)
			(effects
				(font
					(size 1.27 1.27)
					(thickness 0.15)
				)
			)
		)
		(property "Description" "TVS diode array, 15 kV, SC70, 5.5V, 1.5 pF"
			(at 0 0 90)
			(layer "F.Fab")
			(hide yes)
			(effects
				(font
					(size 1.27 1.27)
					(thickness 0.15)
				)
			)
		)
		(property "MPN" "TPD2E2U06DCKR"
			(at 0 0 270)
			(unlocked yes)
			(layer "F.Fab")
			(hide yes)
			(effects
				(font
					(size 1 1)
					(thickness 0.15)
				)
			)
		)
		(property "Manufacturer" "Texas Instruments"
			(at 0 0 270)
			(unlocked yes)
			(layer "F.Fab")
			(hide yes)
			(effects
				(font
					(size 1 1)
					(thickness 0.15)
				)
			)
		)
		(property "Author" "Antmicro"
			(at 0 0 270)
			(unlocked yes)
			(layer "F.Fab")
			(hide yes)
			(effects
				(font
					(size 1 1)
					(thickness 0.15)
				)
			)
		)
		(property "License" "Apache-2.0"
			(at 0 0 270)
			(unlocked yes)
			(layer "F.Fab")
			(hide yes)
			(effects
				(font
					(size 1 1)
					(thickness 0.15)
				)
			)
		)
		(sheetname "/USB-PD/")
		(sheetfile "usb-pd.kicad_sch")
		(attr smd)
		(fp_line
			(start -0.3 1)
			(end 0.627 1.001)
			(stroke
				(width 0.15)
				(type solid)
			)
			(layer "F.SilkS")
		)
		(fp_line
			(start 0.627 0.6)
			(end 0.627 1.001)
			(stroke
				(width 0.15)
				(type solid)
			)
			(layer "F.SilkS")
		)
		(fp_line
			(start 0.627 -0.6)
			(end 0.627 -0.999)
			(stroke
				(width 0.15)
				(type solid)
			)
			(layer "F.SilkS")
		)
		(fp_line
			(start -0.3 -1)
			(end 0.627 -0.999)
			(stroke
				(width 0.15)
				(type solid)
			)
			(layer "F.SilkS")
		)
		(fp_line
			(start -0.9 1.3)
			(end -0.9 1)
			(stroke
				(width 0.05)
				(type solid)
			)
			(layer "F.CrtYd")
		)
		(fp_line
			(start 0.9 1.3)
			(end -0.9 1.3)
			(stroke
				(width 0.05)
				(type solid)
			)
			(layer "F.CrtYd")
		)
		(fp_line
			(start -1.4 1)
			(end -1.4 -1)
			(stroke
				(width 0.05)
				(type solid)
			)
			(layer "F.CrtYd")
		)
		(fp_line
			(start -0.9 1)
			(end -1.4 1)
			(stroke
				(width 0.05)
				(type solid)
			)
			(layer "F.CrtYd")
		)
		(fp_line
			(start 0.9 0.4)
			(end 0.9 1.3)
			(stroke
				(width 0.05)
				(type solid)
			)
			(layer "F.CrtYd")
		)
		(fp_line
			(start 1.4 0.4)
			(end 0.9 0.4)
			(stroke
				(width 0.05)
				(type solid)
			)
			(layer "F.CrtYd")
		)
		(fp_line
			(start 0.9 -0.4)
			(end 1.4 -0.4)
			(stroke
				(width 0.05)
				(type solid)
			)
			(layer "F.CrtYd")
		)
		(fp_line
			(start 1.4 -0.4)
			(end 1.4 0.4)
			(stroke
				(width 0.05)
				(type solid)
			)
			(layer "F.CrtYd")
		)
		(fp_line
			(start -0.9 -1)
			(end -1.4 -1)
			(stroke
				(width 0.05)
				(type solid)
			)
			(layer "F.CrtYd")
		)
		(fp_line
			(start -0.9 -1.3)
			(end -0.9 -1)
			(stroke
				(width 0.05)
				(type solid)
			)
			(layer "F.CrtYd")
		)
		(fp_line
			(start -0.9 -1.3)
			(end 0.9 -1.3)
			(stroke
				(width 0.05)
				(type solid)
			)
			(layer "F.CrtYd")
		)
		(fp_line
			(start 0.9 -1.3)
			(end 0.9 -0.4)
			(stroke
				(width 0.05)
				(type solid)
			)
			(layer "F.CrtYd")
		)
		(fp_rect
			(start -0.623 -0.999)
			(end 0.627 1.001)
			(stroke
				(width 0.15)
				(type solid)
			)
			(fill no)
			(layer "F.Fab")
		)
		(fp_text user "License: Apache-2.0"
			(at -1.45 6.782 90)
			(layer "F.Fab")
			(effects
				(font
					(size 0.7 0.7)
					(thickness 0.15)
				)
				(justify right top)
			)
		)
		(fp_text user "Author: Antmicro"
			(at -1.45 5.782 90)
			(layer "F.Fab")
			(effects
				(font
					(size 0.7 0.7)
					(thickness 0.15)
				)
				(justify right top)
			)
		)
		(fp_text user "${REFERENCE}"
			(at 0 0 90)
			(layer "F.Fab")
			(effects
				(font
					(size 0.7 0.7)
					(thickness 0.15)
				)
				(justify right top)
			)
		)
		(pad "1" smd rect
			(at -1.051 -0.65)
			(size 0.6 0.6)
			(layers "F.Cu" "F.Mask" "F.Paste")
			(net 140 "/USB-PD/CC1")
			(pinfunction "1")
			(pintype "passive")
		)
		(pad "2" smd rect
			(at -1.051 0.65)
			(size 0.6 0.6)
			(layers "F.Cu" "F.Mask" "F.Paste")
			(net 139 "/USB-PD/CC2")
			(pinfunction "2")
			(pintype "passive")
		)
		(pad "3" smd rect
			(at 1.05 0)
			(size 0.6 0.6)
			(layers "F.Cu" "F.Mask" "F.Paste")
			(net 66 "GND")
			(pinfunction "3")
			(pintype "passive")
		)
	)
	(footprint "antmicro-footprints:R_0402_1005Metric"
		(layer "F.Cu")
		(at 137.85 68.050001 -90)
		(descr "Resistor SMD 0402")
		(tags "resistor SMD 0402")
		(property "Reference" "R49"
			(at 0.900001 4.7995 90)
			(layer "F.SilkS")
			(effects
				(font
					(size 0.7 0.7)
					(thickness 0.15)
				)
				(justify left bottom)
			)
		)
		(property "Value" "R_10k_0402"
			(at -1.011843 1.772046 90)
			(layer "F.Fab")
			(effects
				(font
					(size 0.7 0.7)
					(thickness 0.15)
				)
				(justify right top)
			)
		)
		(property "Datasheet" "https://www.bourns.com/docs/product-datasheets/cr.pdf"
			(at 0 0 90)
			(layer "F.Fab")
			(hide yes)
			(effects
				(font
					(size 1.27 1.27)
					(thickness 0.15)
				)
			)
		)
		(property "Description" "SMD Chip Resistor, 10 kohm, ± 1%, 62.5 mW, 0402 [1005 Metric], Thick Film, General Purpose"
			(at 0 0 90)
			(layer "F.Fab")
			(hide yes)
			(effects
				(font
					(size 1.27 1.27)
					(thickness 0.15)
				)
			)
		)
		(property "MPN" "CR0402-FX-1002GLF"
			(at 0 0 270)
			(unlocked yes)
			(layer "F.Fab")
			(hide yes)
			(effects
				(font
					(size 1 1)
					(thickness 0.15)
				)
			)
		)
		(property "Manufacturer" "Bourns"
			(at 0 0 270)
			(unlocked yes)
			(layer "F.Fab")
			(hide yes)
			(effects
				(font
					(size 1 1)
					(thickness 0.15)
				)
			)
		)
		(property "License" "Apache-2.0"
			(at 0 0 270)
			(unlocked yes)
			(layer "F.Fab")
			(hide yes)
			(effects
				(font
					(size 1 1)
					(thickness 0.15)
				)
			)
		)
		(property "Author" "Antmicro"
			(at 0 0 270)
			(unlocked yes)
			(layer "F.Fab")
			(hide yes)
			(effects
				(font
					(size 1 1)
					(thickness 0.15)
				)
			)
		)
		(property "Val" "10k"
			(at 0 0 270)
			(unlocked yes)
			(layer "F.Fab")
			(hide yes)
			(effects
				(font
					(size 1 1)
					(thickness 0.15)
				)
			)
		)
		(property "Tolerance" "1%"
			(at 0 0 270)
			(unlocked yes)
			(layer "F.Fab")
			(hide yes)
			(effects
				(font
					(size 1 1)
					(thickness 0.15)
				)
			)
		)
		(sheetname "/USB-PD/")
		(sheetfile "usb-pd.kicad_sch")
		(attr smd)
		(fp_rect
			(start -0.925 -0.47)
			(end 0.925 0.47)
			(stroke
				(width 0.05)
				(type default)
			)
			(fill no)
			(layer "F.CrtYd")
		)
		(fp_rect
			(start -0.5 -0.25)
			(end 0.5 0.25)
			(stroke
				(width 0.15)
				(type solid)
			)
			(fill no)
			(layer "F.Fab")
		)
		(fp_text user "License: Apache-2.0"
			(at -0.949999 5.169 90)
			(layer "F.Fab")
			(effects
				(font
					(size 0.7 0.7)
					(thickness 0.15)
				)
				(justify right top)
			)
		)
		(fp_text user "${REFERENCE}"
			(at 0 0 270)
			(layer "F.Fab")
			(effects
				(font
					(size 0.7 0.7)
					(thickness 0.15)
				)
				(justify left bottom)
			)
		)
		(fp_text user "Author: Antmicro"
			(at -0.95 4.169 90)
			(layer "F.Fab")
			(effects
				(font
					(size 0.7 0.7)
					(thickness 0.15)
				)
				(justify right top)
			)
		)
		(pad "1" smd roundrect
			(at -0.48 0 270)
			(size 0.59 0.64)
			(layers "F.Cu" "F.Mask" "F.Paste")
			(roundrect_rratio 0.25)
			(net 66 "GND")
			(pintype "passive")
		)
		(pad "2" smd roundrect
			(at 0.48 0 270)
			(size 0.59 0.64)
			(layers "F.Cu" "F.Mask" "F.Paste")
			(roundrect_rratio 0.25)
			(net 173 "/USB-PD/~{FAULT}")
			(pintype "passive")
		)
	)
	(footprint "antmicro-footprints:TP_Pad0.75mm_Drill0.2mm"
		(layer "F.Cu")
		(at 132.8 94.8 90)
		(property "Reference" "TP13"
			(at -0.45 -3.2 180)
			(layer "F.SilkS")
			(effects
				(font
					(size 0.7 0.7)
					(thickness 0.15)
				)
				(justify left bottom)
			)
		)
		(property "Value" "TP_Pad0.75mm_Drill0.2mm"
			(at 0 1.2 90)
			(layer "F.Fab")
			(effects
				(font
					(size 0.7 0.7)
					(thickness 0.15)
				)
				(justify left bottom)
			)
		)
		(property "Description" "SMT test point"
			(at 0 0 90)
			(layer "F.Fab")
			(hide yes)
			(effects
				(font
					(size 1.27 1.27)
					(thickness 0.15)
				)
			)
		)
		(property "MPN" ""
			(at 0 0 90)
			(unlocked yes)
			(layer "F.Fab")
			(hide yes)
			(effects
				(font
					(size 1 1)
					(thickness 0.15)
				)
			)
		)
		(property "Manufacturer" ""
			(at 0 0 90)
			(unlocked yes)
			(layer "F.Fab")
			(hide yes)
			(effects
				(font
					(size 1 1)
					(thickness 0.15)
				)
			)
		)
		(property "Author" "Antmicro"
			(at 0 0 90)
			(unlocked yes)
			(layer "F.Fab")
			(hide yes)
			(effects
				(font
					(size 1 1)
					(thickness 0.15)
				)
			)
		)
		(property "License" "Apache-2.0"
			(at 0 0 90)
			(unlocked yes)
			(layer "F.Fab")
			(hide yes)
			(effects
				(font
					(size 1 1)
					(thickness 0.15)
				)
			)
		)
		(sheetname "/USB-PD/")
		(sheetfile "usb-pd.kicad_sch")
		(attr exclude_from_pos_files exclude_from_bom)
		(fp_circle
			(center 0 0)
			(end 0.475 0)
			(stroke
				(width 0.05)
				(type default)
			)
			(fill no)
			(layer "F.CrtYd")
		)
		(fp_text user "${REFERENCE}"
			(at -0.4 2.7 90)
			(layer "F.Fab")
			(effects
				(font
					(size 0.7 0.7)
					(thickness 0.15)
				)
				(justify left bottom)
			)
		)
		(fp_text user "Author: Antmicro"
			(at -0.4 3.901 90)
			(layer "F.Fab")
			(effects
				(font
					(size 0.7 0.7)
					(thickness 0.15)
				)
				(justify left bottom)
			)
		)
		(fp_text user "License: Apache-2.0"
			(at -0.4 5.101 90)
			(layer "F.Fab")
			(effects
				(font
					(size 0.7 0.7)
					(thickness 0.15)
				)
				(justify left bottom)
			)
		)
		(pad "1" thru_hole circle
			(at 0 0 90)
			(size 0.75 0.75)
			(drill 0.2)
			(layers "*.Cu" "*.Mask")
			(remove_unused_layers no)
			(net 187 "/USB-PD/12V_CONV")
			(pinfunction "1")
			(pintype "passive")
		)
	)
	(footprint "antmicro-footprints:TP_Pad0.75mm_Drill0.2mm"
		(layer "F.Cu")
		(at 155.75 152)
		(property "Reference" "TP3"
			(at 0.6 0.5 0)
			(layer "F.SilkS")
			(effects
				(font
					(size 0.7 0.7)
					(thickness 0.15)
				)
				(justify left bottom)
			)
		)
		(property "Value" "TP_Pad0.75mm_Drill0.2mm"
			(at 0 1.2 0)
			(layer "F.Fab")
			(effects
				(font
					(size 0.7 0.7)
					(thickness 0.15)
				)
				(justify left bottom)
			)
		)
		(property "Description" "SMT test point"
			(at 0 0 0)
			(layer "F.Fab")
			(hide yes)
			(effects
				(font
					(size 1.27 1.27)
					(thickness 0.15)
				)
			)
		)
		(property "MPN" ""
			(at 0 0 0)
			(unlocked yes)
			(layer "F.Fab")
			(hide yes)
			(effects
				(font
					(size 1 1)
					(thickness 0.15)
				)
			)
		)
		(property "Manufacturer" ""
			(at 0 0 0)
			(unlocked yes)
			(layer "F.Fab")
			(hide yes)
			(effects
				(font
					(size 1 1)
					(thickness 0.15)
				)
			)
		)
		(property "Author" "Antmicro"
			(at 0 0 0)
			(unlocked yes)
			(layer "F.Fab")
			(hide yes)
			(effects
				(font
					(size 1 1)
					(thickness 0.15)
				)
			)
		)
		(property "License" "Apache-2.0"
			(at 0 0 0)
			(unlocked yes)
			(layer "F.Fab")
			(hide yes)
			(effects
				(font
					(size 1 1)
					(thickness 0.15)
				)
			)
		)
		(sheetname "/Power/")
		(sheetfile "power.kicad_sch")
		(attr exclude_from_pos_files exclude_from_bom)
		(fp_circle
			(center 0 0)
			(end 0.475 0)
			(stroke
				(width 0.05)
				(type default)
			)
			(fill no)
			(layer "F.CrtYd")
		)
		(fp_text user "${REFERENCE}"
			(at -0.4 2.7 0)
			(layer "F.Fab")
			(effects
				(font
					(size 0.7 0.7)
					(thickness 0.15)
				)
				(justify left bottom)
			)
		)
		(fp_text user "License: Apache-2.0"
			(at -0.4 5.101 0)
			(layer "F.Fab")
			(effects
				(font
					(size 0.7 0.7)
					(thickness 0.15)
				)
				(justify left bottom)
			)
		)
		(fp_text user "Author: Antmicro"
			(at -0.4 3.901 0)
			(layer "F.Fab")
			(effects
				(font
					(size 0.7 0.7)
					(thickness 0.15)
				)
				(justify left bottom)
			)
		)
		(pad "1" thru_hole circle
			(at 0 0)
			(size 0.75 0.75)
			(drill 0.2)
			(layers "*.Cu" "*.Mask")
			(remove_unused_layers no)
			(net 87 "+12V")
			(pinfunction "1")
			(pintype "passive")
		)
	)
	(footprint "antmicro-footprints:C_0402_1005Metric"
		(layer "F.Cu")
		(at 144.002 95.55 180)
		(descr "Capacitor SMD 0402")
		(tags "capacitor SMD 0402")
		(property "Reference" "C21"
			(at 1.002 0.55 180)
			(layer "F.SilkS")
			(effects
				(font
					(size 0.7 0.7)
					(thickness 0.15)
				)
				(justify right top)
			)
		)
		(property "Value" "C_4u7_25V_0402"
			(at -1.022927 2.155213 0)
			(layer "F.Fab")
			(effects
				(font
					(size 0.7 0.7)
					(thickness 0.15)
				)
				(justify right top)
			)
		)
		(property "Datasheet" "https://www.murata.com/products/productdetail?partno=GRM155C61E475ME15%23"
			(at 0 0 0)
			(layer "F.Fab")
			(hide yes)
			(effects
				(font
					(size 1.27 1.27)
					(thickness 0.15)
				)
			)
		)
		(property "Description" "SMD Multilayer Ceramic Capacitor"
			(at 0 0 0)
			(layer "F.Fab")
			(hide yes)
			(effects
				(font
					(size 1.27 1.27)
					(thickness 0.15)
				)
			)
		)
		(property "MPN" "GRM155C61E475ME15J"
			(at 0 0 180)
			(unlocked yes)
			(layer "F.Fab")
			(hide yes)
			(effects
				(font
					(size 1 1)
					(thickness 0.15)
				)
			)
		)
		(property "Manufacturer" "Murata"
			(at 0 0 180)
			(unlocked yes)
			(layer "F.Fab")
			(hide yes)
			(effects
				(font
					(size 1 1)
					(thickness 0.15)
				)
			)
		)
		(property "License" "Apache-2.0"
			(at 0 0 180)
			(unlocked yes)
			(layer "F.Fab")
			(hide yes)
			(effects
				(font
					(size 1 1)
					(thickness 0.15)
				)
			)
		)
		(property "Author" "Antmicro"
			(at 0 0 180)
			(unlocked yes)
			(layer "F.Fab")
			(hide yes)
			(effects
				(font
					(size 1 1)
					(thickness 0.15)
				)
			)
		)
		(property "Val" "4u7"
			(at 0 0 180)
			(unlocked yes)
			(layer "F.Fab")
			(hide yes)
			(effects
				(font
					(size 1 1)
					(thickness 0.15)
				)
			)
		)
		(property "Voltage" "25V"
			(at 0 0 180)
			(unlocked yes)
			(layer "F.Fab")
			(hide yes)
			(effects
				(font
					(size 1 1)
					(thickness 0.15)
				)
			)
		)
		(property "Dielectric" "X5S"
			(at 0 0 180)
			(unlocked yes)
			(layer "F.Fab")
			(hide yes)
			(effects
				(font
					(size 1 1)
					(thickness 0.15)
				)
			)
		)
		(sheetname "/USB-PD/")
		(sheetfile "usb-pd.kicad_sch")
		(attr smd)
		(fp_rect
			(start -0.925 -0.47)
			(end 0.925 0.47)
			(stroke
				(width 0.05)
				(type default)
			)
			(fill no)
			(layer "F.CrtYd")
		)
		(fp_line
			(start 0.504 0.248)
			(end -0.494 0.248)
			(stroke
				(width 0.15)
				(type solid)
			)
			(layer "F.Fab")
		)
		(fp_line
			(start 0.504 -0.25)
			(end 0.504 0.248)
			(stroke
				(width 0.15)
				(type solid)
			)
			(layer "F.Fab")
		)
		(fp_line
			(start -0.494 0.248)
			(end -0.494 -0.25)
			(stroke
				(width 0.15)
				(type solid)
			)
			(layer "F.Fab")
		)
		(fp_line
			(start -0.494 -0.25)
			(end 0.504 -0.25)
			(stroke
				(width 0.15)
				(type solid)
			)
			(layer "F.Fab")
		)
		(fp_text user "Author: Antmicro"
			(at -0.939 3.399 0)
			(layer "F.Fab")
			(effects
				(font
					(size 0.7 0.7)
					(thickness 0.15)
				)
				(justify right top)
			)
		)
		(fp_text user "License: Apache-2.0"
			(at -0.939 5.799 0)
			(layer "F.Fab")
			(effects
				(font
					(size 0.7 0.7)
					(thickness 0.15)
				)
				(justify right top)
			)
		)
		(fp_text user "${REFERENCE}"
			(at 0 0 0)
			(layer "F.Fab")
			(effects
				(font
					(size 0.7 0.7)
					(thickness 0.15)
				)
				(justify right top)
			)
		)
		(pad "1" smd roundrect
			(at -0.48 0 180)
			(size 0.59 0.64)
			(layers "F.Cu" "F.Mask" "F.Paste")
			(roundrect_rratio 0.25)
			(net 66 "GND")
			(pintype "passive")
		)
		(pad "2" smd roundrect
			(at 0.48 0 180)
			(size 0.59 0.64)
			(layers "F.Cu" "F.Mask" "F.Paste")
			(roundrect_rratio 0.25)
			(net 123 "/USB-PD/12V_VDRV")
			(pintype "passive")
		)
	)
	(footprint "antmicro-footprints:MP_Pad6mm_Drill3.2mm"
		(layer "F.Cu")
		(at 104.8 162.8 -90)
		(property "Reference" "MP4"
			(at 0 0 90)
			(layer "F.SilkS")
			(hide yes)
			(effects
				(font
					(size 0.7 0.7)
					(thickness 0.15)
				)
				(justify right top)
			)
		)
		(property "Value" "MP_Pad6mm_Drill3.2mm"
			(at 0 3.899999 90)
			(layer "F.Fab")
			(effects
				(font
					(size 0.7 0.7)
					(thickness 0.15)
				)
				(justify right top)
			)
		)
		(property "Description" "Mechanical part"
			(at 0 0 90)
			(layer "F.Fab")
			(hide yes)
			(effects
				(font
					(size 1.27 1.27)
					(thickness 0.15)
				)
			)
		)
		(property "Author" "Antmicro"
			(at 0 0 270)
			(unlocked yes)
			(layer "F.Fab")
			(hide yes)
			(effects
				(font
					(size 1 1)
					(thickness 0.15)
				)
			)
		)
		(property "License" "Apache-2.0"
			(at 0 0 270)
			(unlocked yes)
			(layer "F.Fab")
			(hide yes)
			(effects
				(font
					(size 1 1)
					(thickness 0.15)
				)
			)
		)
		(sheetname "/")
		(sheetfile "oculink-to-pcie-adapter.kicad_sch")
		(attr exclude_from_pos_files exclude_from_bom)
		(fp_circle
			(center 0 0)
			(end 3.25 0)
			(stroke
				(width 0.05)
				(type default)
			)
			(fill no)
			(layer "F.CrtYd")
		)
		(fp_text user "Author: Antmicro"
			(at -0.178001 7.225 90)
			(layer "F.Fab")
			(effects
				(font
					(size 0.7 0.7)
					(thickness 0.15)
				)
				(justify right top)
			)
		)
		(fp_text user "${REFERENCE}"
			(at 0 0 90)
			(layer "F.Fab")
			(effects
				(font
					(size 0.7 0.7)
					(thickness 0.15)
				)
				(justify right top)
			)
		)
		(fp_text user "License: Apache-2.0"
			(at -0.178 8.425001 90)
			(layer "F.Fab")
			(effects
				(font
					(size 0.7 0.7)
					(thickness 0.15)
				)
				(justify right top)
			)
		)
		(pad "1" thru_hole circle
			(at 0 0 270)
			(size 6 6)
			(drill 3.2)
			(layers "*.Cu" "*.Mask")
			(remove_unused_layers no)
			(net 66 "GND")
			(pintype "passive")
		)
	)
	(footprint "antmicro-footprints:R_0603_1608Metric"
		(layer "F.Cu")
		(at 117.5 138.6 -90)
		(descr "Resistor SMD 0603")
		(tags "resistor SMD 0603")
		(property "Reference" "R53"
			(at -1.1 1.7 90)
			(layer "F.SilkS")
			(effects
				(font
					(size 0.7 0.7)
					(thickness 0.15)
				)
				(justify right top)
			)
		)
		(property "Value" "R_0R_22.4A_0603"
			(at 0 1.6 90)
			(layer "F.Fab")
			(effects
				(font
					(size 0.7 0.7)
					(thickness 0.15)
				)
				(justify right top)
			)
		)
		(property "Datasheet" "https://fscdn.rohm.com/en/products/databook/datasheet/passive/resistor/chip_resistor/pmr-jpw-e.pdf"
			(at 0 0 90)
			(layer "F.Fab")
			(hide yes)
			(effects
				(font
					(size 1.27 1.27)
					(thickness 0.15)
				)
			)
		)
		(property "Description" "SMD Chip Resistor"
			(at 0 0 90)
			(layer "F.Fab")
			(hide yes)
			(effects
				(font
					(size 1.27 1.27)
					(thickness 0.15)
				)
			)
		)
		(property "MPN" "PMR03EZPJ000"
			(at 0 0 270)
			(unlocked yes)
			(layer "F.Fab")
			(hide yes)
			(effects
				(font
					(size 1 1)
					(thickness 0.15)
				)
			)
		)
		(property "Manufacturer" "ROHM Semiconductor"
			(at 0 0 270)
			(unlocked yes)
			(layer "F.Fab")
			(hide yes)
			(effects
				(font
					(size 1 1)
					(thickness 0.15)
				)
			)
		)
		(property "Val" "0R"
			(at 0 0 270)
			(unlocked yes)
			(layer "F.Fab")
			(hide yes)
			(effects
				(font
					(size 1 1)
					(thickness 0.15)
				)
			)
		)
		(property "Max. Curr." "22.4A"
			(at 0 0 270)
			(unlocked yes)
			(layer "F.Fab")
			(hide yes)
			(effects
				(font
					(size 1 1)
					(thickness 0.15)
				)
			)
		)
		(property "Author" "Antmicro"
			(at 0 0 270)
			(unlocked yes)
			(layer "F.Fab")
			(hide yes)
			(effects
				(font
					(size 1 1)
					(thickness 0.15)
				)
			)
		)
		(property "License" "Apache-2.0"
			(at 0 0 270)
			(unlocked yes)
			(layer "F.Fab")
			(hide yes)
			(effects
				(font
					(size 1 1)
					(thickness 0.15)
				)
			)
		)
		(property "Tolerance" "template_tolerance"
			(at 0 0 270)
			(unlocked yes)
			(layer "F.Fab")
			(hide yes)
			(effects
				(font
					(size 1 1)
					(thickness 0.15)
				)
			)
		)
		(sheetname "/Power/")
		(sheetfile "power.kicad_sch")
		(attr smd exclude_from_bom)
		(fp_line
			(start -0.15 0.4)
			(end 0.15 0.4)
			(stroke
				(width 0.15)
				(type solid)
			)
			(layer "F.SilkS")
		)
		(fp_line
			(start -0.15 -0.4)
			(end 0.15 -0.4)
			(stroke
				(width 0.15)
				(type solid)
			)
			(layer "F.SilkS")
		)
		(fp_rect
			(start -1.25 -0.65)
			(end 1.25 0.65)
			(stroke
				(width 0.05)
				(type solid)
			)
			(fill no)
			(layer "F.CrtYd")
		)
		(fp_rect
			(start -0.8 -0.4)
			(end 0.8 0.4)
			(stroke
				(width 0.15)
				(type solid)
			)
			(fill no)
			(layer "F.Fab")
		)
		(fp_text user "Author: Antmicro"
			(at -1.25 4.9 90)
			(layer "F.Fab")
			(effects
				(font
					(size 0.7 0.7)
					(thickness 0.15)
				)
				(justify right top)
			)
		)
		(fp_text user "${REFERENCE}"
			(at -1.25 3.898 90)
			(layer "F.Fab")
			(effects
				(font
					(size 0.7 0.7)
					(thickness 0.15)
				)
				(justify right top)
			)
		)
		(fp_text user "License: Apache-2.0"
			(at -1.249999 5.9 90)
			(layer "F.Fab")
			(effects
				(font
					(size 0.7 0.7)
					(thickness 0.15)
				)
				(justify right top)
			)
		)
		(pad "1" smd roundrect
			(at -0.7 0 270)
			(size 0.8 1)
			(layers "F.Cu" "F.Mask" "F.Paste")
			(roundrect_rratio 0.2)
			(net 134 "+3V3")
			(pintype "passive")
		)
		(pad "2" smd roundrect
			(at 0.7 0 270)
			(size 0.8 1)
			(layers "F.Cu" "F.Mask" "F.Paste")
			(roundrect_rratio 0.2)
			(net 186 "/Power/3V3_CONV")
			(pintype "passive")
		)
	)
	(footprint "antmicro-footprints:SOT-23-3"
		(layer "F.Cu")
		(at 136.7505 71.35 90)
		(property "Reference" "Q9"
			(at 2.406999 -1.524 90)
			(layer "F.SilkS")
			(effects
				(font
					(size 0.7 0.7)
					(thickness 0.15)
				)
				(justify right top)
			)
		)
		(property "Value" "BSS138-7-F"
			(at -1.9 2.7 90)
			(layer "F.Fab")
			(effects
				(font
					(size 0.7 0.7)
					(thickness 0.15)
				)
				(justify left bottom)
			)
		)
		(property "Datasheet" "https://www.diodes.com/assets/Datasheets/ds30144.pdf"
			(at 0 0 90)
			(layer "F.Fab")
			(hide yes)
			(effects
				(font
					(size 1.27 1.27)
					(thickness 0.15)
				)
			)
		)
		(property "Description" "Power MOSFET, N Channel, 50 V, 200 mA, 1.4 ohm, SOT-23, Surface Mount"
			(at 0 0 90)
			(layer "F.Fab")
			(hide yes)
			(effects
				(font
					(size 1.27 1.27)
					(thickness 0.15)
				)
			)
		)
		(property "MPN" "BSS138-7-F"
			(at 0 0 90)
			(unlocked yes)
			(layer "F.Fab")
			(hide yes)
			(effects
				(font
					(size 1 1)
					(thickness 0.15)
				)
			)
		)
		(property "Manufacturer" "Diodes Incorporated"
			(at 0 0 90)
			(unlocked yes)
			(layer "F.Fab")
			(hide yes)
			(effects
				(font
					(size 1 1)
					(thickness 0.15)
				)
			)
		)
		(property "Author" "Antmicro"
			(at 0 0 90)
			(unlocked yes)
			(layer "F.Fab")
			(hide yes)
			(effects
				(font
					(size 1 1)
					(thickness 0.15)
				)
			)
		)
		(property "License" "Apache-2.0"
			(at 0 0 90)
			(unlocked yes)
			(layer "F.Fab")
			(hide yes)
			(effects
				(font
					(size 1 1)
					(thickness 0.15)
				)
			)
		)
		(sheetname "/USB-PD/")
		(sheetfile "usb-pd.kicad_sch")
		(attr smd)
		(fp_line
			(start 0.7 -1.5)
			(end -0.7 -1.5)
			(stroke
				(width 0.15)
				(type solid)
			)
			(layer "F.SilkS")
		)
		(fp_line
			(start -0.85 -1.35)
			(end -0.7 -1.5)
			(stroke
				(width 0.15)
				(type solid)
			)
			(layer "F.SilkS")
		)
		(fp_line
			(start -1.45 -1.35)
			(end -0.85 -1.35)
			(stroke
				(width 0.15)
				(type solid)
			)
			(layer "F.SilkS")
		)
		(fp_line
			(start 0.7 -0.4)
			(end 0.7 -1.5)
			(stroke
				(width 0.15)
				(type solid)
			)
			(layer "F.SilkS")
		)
		(fp_line
			(start 0.7 0.4)
			(end 0.7 1.5)
			(stroke
				(width 0.15)
				(type solid)
			)
			(layer "F.SilkS")
		)
		(fp_line
			(start 0.7 1.5)
			(end -0.7 1.5)
			(stroke
				(width 0.15)
				(type solid)
			)
			(layer "F.SilkS")
		)
		(fp_line
			(start -0.7 1.5)
			(end -0.7 1.35)
			(stroke
				(width 0.15)
				(type solid)
			)
			(layer "F.SilkS")
		)
		(fp_line
			(start 0.825 -1.6)
			(end 0.825 -0.45)
			(stroke
				(width 0.05)
				(type solid)
			)
			(layer "F.CrtYd")
		)
		(fp_line
			(start -0.9 -1.6)
			(end 0.825 -1.6)
			(stroke
				(width 0.05)
				(type solid)
			)
			(layer "F.CrtYd")
		)
		(fp_line
			(start -0.9 -1.6)
			(end -0.9 -1.4)
			(stroke
				(width 0.05)
				(type solid)
			)
			(layer "F.CrtYd")
		)
		(fp_line
			(start -0.9 -1.4)
			(end -1.75 -1.4)
			(stroke
				(width 0.05)
				(type solid)
			)
			(layer "F.CrtYd")
		)
		(fp_line
			(start -0.85 -0.5)
			(end -1.75 -0.5)
			(stroke
				(width 0.05)
				(type solid)
			)
			(layer "F.CrtYd")
		)
		(fp_line
			(start -1.75 -0.5)
			(end -1.75 -1.4)
			(stroke
				(width 0.05)
				(type solid)
			)
			(layer "F.CrtYd")
		)
		(fp_line
			(start 1.75 -0.45)
			(end 1.75 0.45)
			(stroke
				(width 0.05)
				(type solid)
			)
			(layer "F.CrtYd")
		)
		(fp_line
			(start 0.825 -0.45)
			(end 1.75 -0.45)
			(stroke
				(width 0.05)
				(type solid)
			)
			(layer "F.CrtYd")
		)
		(fp_line
			(start 1.75 0.45)
			(end 0.85 0.45)
			(stroke
				(width 0.05)
				(type solid)
			)
			(layer "F.CrtYd")
		)
		(fp_line
			(start 0.85 0.45)
			(end 0.85 1.65)
			(stroke
				(width 0.05)
				(type solid)
			)
			(layer "F.CrtYd")
		)
		(fp_line
			(start -0.85 0.5)
			(end -0.85 -0.5)
			(stroke
				(width 0.05)
				(type solid)
			)
			(layer "F.CrtYd")
		)
		(fp_line
			(start -1.75 0.5)
			(end -0.85 0.5)
			(stroke
				(width 0.05)
				(type solid)
			)
			(layer "F.CrtYd")
		)
		(fp_line
			(start -0.85 1.4)
			(end -1.75 1.4)
			(stroke
				(width 0.05)
				(type solid)
			)
			(layer "F.CrtYd")
		)
		(fp_line
			(start -1.75 1.4)
			(end -1.75 0.5)
			(stroke
				(width 0.05)
				(type solid)
			)
			(layer "F.CrtYd")
		)
		(fp_line
			(start 0.85 1.65)
			(end -0.85 1.65)
			(stroke
				(width 0.05)
				(type solid)
			)
			(layer "F.CrtYd")
		)
		(fp_line
			(start -0.85 1.65)
			(end -0.85 1.4)
			(stroke
				(width 0.05)
				(type solid)
			)
			(layer "F.CrtYd")
		)
		(fp_line
			(start -0.437 -1.526)
			(end 0.688 -1.526)
			(stroke
				(width 0.15)
				(type solid)
			)
			(layer "F.Fab")
		)
		(fp_line
			(start -0.437 -1.526)
			(end -0.712 -1.325)
			(stroke
				(width 0.15)
				(type solid)
			)
			(layer "F.Fab")
		)
		(fp_line
			(start -0.712 -1.325)
			(end -0.712 1.523)
			(stroke
				(width 0.15)
				(type solid)
			)
			(layer "F.Fab")
		)
		(fp_line
			(start 0.688 1.519)
			(end 0.688 -1.52)
			(stroke
				(width 0.15)
				(type solid)
			)
			(layer "F.Fab")
		)
		(fp_line
			(start -0.712 1.519)
			(end 0.688 1.519)
			(stroke
				(width 0.15)
				(type solid)
			)
			(layer "F.Fab")
		)
		(fp_text user "Author: Antmicro"
			(at -1.837 5.3 90)
			(layer "F.Fab")
			(effects
				(font
					(size 0.7 0.7)
					(thickness 0.15)
				)
				(justify left bottom)
			)
		)
		(fp_text user "License: Apache-2.0"
			(at -1.8 6.8 90)
			(layer "F.Fab")
			(effects
				(font
					(size 0.7 0.7)
					(thickness 0.15)
				)
				(justify left bottom)
			)
		)
		(fp_text user "${REFERENCE}"
			(at 0 0.025 270)
			(layer "F.Fab")
			(effects
				(font
					(size 0.7 0.7)
					(thickness 0.15)
				)
				(justify right top)
			)
		)
		(pad "1" smd roundrect
			(at -1.1 -0.951 90)
			(size 1 0.6)
			(layers "F.Cu" "F.Mask" "F.Paste")
			(roundrect_rratio 0.15)
			(net 124 "/USB-PD/FAULT")
			(pinfunction "G")
			(pintype "input")
		)
		(pad "2" smd roundrect
			(at -1.1 0.949 90)
			(size 1 0.6)
			(layers "F.Cu" "F.Mask" "F.Paste")
			(roundrect_rratio 0.15)
			(net 66 "GND")
			(pinfunction "S")
			(pintype "passive")
		)
		(pad "3" smd roundrect
			(at 1.1 -0.0005 90)
			(size 1 0.6)
			(layers "F.Cu" "F.Mask" "F.Paste")
			(roundrect_rratio 0.15)
			(net 173 "/USB-PD/~{FAULT}")
			(pinfunction "D")
			(pintype "passive")
		)
	)
	(footprint "antmicro-footprints:SOT-23-6"
		(layer "F.Cu")
		(at 141 119.902999 90)
		(property "Reference" "U4"
			(at 0.502999 -3.4 180)
			(layer "F.SilkS")
			(effects
				(font
					(size 0.7 0.7)
					(thickness 0.15)
				)
				(justify left bottom)
			)
		)
		(property "Value" "LTC4412IS6"
			(at -1.749999 2.693 90)
			(layer "F.Fab")
			(effects
				(font
					(size 0.7 0.7)
					(thickness 0.15)
				)
				(justify left bottom)
			)
		)
		(property "Datasheet" "https://www.analog.com/media/en/technical-documentation/data-sheets/4412fb.pdf"
			(at 0 -0.057 90)
			(layer "F.Fab")
			(hide yes)
			(effects
				(font
					(size 1.27 1.27)
					(thickness 0.15)
				)
			)
		)
		(property "Description" "Ideal diode controller"
			(at 0 -0.057 90)
			(layer "F.Fab")
			(hide yes)
			(effects
				(font
					(size 1.27 1.27)
					(thickness 0.15)
				)
			)
		)
		(property "MPN" "LTC4412IS6#TRMPBF"
			(at 0 0 90)
			(unlocked yes)
			(layer "F.Fab")
			(hide yes)
			(effects
				(font
					(size 1 1)
					(thickness 0.15)
				)
			)
		)
		(property "Manufacturer" "Analog Devices"
			(at 0 0 90)
			(unlocked yes)
			(layer "F.Fab")
			(hide yes)
			(effects
				(font
					(size 1 1)
					(thickness 0.15)
				)
			)
		)
		(property "Author" "Antmicro"
			(at 0 0 90)
			(unlocked yes)
			(layer "F.Fab")
			(hide yes)
			(effects
				(font
					(size 1 1)
					(thickness 0.15)
				)
			)
		)
		(property "License" "Apache-2.0"
			(at 0 0 90)
			(unlocked yes)
			(layer "F.Fab")
			(hide yes)
			(effects
				(font
					(size 1 1)
					(thickness 0.15)
				)
			)
		)
		(sheetname "/Power/Ideal-diode-1/")
		(sheetfile "ideal-diode.kicad_sch")
		(attr smd)
		(fp_line
			(start 1.45 -0.757)
			(end 1.45 -0.457)
			(stroke
				(width 0.12)
				(type solid)
			)
			(layer "F.SilkS")
		)
		(fp_line
			(start 1.3 -0.757)
			(end 1.45 -0.757)
			(stroke
				(width 0.12)
				(type solid)
			)
			(layer "F.SilkS")
		)
		(fp_line
			(start -1.3 -0.757)
			(end -1.45 -0.757)
			(stroke
				(width 0.12)
				(type solid)
			)
			(layer "F.SilkS")
		)
		(fp_line
			(start -1.45 -0.757)
			(end -1.45 -0.457)
			(stroke
				(width 0.12)
				(type solid)
			)
			(layer "F.SilkS")
		)
		(fp_line
			(start 1.45 0.643)
			(end 1.45 0.343)
			(stroke
				(width 0.12)
				(type solid)
			)
			(layer "F.SilkS")
		)
		(fp_line
			(start 1.3 0.643)
			(end 1.45 0.643)
			(stroke
				(width 0.12)
				(type solid)
			)
			(layer "F.SilkS")
		)
		(fp_line
			(start -1.45 0.643)
			(end -1.45 0.343)
			(stroke
				(width 0.12)
				(type solid)
			)
			(layer "F.SilkS")
		)
		(fp_rect
			(start -1.55 -1.85)
			(end 1.55 1.75)
			(stroke
				(width 0.05)
				(type solid)
			)
			(fill no)
			(layer "F.CrtYd")
		)
		(fp_line
			(start 1.5 -0.757)
			(end 1.5 0.643)
			(stroke
				(width 0.1)
				(type solid)
			)
			(layer "F.Fab")
		)
		(fp_line
			(start -1.5 -0.757)
			(end 1.5 -0.757)
			(stroke
				(width 0.1)
				(type solid)
			)
			(layer "F.Fab")
		)
		(fp_line
			(start 1.5 0.643)
			(end -1.5 0.643)
			(stroke
				(width 0.1)
				(type solid)
			)
			(layer "F.Fab")
		)
		(fp_line
			(start -1.5 0.643)
			(end -1.5 -0.757)
			(stroke
				(width 0.1)
				(type solid)
			)
			(layer "F.Fab")
		)
		(fp_text user "."
			(at -1.4 1.143001 90)
			(layer "F.SilkS")
			(effects
				(font
					(size 1 1)
					(thickness 0.15)
				)
			)
		)
		(fp_text user "License: Apache-2.0"
			(at -1.75 6.5 90)
			(layer "F.Fab")
			(effects
				(font
					(size 0.7 0.7)
					(thickness 0.15)
				)
				(justify left bottom)
			)
		)
		(fp_text user "${REFERENCE}"
			(at 0 -0.05 90)
			(layer "F.Fab")
			(effects
				(font
					(size 0.7 0.7)
					(thickness 0.15)
				)
				(justify left bottom)
			)
		)
		(fp_text user "Author: Antmicro"
			(at -1.829 5.25 90)
			(layer "F.Fab")
			(effects
				(font
					(size 0.7 0.7)
					(thickness 0.15)
				)
				(justify left bottom)
			)
		)
		(pad "1" smd roundrect
			(at -0.954 1.1 90)
			(size 0.55 1)
			(layers "F.Cu" "F.Mask" "F.Paste")
			(roundrect_rratio 0.15)
			(net 118 "/Power/Ideal-diode-1/VIN")
			(pinfunction "IN")
			(pintype "power_in")
		)
		(pad "2" smd roundrect
			(at -0.003 1.1 90)
			(size 0.55 1)
			(layers "F.Cu" "F.Mask" "F.Paste")
			(roundrect_rratio 0.15)
			(net 66 "GND")
			(pinfunction "GND")
			(pintype "power_in")
		)
		(pad "3" smd roundrect
			(at 0.947 1.1 90)
			(size 0.55 1)
			(layers "F.Cu" "F.Mask" "F.Paste")
			(roundrect_rratio 0.15)
			(net 66 "GND")
			(pinfunction "CTL")
			(pintype "input")
		)
		(pad "4" smd roundrect
			(at 0.947 -1.214 90)
			(size 0.55 1)
			(layers "F.Cu" "F.Mask" "F.Paste")
			(roundrect_rratio 0.15)
			(net 163 "unconnected-(U4-STAT-Pad4)")
			(pinfunction "STAT")
			(pintype "output+no_connect")
		)
		(pad "5" smd roundrect
			(at -0.003 -1.214 90)
			(size 0.55 1)
			(layers "F.Cu" "F.Mask" "F.Paste")
			(roundrect_rratio 0.15)
			(net 104 "Net-(Q1-G)")
			(pinfunction "GATE")
			(pintype "output")
		)
		(pad "6" smd roundrect
			(at -0.954 -1.214 90)
			(size 0.55 1)
			(layers "F.Cu" "F.Mask" "F.Paste")
			(roundrect_rratio 0.15)
			(net 87 "+12V")
			(pinfunction "SENSE")
			(pintype "input")
		)
	)
	(footprint "antmicro-footprints:C_Pol_Vishay-T59-EE"
		(layer "F.Cu")
		(at 138.5 83.499998 180)
		(property "Reference" "C44"
			(at -5.1 -0.300002 180)
			(layer "F.SilkS")
			(effects
				(font
					(size 0.7 0.7)
					(thickness 0.15)
				)
				(justify left bottom)
			)
		)
		(property "Value" "C_Pol_150u_30V_Vishay-T59-EE"
			(at -5.08 5.08 180)
			(unlocked yes)
			(layer "F.Fab")
			(effects
				(font
					(size 0.7 0.7)
					(thickness 0.15)
				)
				(justify left bottom)
			)
		)
		(property "Datasheet" "https://www.vishay.com/docs/40191/t59.pdf"
			(at 0 0 0)
			(layer "F.Fab")
			(hide yes)
			(effects
				(font
					(size 1.27 1.27)
					(thickness 0.15)
				)
			)
		)
		(property "Description" "Tantalum Capacitors - Polymer 150uF 30volts 20% 75mohms maxESR"
			(at 0 0 0)
			(layer "F.Fab")
			(hide yes)
			(effects
				(font
					(size 1.27 1.27)
					(thickness 0.15)
				)
			)
		)
		(property "MPN" "T59EE157M030C0075"
			(at 0 0 180)
			(unlocked yes)
			(layer "F.Fab")
			(hide yes)
			(effects
				(font
					(size 1 1)
					(thickness 0.15)
				)
			)
		)
		(property "Manufacturer" "Vishay"
			(at 0 0 180)
			(unlocked yes)
			(layer "F.Fab")
			(hide yes)
			(effects
				(font
					(size 1 1)
					(thickness 0.15)
				)
			)
		)
		(property "Voltage" "30V"
			(at 0 0 180)
			(unlocked yes)
			(layer "F.Fab")
			(hide yes)
			(effects
				(font
					(size 1 1)
					(thickness 0.15)
				)
			)
		)
		(property "Val" "150u"
			(at 0 0 180)
			(unlocked yes)
			(layer "F.Fab")
			(hide yes)
			(effects
				(font
					(size 1 1)
					(thickness 0.15)
				)
			)
		)
		(property "Author" "Antmicro"
			(at 0 0 180)
			(unlocked yes)
			(layer "F.Fab")
			(hide yes)
			(effects
				(font
					(size 1 1)
					(thickness 0.15)
				)
			)
		)
		(property "License" "Apache-2.0"
			(at 0 0 180)
			(unlocked yes)
			(layer "F.Fab")
			(hide yes)
			(effects
				(font
					(size 1 1)
					(thickness 0.15)
				)
			)
		)
		(property "Dielectric" "template_dielectric"
			(at 0 0 180)
			(unlocked yes)
			(layer "F.Fab")
			(hide yes)
			(effects
				(font
					(size 1 1)
					(thickness 0.15)
				)
			)
		)
		(sheetname "/USB-PD/")
		(sheetfile "usb-pd.kicad_sch")
		(attr smd)
		(fp_line
			(start -2 2.25)
			(end 2 2.25)
			(stroke
				(width 0.15)
				(type solid)
			)
			(layer "F.SilkS")
		)
		(fp_line
			(start -2 -2.25)
			(end 2 -2.25)
			(stroke
				(width 0.15)
				(type solid)
			)
			(layer "F.SilkS")
		)
		(fp_line
			(start -3.5 -2.8)
			(end -3.5 -3.2)
			(stroke
				(width 0.15)
				(type solid)
			)
			(layer "F.SilkS")
		)
		(fp_line
			(start -3.7 -3)
			(end -3.3 -3)
			(stroke
				(width 0.15)
				(type solid)
			)
			(layer "F.SilkS")
		)
		(fp_rect
			(start -4.9 -2.9)
			(end 4.9 2.9)
			(stroke
				(width 0.05)
				(type solid)
			)
			(fill no)
			(layer "F.CrtYd")
		)
		(fp_rect
			(start -3.75 -2.25)
			(end 3.75 2.25)
			(stroke
				(width 0.15)
				(type solid)
			)
			(fill no)
			(layer "F.Fab")
		)
		(fp_text user "Author: Antmicro"
			(at -5.079999 7.08 0)
			(layer "F.Fab")
			(effects
				(font
					(size 0.7 0.7)
					(thickness 0.15)
				)
				(justify right top)
			)
		)
		(fp_text user "License: Apache-2.0"
			(at -5.08 9.48 0)
			(layer "F.Fab")
			(effects
				(font
					(size 0.7 0.7)
					(thickness 0.15)
				)
				(justify right top)
			)
		)
		(fp_text user "${REFERENCE}"
			(at 0 -0.175 180)
			(layer "F.Fab")
			(effects
				(font
					(size 0.7 0.7)
					(thickness 0.15)
				)
				(justify left bottom)
			)
		)
		(pad "1" smd trapezoid
			(at -3.4 0 180)
			(size 2.5 5.3)
			(layers "F.Cu" "F.Mask" "F.Paste")
			(net 115 "/USB-PD/VCC")
			(pintype "passive")
		)
		(pad "2" smd trapezoid
			(at 3.4 0 180)
			(size 2.5 5.3)
			(layers "F.Cu" "F.Mask" "F.Paste")
			(net 66 "GND")
			(pintype "passive")
		)
	)
	(footprint "antmicro-footprints:C_0402_1005Metric"
		(layer "F.Cu")
		(at 148.152 97)
		(descr "Capacitor SMD 0402")
		(tags "capacitor SMD 0402")
		(property "Reference" "C23"
			(at 1.248 0.4 180)
			(layer "F.SilkS")
			(effects
				(font
					(size 0.7 0.7)
					(thickness 0.15)
				)
				(justify left bottom)
			)
		)
		(property "Value" "C_33n_0402"
			(at -1.022927 2.155213 0)
			(layer "F.Fab")
			(effects
				(font
					(size 0.7 0.7)
					(thickness 0.15)
				)
				(justify left bottom)
			)
		)
		(property "Datasheet" "https://www.murata.com/products/productdetail?partno=GCM155R71E333KA55%23"
			(at 0 0 0)
			(layer "F.Fab")
			(hide yes)
			(effects
				(font
					(size 1.27 1.27)
					(thickness 0.15)
				)
			)
		)
		(property "Description" "SMD Multilayer Ceramic Capacitor, 33000 pF, 25 V, 0402 [1005 Metric], ± 10%, X7R, MC"
			(at 0 0 0)
			(layer "F.Fab")
			(hide yes)
			(effects
				(font
					(size 1.27 1.27)
					(thickness 0.15)
				)
			)
		)
		(property "Manufacturer" "Murata"
			(at 0 0 0)
			(unlocked yes)
			(layer "F.Fab")
			(hide yes)
			(effects
				(font
					(size 1 1)
					(thickness 0.15)
				)
			)
		)
		(property "MPN" "GCM155R71E333KA55D"
			(at 0 0 0)
			(unlocked yes)
			(layer "F.Fab")
			(hide yes)
			(effects
				(font
					(size 1 1)
					(thickness 0.15)
				)
			)
		)
		(property "Val" "33n"
			(at 0 0 0)
			(unlocked yes)
			(layer "F.Fab")
			(hide yes)
			(effects
				(font
					(size 1 1)
					(thickness 0.15)
				)
			)
		)
		(property "License" "Apache-2.0"
			(at 0 0 0)
			(unlocked yes)
			(layer "F.Fab")
			(hide yes)
			(effects
				(font
					(size 1 1)
					(thickness 0.15)
				)
			)
		)
		(property "Author" "Antmicro"
			(at 0 0 0)
			(unlocked yes)
			(layer "F.Fab")
			(hide yes)
			(effects
				(font
					(size 1 1)
					(thickness 0.15)
				)
			)
		)
		(property "Voltage" ""
			(at 0 0 0)
			(unlocked yes)
			(layer "F.Fab")
			(hide yes)
			(effects
				(font
					(size 1 1)
					(thickness 0.15)
				)
			)
		)
		(property "Dielectric" ""
			(at 0 0 0)
			(unlocked yes)
			(layer "F.Fab")
			(hide yes)
			(effects
				(font
					(size 1 1)
					(thickness 0.15)
				)
			)
		)
		(sheetname "/USB-PD/")
		(sheetfile "usb-pd.kicad_sch")
		(attr smd)
		(fp_rect
			(start -0.925 -0.47)
			(end 0.925 0.47)
			(stroke
				(width 0.05)
				(type default)
			)
			(fill no)
			(layer "F.CrtYd")
		)
		(fp_line
			(start -0.494 -0.25)
			(end 0.504 -0.25)
			(stroke
				(width 0.15)
				(type solid)
			)
			(layer "F.Fab")
		)
		(fp_line
			(start -0.494 0.248)
			(end -0.494 -0.25)
			(stroke
				(width 0.15)
				(type solid)
			)
			(layer "F.Fab")
		)
		(fp_line
			(start 0.504 -0.25)
			(end 0.504 0.248)
			(stroke
				(width 0.15)
				(type solid)
			)
			(layer "F.Fab")
		)
		(fp_line
			(start 0.504 0.248)
			(end -0.494 0.248)
			(stroke
				(width 0.15)
				(type solid)
			)
			(layer "F.Fab")
		)
		(fp_text user "License: Apache-2.0"
			(at -0.939 5.799 0)
			(layer "F.Fab")
			(effects
				(font
					(size 0.7 0.7)
					(thickness 0.15)
				)
				(justify left bottom)
			)
		)
		(fp_text user "${REFERENCE}"
			(at 0 0 0)
			(layer "F.Fab")
			(effects
				(font
					(size 0.7 0.7)
					(thickness 0.15)
				)
				(justify left bottom)
			)
		)
		(fp_text user "Author: Antmicro"
			(at -0.939 3.399 0)
			(layer "F.Fab")
			(effects
				(font
					(size 0.7 0.7)
					(thickness 0.15)
				)
				(justify left bottom)
			)
		)
		(pad "1" smd roundrect
			(at -0.48 0)
			(size 0.59 0.64)
			(layers "F.Cu" "F.Mask" "F.Paste")
			(roundrect_rratio 0.25)
			(net 125 "/USB-PD/12V_SS")
			(pintype "passive")
		)
		(pad "2" smd roundrect
			(at 0.48 0)
			(size 0.59 0.64)
			(layers "F.Cu" "F.Mask" "F.Paste")
			(roundrect_rratio 0.25)
			(net 66 "GND")
			(pintype "passive")
		)
	)
	(footprint "antmicro-footprints:Vishay_PowerPAK_1212-8_Single"
		(layer "F.Cu")
		(at 141 141)
		(descr "PowerPAK 1212-8 Single")
		(tags "Vishay PowerPAK 1212-8 Single")
		(property "Reference" "Q7"
			(at -3.6 -1 180)
			(layer "F.SilkS")
			(effects
				(font
					(size 0.7 0.7)
					(thickness 0.15)
				)
				(justify left bottom)
			)
		)
		(property "Value" "SQS401EN-T1_BE3"
			(at 0 2.7 0)
			(layer "F.Fab")
			(effects
				(font
					(size 0.7 0.7)
					(thickness 0.15)
				)
				(justify left bottom)
			)
		)
		(property "Datasheet" "https://www.vishay.com/docs/65529/sqs401en.pdf"
			(at 0 0 0)
			(layer "F.Fab")
			(hide yes)
			(effects
				(font
					(size 1.27 1.27)
					(thickness 0.15)
				)
			)
		)
		(property "Description" "MOSFET, P Channel, 40 V, 16A, 0.047 ohm, PowerPAK 1212-8, Surface Mount"
			(at 0 0 0)
			(layer "F.Fab")
			(hide yes)
			(effects
				(font
					(size 1.27 1.27)
					(thickness 0.15)
				)
			)
		)
		(property "MPN" "SQS401EN-T1_BE3"
			(at 0 0 0)
			(unlocked yes)
			(layer "F.Fab")
			(hide yes)
			(effects
				(font
					(size 1 1)
					(thickness 0.15)
				)
			)
		)
		(property "Manufacturer" "Vishay"
			(at 0 0 0)
			(unlocked yes)
			(layer "F.Fab")
			(hide yes)
			(effects
				(font
					(size 1 1)
					(thickness 0.15)
				)
			)
		)
		(property "Author" "Antmicro"
			(at 0 0 0)
			(unlocked yes)
			(layer "F.Fab")
			(hide yes)
			(effects
				(font
					(size 1 1)
					(thickness 0.15)
				)
			)
		)
		(property "License" "Apache-2.0"
			(at 0 0 0)
			(unlocked yes)
			(layer "F.Fab")
			(hide yes)
			(effects
				(font
					(size 1 1)
					(thickness 0.15)
				)
			)
		)
		(sheetname "/Power/Ideal-diode-2/")
		(sheetfile "ideal-diode.kicad_sch")
		(attr smd)
		(fp_line
			(start -1.651 -1.651)
			(end -1.651 -1.317)
			(stroke
				(width 0.15)
				(type solid)
			)
			(layer "F.SilkS")
		)
		(fp_line
			(start -1.651 -1.651)
			(end 1.648 -1.651)
			(stroke
				(width 0.15)
				(type solid)
			)
			(layer "F.SilkS")
		)
		(fp_line
			(start -1.635 1.3)
			(end -1.635 1.634)
			(stroke
				(width 0.15)
				(type solid)
			)
			(layer "F.SilkS")
		)
		(fp_line
			(start -1.635 1.634)
			(end 1.634 1.634)
			(stroke
				(width 0.15)
				(type solid)
			)
			(layer "F.SilkS")
		)
		(fp_line
			(start 1.634 1.3)
			(end 1.634 1.634)
			(stroke
				(width 0.15)
				(type solid)
			)
			(layer "F.SilkS")
		)
		(fp_line
			(start 1.648 -1.651)
			(end 1.648 -1.317)
			(stroke
				(width 0.15)
				(type solid)
			)
			(layer "F.SilkS")
		)
		(fp_circle
			(center -1.9 -1.4)
			(end -1.85 -1.4)
			(stroke
				(width 0.15)
				(type solid)
			)
			(fill yes)
			(layer "F.SilkS")
		)
		(fp_rect
			(start -2 -1.8)
			(end 2 1.798)
			(stroke
				(width 0.05)
				(type solid)
			)
			(fill no)
			(layer "F.CrtYd")
		)
		(fp_line
			(start -1.6425 -1.4175)
			(end -1.4175 -1.6425)
			(stroke
				(width 0.15)
				(type solid)
			)
			(layer "F.Fab")
		)
		(fp_rect
			(start -1.651 -1.651)
			(end 1.648 1.648)
			(stroke
				(width 0.15)
				(type solid)
			)
			(fill no)
			(layer "F.Fab")
		)
		(fp_text user "Author: Antmicro"
			(at -8 5.9 0)
			(layer "F.Fab")
			(effects
				(font
					(size 0.7 0.7)
					(thickness 0.15)
				)
				(justify left bottom)
			)
		)
		(fp_text user "License: Apache-2.0"
			(at -8 7.1 0)
			(layer "F.Fab")
			(effects
				(font
					(size 0.7 0.7)
					(thickness 0.15)
				)
				(justify left bottom)
			)
		)
		(fp_text user "${REFERENCE}"
			(at 0 -0.001 0)
			(layer "F.Fab")
			(effects
				(font
					(size 0.7 0.7)
					(thickness 0.15)
				)
				(justify left bottom)
			)
		)
		(pad "1" smd rect
			(at -1.436 -0.99)
			(size 0.99 0.405)
			(layers "F.Cu" "F.Mask" "F.Paste")
			(net 87 "+12V")
			(pinfunction "S")
			(pintype "passive")
		)
		(pad "2" smd rect
			(at -1.436 -0.332)
			(size 0.99 0.405)
			(layers "F.Cu" "F.Mask" "F.Paste")
			(net 87 "+12V")
			(pinfunction "S")
			(pintype "passive")
		)
		(pad "3" smd rect
			(at -1.436 0.33)
			(size 0.99 0.405)
			(layers "F.Cu" "F.Mask" "F.Paste")
			(net 87 "+12V")
			(pinfunction "S")
			(pintype "passive")
		)
		(pad "4" smd rect
			(at -1.436 0.988)
			(size 0.99 0.405)
			(layers "F.Cu" "F.Mask" "F.Paste")
			(net 175 "Net-(Q7-G)")
			(pinfunction "G")
			(pintype "input")
		)
		(pad "5" smd custom
			(at 0.557 0)
			(size 1.725 2.235)
			(layers "F.Cu" "F.Mask" "F.Paste")
			(net 116 "/Power/Ideal-diode-2/VIN")
			(pinfunction "D")
			(pintype "passive")
			(zone_connect 2)
			(options
				(clearance outline)
				(anchor rect)
			)
			(primitives
				(gr_poly
					(pts
						(xy 0.8625 0.1275) (xy 0.8625 -0.1275) (xy 1.3725 -0.1275) (xy 1.3725 -0.5325) (xy 0.8625 -0.5325)
						(xy 0.8625 -0.7875) (xy 1.3725 -0.7875) (xy 1.3725 -1.195) (xy 0.6125 -1.195) (xy 0.6125 1.195)
						(xy 1.3725 1.195) (xy 1.3725 0.7875) (xy 0.8625 0.7875) (xy 0.8625 0.5325) (xy 1.3725 0.5325)
						(xy 1.3725 0.1275)
					)
					(width 0)
					(fill yes)
				)
			)
		)
	)
	(footprint "antmicro-footprints:R_0402_1005Metric"
		(layer "F.Cu")
		(at 149.737 57.376 90)
		(descr "Resistor SMD 0402")
		(tags "resistor SMD 0402")
		(property "Reference" "R22"
			(at -3.274 0.439001 90)
			(layer "F.SilkS")
			(effects
				(font
					(size 0.7 0.7)
					(thickness 0.15)
				)
				(justify left bottom)
			)
		)
		(property "Value" "R_1k_0402"
			(at -1.011843 1.772046 90)
			(layer "F.Fab")
			(effects
				(font
					(size 0.7 0.7)
					(thickness 0.15)
				)
				(justify left bottom)
			)
		)
		(property "Datasheet" "https://www.bourns.com/docs/product-datasheets/cr.pdf"
			(at 0 0 90)
			(layer "F.Fab")
			(hide yes)
			(effects
				(font
					(size 1.27 1.27)
					(thickness 0.15)
				)
			)
		)
		(property "Description" "SMD Chip Resistor, 1 kohm, ± 1%, 63 mW, 0402 [1005 Metric], Thick Film, General Purpose"
			(at 0 0 90)
			(layer "F.Fab")
			(hide yes)
			(effects
				(font
					(size 1.27 1.27)
					(thickness 0.15)
				)
			)
		)
		(property "MPN" "CR0402-FX-1001GLF"
			(at 0 0 90)
			(unlocked yes)
			(layer "F.Fab")
			(hide yes)
			(effects
				(font
					(size 1 1)
					(thickness 0.15)
				)
			)
		)
		(property "Manufacturer" "Bourns"
			(at 0 0 90)
			(unlocked yes)
			(layer "F.Fab")
			(hide yes)
			(effects
				(font
					(size 1 1)
					(thickness 0.15)
				)
			)
		)
		(property "License" "Apache-2.0"
			(at 0 0 90)
			(unlocked yes)
			(layer "F.Fab")
			(hide yes)
			(effects
				(font
					(size 1 1)
					(thickness 0.15)
				)
			)
		)
		(property "Author" "Antmicro"
			(at 0 0 90)
			(unlocked yes)
			(layer "F.Fab")
			(hide yes)
			(effects
				(font
					(size 1 1)
					(thickness 0.15)
				)
			)
		)
		(property "Val" "1k"
			(at 0 0 90)
			(unlocked yes)
			(layer "F.Fab")
			(hide yes)
			(effects
				(font
					(size 1 1)
					(thickness 0.15)
				)
			)
		)
		(property "Tolerance" "1%"
			(at 0 0 90)
			(unlocked yes)
			(layer "F.Fab")
			(hide yes)
			(effects
				(font
					(size 1 1)
					(thickness 0.15)
				)
			)
		)
		(sheetname "/USB-PD/")
		(sheetfile "usb-pd.kicad_sch")
		(attr smd exclude_from_bom dnp)
		(fp_rect
			(start -0.925 -0.47)
			(end 0.925 0.47)
			(stroke
				(width 0.05)
				(type default)
			)
			(fill no)
			(layer "F.CrtYd")
		)
		(fp_rect
			(start -0.5 -0.25)
			(end 0.5 0.25)
			(stroke
				(width 0.15)
				(type solid)
			)
			(fill no)
			(layer "F.Fab")
		)
		(fp_text user "License: Apache-2.0"
			(at -0.949999 5.169 90)
			(layer "F.Fab")
			(effects
				(font
					(size 0.7 0.7)
					(thickness 0.15)
				)
				(justify left bottom)
			)
		)
		(fp_text user "Author: Antmicro"
			(at -0.95 4.169 90)
			(layer "F.Fab")
			(effects
				(font
					(size 0.7 0.7)
					(thickness 0.15)
				)
				(justify left bottom)
			)
		)
		(fp_text user "${REFERENCE}"
			(at 0 0 90)
			(layer "F.Fab")
			(effects
				(font
					(size 0.7 0.7)
					(thickness 0.15)
				)
				(justify left bottom)
			)
		)
		(pad "1" smd roundrect
			(at -0.48 0 90)
			(size 0.59 0.64)
			(layers "F.Cu" "F.Mask" "F.Paste")
			(roundrect_rratio 0.25)
			(net 66 "GND")
			(pintype "passive")
		)
		(pad "2" smd roundrect
			(at 0.48 0 90)
			(size 0.59 0.64)
			(layers "F.Cu" "F.Mask" "F.Paste")
			(roundrect_rratio 0.25)
			(net 136 "/USB-PD/VBUS_MAX")
			(pintype "passive")
		)
	)
	(footprint "antmicro-footprints:TP_Pad0.75mm_Drill0.2mm"
		(layer "F.Cu")
		(at 117.6 140.6 180)
		(property "Reference" "TP7"
			(at 2.75 -0.6 180)
			(layer "F.SilkS")
			(effects
				(font
					(size 0.7 0.7)
					(thickness 0.15)
				)
				(justify left bottom)
			)
		)
		(property "Value" "TP_Pad0.75mm_Drill0.2mm"
			(at 0 1.2 180)
			(layer "F.Fab")
			(effects
				(font
					(size 0.7 0.7)
					(thickness 0.15)
				)
				(justify left bottom)
			)
		)
		(property "Description" "SMT test point"
			(at 0 0 180)
			(layer "F.Fab")
			(hide yes)
			(effects
				(font
					(size 1.27 1.27)
					(thickness 0.15)
				)
			)
		)
		(property "MPN" ""
			(at 0 0 180)
			(unlocked yes)
			(layer "F.Fab")
			(hide yes)
			(effects
				(font
					(size 1 1)
					(thickness 0.15)
				)
			)
		)
		(property "Manufacturer" ""
			(at 0 0 180)
			(unlocked yes)
			(layer "F.Fab")
			(hide yes)
			(effects
				(font
					(size 1 1)
					(thickness 0.15)
				)
			)
		)
		(property "Author" "Antmicro"
			(at 0 0 180)
			(unlocked yes)
			(layer "F.Fab")
			(hide yes)
			(effects
				(font
					(size 1 1)
					(thickness 0.15)
				)
			)
		)
		(property "License" "Apache-2.0"
			(at 0 0 180)
			(unlocked yes)
			(layer "F.Fab")
			(hide yes)
			(effects
				(font
					(size 1 1)
					(thickness 0.15)
				)
			)
		)
		(sheetname "/Power/")
		(sheetfile "power.kicad_sch")
		(attr exclude_from_pos_files exclude_from_bom)
		(fp_circle
			(center 0 0)
			(end 0.475 0)
			(stroke
				(width 0.05)
				(type default)
			)
			(fill no)
			(layer "F.CrtYd")
		)
		(fp_text user "Author: Antmicro"
			(at -0.4 3.901 180)
			(layer "F.Fab")
			(effects
				(font
					(size 0.7 0.7)
					(thickness 0.15)
				)
				(justify left bottom)
			)
		)
		(fp_text user "${REFERENCE}"
			(at -0.4 2.7 180)
			(layer "F.Fab")
			(effects
				(font
					(size 0.7 0.7)
					(thickness 0.15)
				)
				(justify left bottom)
			)
		)
		(fp_text user "License: Apache-2.0"
			(at -0.4 5.101 180)
			(layer "F.Fab")
			(effects
				(font
					(size 0.7 0.7)
					(thickness 0.15)
				)
				(justify left bottom)
			)
		)
		(pad "1" thru_hole circle
			(at 0 0 180)
			(size 0.75 0.75)
			(drill 0.2)
			(layers "*.Cu" "*.Mask")
			(remove_unused_layers no)
			(net 186 "/Power/3V3_CONV")
			(pinfunction "1")
			(pintype "passive")
		)
	)
	(footprint "antmicro-footprints:TP_Pad0.75mm_Drill0.2mm"
		(layer "F.Cu")
		(at 153.912 55.726 180)
		(property "Reference" "TP5"
			(at -0.438 -0.274 180)
			(layer "F.SilkS")
			(effects
				(font
					(size 0.7 0.7)
					(thickness 0.15)
				)
				(justify left bottom)
			)
		)
		(property "Value" "TP_Pad0.75mm_Drill0.2mm"
			(at 0 1.2 180)
			(layer "F.Fab")
			(effects
				(font
					(size 0.7 0.7)
					(thickness 0.15)
				)
				(justify left bottom)
			)
		)
		(property "Description" "SMT test point"
			(at 0 0 180)
			(layer "F.Fab")
			(hide yes)
			(effects
				(font
					(size 1.27 1.27)
					(thickness 0.15)
				)
			)
		)
		(property "MPN" ""
			(at 0 0 180)
			(unlocked yes)
			(layer "F.Fab")
			(hide yes)
			(effects
				(font
					(size 1 1)
					(thickness 0.15)
				)
			)
		)
		(property "Manufacturer" ""
			(at 0 0 180)
			(unlocked yes)
			(layer "F.Fab")
			(hide yes)
			(effects
				(font
					(size 1 1)
					(thickness 0.15)
				)
			)
		)
		(property "Author" "Antmicro"
			(at 0 0 180)
			(unlocked yes)
			(layer "F.Fab")
			(hide yes)
			(effects
				(font
					(size 1 1)
					(thickness 0.15)
				)
			)
		)
		(property "License" "Apache-2.0"
			(at 0 0 180)
			(unlocked yes)
			(layer "F.Fab")
			(hide yes)
			(effects
				(font
					(size 1 1)
					(thickness 0.15)
				)
			)
		)
		(sheetname "/USB-PD/")
		(sheetfile "usb-pd.kicad_sch")
		(attr exclude_from_pos_files exclude_from_bom)
		(fp_circle
			(center 0 0)
			(end 0.475 0)
			(stroke
				(width 0.05)
				(type default)
			)
			(fill no)
			(layer "F.CrtYd")
		)
		(fp_text user "Author: Antmicro"
			(at -0.4 3.901 180)
			(layer "F.Fab")
			(effects
				(font
					(size 0.7 0.7)
					(thickness 0.15)
				)
				(justify left bottom)
			)
		)
		(fp_text user "${REFERENCE}"
			(at -0.4 2.7 180)
			(layer "F.Fab")
			(effects
				(font
					(size 0.7 0.7)
					(thickness 0.15)
				)
				(justify left bottom)
			)
		)
		(fp_text user "License: Apache-2.0"
			(at -0.4 5.101 180)
			(layer "F.Fab")
			(effects
				(font
					(size 0.7 0.7)
					(thickness 0.15)
				)
				(justify left bottom)
			)
		)
		(pad "1" thru_hole circle
			(at 0 0 180)
			(size 0.75 0.75)
			(drill 0.2)
			(layers "*.Cu" "*.Mask")
			(remove_unused_layers no)
			(net 144 "/USB-PD/~{HPI_INT}")
			(pinfunction "1")
			(pintype "passive")
		)
	)
	(footprint "antmicro-footprints:SOD-123FL"
		(layer "F.Cu")
		(at 143 135)
		(property "Reference" "D8"
			(at -3.8 0.3 180)
			(layer "F.SilkS")
			(effects
				(font
					(size 0.7 0.7)
					(thickness 0.15)
				)
				(justify left bottom)
			)
		)
		(property "Value" "SZSMF4L14AT3G"
			(at 0 1.967 0)
			(layer "F.Fab")
			(effects
				(font
					(size 0.7 0.7)
					(thickness 0.15)
				)
				(justify left bottom)
			)
		)
		(property "Datasheet" "https://www.mouser.com/datasheet/2/240/media-3320461.pdf"
			(at 0 0 0)
			(layer "F.Fab")
			(hide yes)
			(effects
				(font
					(size 1.27 1.27)
					(thickness 0.15)
				)
			)
		)
		(property "Description" "ESD, TVS Diode, 14V, UNI, 400W, SOD-123FL"
			(at 0 0 0)
			(layer "F.Fab")
			(hide yes)
			(effects
				(font
					(size 1.27 1.27)
					(thickness 0.15)
				)
			)
		)
		(property "MPN" "SZSMF4L12AT3G"
			(at 0 0 0)
			(unlocked yes)
			(layer "F.Fab")
			(hide yes)
			(effects
				(font
					(size 1 1)
					(thickness 0.15)
				)
			)
		)
		(property "Author" "Antmicro"
			(at 0 0 0)
			(unlocked yes)
			(layer "F.Fab")
			(hide yes)
			(effects
				(font
					(size 1 1)
					(thickness 0.15)
				)
			)
		)
		(property "License" "Apache-2.0"
			(at 0 0 0)
			(unlocked yes)
			(layer "F.Fab")
			(hide yes)
			(effects
				(font
					(size 1 1)
					(thickness 0.15)
				)
			)
		)
		(property "Manufacturer" "Littelfuse"
			(at 0 0 0)
			(unlocked yes)
			(layer "F.Fab")
			(hide yes)
			(effects
				(font
					(size 1 1)
					(thickness 0.15)
				)
			)
		)
		(sheetname "/Power/")
		(sheetfile "power.kicad_sch")
		(attr smd)
		(fp_line
			(start -2.3 -1.1)
			(end -2.3 1.1)
			(stroke
				(width 0.15)
				(type solid)
			)
			(layer "F.SilkS")
		)
		(fp_line
			(start -2.3 1.1)
			(end 0 1.1)
			(stroke
				(width 0.15)
				(type solid)
			)
			(layer "F.SilkS")
		)
		(fp_line
			(start 0 -1.1)
			(end -2.3 -1.1)
			(stroke
				(width 0.15)
				(type solid)
			)
			(layer "F.SilkS")
		)
		(fp_rect
			(start -2.35 -1.125)
			(end 2.35 1.125)
			(stroke
				(width 0.05)
				(type solid)
			)
			(fill no)
			(layer "F.CrtYd")
		)
		(fp_rect
			(start -1.825 -0.875)
			(end 1.824 0.873)
			(stroke
				(width 0.15)
				(type solid)
			)
			(fill no)
			(layer "F.Fab")
		)
		(fp_rect
			(start -0.775 -0.875)
			(end -0.525 0.875)
			(stroke
				(width 0.15)
				(type solid)
			)
			(fill yes)
			(layer "F.Fab")
		)
		(fp_text user "${REFERENCE}"
			(at 0 0 0)
			(layer "F.Fab")
			(effects
				(font
					(size 0.7 0.7)
					(thickness 0.15)
				)
				(justify left bottom)
			)
		)
		(fp_text user "License: Apache-2.0"
			(at -2.406 6.368 0)
			(layer "F.Fab")
			(effects
				(font
					(size 0.7 0.7)
					(thickness 0.15)
				)
				(justify left bottom)
			)
		)
		(fp_text user "Author: Antmicro"
			(at -2.406 5.168 0)
			(layer "F.Fab")
			(effects
				(font
					(size 0.7 0.7)
					(thickness 0.15)
				)
				(justify left bottom)
			)
		)
		(pad "1" smd roundrect
			(at -1.43 0)
			(size 1.34 1.8)
			(layers "F.Cu" "F.Mask" "F.Paste")
			(roundrect_rratio 0.14)
			(net 116 "/Power/Ideal-diode-2/VIN")
			(pinfunction "C")
			(pintype "passive")
		)
		(pad "2" smd roundrect
			(at 1.429 0)
			(size 1.34 1.8)
			(layers "F.Cu" "F.Mask" "F.Paste")
			(roundrect_rratio 0.14)
			(net 66 "GND")
			(pinfunction "A")
			(pintype "passive")
		)
	)
	(footprint "antmicro-footprints:R_0402_1005Metric"
		(layer "F.Cu")
		(at 143.8 64)
		(descr "Resistor SMD 0402")
		(tags "resistor SMD 0402")
		(property "Reference" "R55"
			(at -1.1 1.5 0)
			(layer "F.SilkS")
			(effects
				(font
					(size 0.7 0.7)
					(thickness 0.15)
				)
				(justify left bottom)
			)
		)
		(property "Value" "R_22R_0402"
			(at -1.011843 1.772047 0)
			(layer "F.Fab")
			(effects
				(font
					(size 0.7 0.7)
					(thickness 0.15)
				)
				(justify left bottom)
			)
		)
		(property "Datasheet" "https://www.bourns.com/docs/product-datasheets/cr.pdf"
			(at 0 0 0)
			(layer "F.Fab")
			(hide yes)
			(effects
				(font
					(size 1.27 1.27)
					(thickness 0.15)
				)
			)
		)
		(property "Description" "SMD Chip Resistor, 22 ohm, ± 1%, 62.5 mW, 0402 [1005 Metric], Thick Film, General Purpose"
			(at 0 0 0)
			(layer "F.Fab")
			(hide yes)
			(effects
				(font
					(size 1.27 1.27)
					(thickness 0.15)
				)
			)
		)
		(property "MPN" "CR0402-FX-22R0GLF"
			(at 0 0 0)
			(unlocked yes)
			(layer "F.Fab")
			(hide yes)
			(effects
				(font
					(size 1 1)
					(thickness 0.15)
				)
			)
		)
		(property "Manufacturer" "Bourns"
			(at 0 0 0)
			(unlocked yes)
			(layer "F.Fab")
			(hide yes)
			(effects
				(font
					(size 1 1)
					(thickness 0.15)
				)
			)
		)
		(property "License" "Apache-2.0"
			(at 0 0 0)
			(unlocked yes)
			(layer "F.Fab")
			(hide yes)
			(effects
				(font
					(size 1 1)
					(thickness 0.15)
				)
			)
		)
		(property "Author" "Antmicro"
			(at 0 0 0)
			(unlocked yes)
			(layer "F.Fab")
			(hide yes)
			(effects
				(font
					(size 1 1)
					(thickness 0.15)
				)
			)
		)
		(property "Val" "22R"
			(at 0 0 0)
			(unlocked yes)
			(layer "F.Fab")
			(hide yes)
			(effects
				(font
					(size 1 1)
					(thickness 0.15)
				)
			)
		)
		(property "Tolerance" "1%"
			(at 0 0 0)
			(unlocked yes)
			(layer "F.Fab")
			(hide yes)
			(effects
				(font
					(size 1 1)
					(thickness 0.15)
				)
			)
		)
		(sheetname "/PCIe-clock-generator/")
		(sheetfile "pcie-clock-generator.kicad_sch")
		(attr smd exclude_from_bom dnp)
		(fp_rect
			(start -0.925 -0.47)
			(end 0.925 0.47)
			(stroke
				(width 0.05)
				(type default)
			)
			(fill no)
			(layer "F.CrtYd")
		)
		(fp_rect
			(start -0.5 -0.25)
			(end 0.5 0.25)
			(stroke
				(width 0.15)
				(type solid)
			)
			(fill no)
			(layer "F.Fab")
		)
		(fp_text user "Author: Antmicro"
			(at -0.95 4.169 0)
			(layer "F.Fab")
			(effects
				(font
					(size 0.7 0.7)
					(thickness 0.15)
				)
				(justify left bottom)
			)
		)
		(fp_text user "${REFERENCE}"
			(at -0.95 3.168 0)
			(layer "F.Fab")
			(effects
				(font
					(size 0.7 0.7)
					(thickness 0.15)
				)
				(justify left bottom)
			)
		)
		(fp_text user "License: Apache-2.0"
			(at -0.95 5.169 0)
			(layer "F.Fab")
			(effects
				(font
					(size 0.7 0.7)
					(thickness 0.15)
				)
				(justify left bottom)
			)
		)
		(pad "1" smd roundrect
			(at -0.48 0)
			(size 0.59 0.64)
			(layers "F.Cu" "F.Mask" "F.Paste")
			(roundrect_rratio 0.25)
			(net 197 "/PCIe-clock-generator/PCIe_{REF1}_R2.CK+")
			(pintype "passive")
		)
		(pad "2" smd roundrect
			(at 0.48 0)
			(size 0.59 0.64)
			(layers "F.Cu" "F.Mask" "F.Paste")
			(roundrect_rratio 0.25)
			(net 178 "/PCIe-clock-generator/PCIe_{REF1}_R.CK+")
			(pintype "passive")
		)
	)
	(footprint "antmicro-footprints:R_0402_1005Metric"
		(layer "F.Cu")
		(at 120.5 127.8)
		(descr "Resistor SMD 0402")
		(tags "resistor SMD 0402")
		(property "Reference" "R6"
			(at -3.3 0.4 180)
			(layer "F.SilkS")
			(effects
				(font
					(size 0.7 0.7)
					(thickness 0.15)
				)
				(justify left bottom)
			)
		)
		(property "Value" "R_10k_0402"
			(at -1.011843 1.772046 0)
			(layer "F.Fab")
			(effects
				(font
					(size 0.7 0.7)
					(thickness 0.15)
				)
				(justify left bottom)
			)
		)
		(property "Datasheet" "https://www.bourns.com/docs/product-datasheets/cr.pdf"
			(at 0 0 0)
			(layer "F.Fab")
			(hide yes)
			(effects
				(font
					(size 1.27 1.27)
					(thickness 0.15)
				)
			)
		)
		(property "Description" "SMD Chip Resistor, 10 kohm, ± 1%, 62.5 mW, 0402 [1005 Metric], Thick Film, General Purpose"
			(at 0 0 0)
			(layer "F.Fab")
			(hide yes)
			(effects
				(font
					(size 1.27 1.27)
					(thickness 0.15)
				)
			)
		)
		(property "MPN" "CR0402-FX-1002GLF"
			(at 0 0 0)
			(unlocked yes)
			(layer "F.Fab")
			(hide yes)
			(effects
				(font
					(size 1 1)
					(thickness 0.15)
				)
			)
		)
		(property "Manufacturer" "Bourns"
			(at 0 0 0)
			(unlocked yes)
			(layer "F.Fab")
			(hide yes)
			(effects
				(font
					(size 1 1)
					(thickness 0.15)
				)
			)
		)
		(property "License" "Apache-2.0"
			(at 0 0 0)
			(unlocked yes)
			(layer "F.Fab")
			(hide yes)
			(effects
				(font
					(size 1 1)
					(thickness 0.15)
				)
			)
		)
		(property "Author" "Antmicro"
			(at 0 0 0)
			(unlocked yes)
			(layer "F.Fab")
			(hide yes)
			(effects
				(font
					(size 1 1)
					(thickness 0.15)
				)
			)
		)
		(property "Val" "10k"
			(at 0 0 0)
			(unlocked yes)
			(layer "F.Fab")
			(hide yes)
			(effects
				(font
					(size 1 1)
					(thickness 0.15)
				)
			)
		)
		(property "Tolerance" "1%"
			(at 0 0 0)
			(unlocked yes)
			(layer "F.Fab")
			(hide yes)
			(effects
				(font
					(size 1 1)
					(thickness 0.15)
				)
			)
		)
		(sheetname "/Power/")
		(sheetfile "power.kicad_sch")
		(attr smd)
		(fp_rect
			(start -0.925 -0.47)
			(end 0.925 0.47)
			(stroke
				(width 0.05)
				(type default)
			)
			(fill no)
			(layer "F.CrtYd")
		)
		(fp_rect
			(start -0.5 -0.25)
			(end 0.5 0.25)
			(stroke
				(width 0.15)
				(type solid)
			)
			(fill no)
			(layer "F.Fab")
		)
		(fp_text user "${REFERENCE}"
			(at 0 0 0)
			(layer "F.Fab")
			(effects
				(font
					(size 0.7 0.7)
					(thickness 0.15)
				)
				(justify left bottom)
			)
		)
		(fp_text user "License: Apache-2.0"
			(at -0.949999 5.169 0)
			(layer "F.Fab")
			(effects
				(font
					(size 0.7 0.7)
					(thickness 0.15)
				)
				(justify left bottom)
			)
		)
		(fp_text user "Author: Antmicro"
			(at -0.95 4.169 0)
			(layer "F.Fab")
			(effects
				(font
					(size 0.7 0.7)
					(thickness 0.15)
				)
				(justify left bottom)
			)
		)
		(pad "1" smd roundrect
			(at -0.48 0)
			(size 0.59 0.64)
			(layers "F.Cu" "F.Mask" "F.Paste")
			(roundrect_rratio 0.25)
			(net 88 "/Power/3V3_VCC")
			(pintype "passive")
		)
		(pad "2" smd roundrect
			(at 0.48 0)
			(size 0.59 0.64)
			(layers "F.Cu" "F.Mask" "F.Paste")
			(roundrect_rratio 0.25)
			(net 105 "/Power/3V3_PG")
			(pintype "passive")
		)
	)
	(footprint "antmicro-footprints:SOT-23-6"
		(layer "F.Cu")
		(at 141 144.5 90)
		(property "Reference" "U2"
			(at 0.7 -3.4 180)
			(layer "F.SilkS")
			(effects
				(font
					(size 0.7 0.7)
					(thickness 0.15)
				)
				(justify left bottom)
			)
		)
		(property "Value" "LTC4412IS6"
			(at -1.749999 2.693 90)
			(layer "F.Fab")
			(effects
				(font
					(size 0.7 0.7)
					(thickness 0.15)
				)
				(justify left bottom)
			)
		)
		(property "Datasheet" "https://www.analog.com/media/en/technical-documentation/data-sheets/4412fb.pdf"
			(at 0 -0.057 90)
			(layer "F.Fab")
			(hide yes)
			(effects
				(font
					(size 1.27 1.27)
					(thickness 0.15)
				)
			)
		)
		(property "Description" "Ideal diode controller"
			(at 0 -0.057 90)
			(layer "F.Fab")
			(hide yes)
			(effects
				(font
					(size 1.27 1.27)
					(thickness 0.15)
				)
			)
		)
		(property "MPN" "LTC4412IS6#TRMPBF"
			(at 0 0 90)
			(unlocked yes)
			(layer "F.Fab")
			(hide yes)
			(effects
				(font
					(size 1 1)
					(thickness 0.15)
				)
			)
		)
		(property "Manufacturer" "Analog Devices"
			(at 0 0 90)
			(unlocked yes)
			(layer "F.Fab")
			(hide yes)
			(effects
				(font
					(size 1 1)
					(thickness 0.15)
				)
			)
		)
		(property "Author" "Antmicro"
			(at 0 0 90)
			(unlocked yes)
			(layer "F.Fab")
			(hide yes)
			(effects
				(font
					(size 1 1)
					(thickness 0.15)
				)
			)
		)
		(property "License" "Apache-2.0"
			(at 0 0 90)
			(unlocked yes)
			(layer "F.Fab")
			(hide yes)
			(effects
				(font
					(size 1 1)
					(thickness 0.15)
				)
			)
		)
		(sheetname "/Power/Ideal-diode-2/")
		(sheetfile "ideal-diode.kicad_sch")
		(attr smd)
		(fp_line
			(start 1.45 -0.757)
			(end 1.45 -0.457)
			(stroke
				(width 0.12)
				(type solid)
			)
			(layer "F.SilkS")
		)
		(fp_line
			(start 1.3 -0.757)
			(end 1.45 -0.757)
			(stroke
				(width 0.12)
				(type solid)
			)
			(layer "F.SilkS")
		)
		(fp_line
			(start -1.3 -0.757)
			(end -1.45 -0.757)
			(stroke
				(width 0.12)
				(type solid)
			)
			(layer "F.SilkS")
		)
		(fp_line
			(start -1.45 -0.757)
			(end -1.45 -0.457)
			(stroke
				(width 0.12)
				(type solid)
			)
			(layer "F.SilkS")
		)
		(fp_line
			(start 1.45 0.643)
			(end 1.45 0.343)
			(stroke
				(width 0.12)
				(type solid)
			)
			(layer "F.SilkS")
		)
		(fp_line
			(start 1.3 0.643)
			(end 1.45 0.643)
			(stroke
				(width 0.12)
				(type solid)
			)
			(layer "F.SilkS")
		)
		(fp_line
			(start -1.45 0.643)
			(end -1.45 0.343)
			(stroke
				(width 0.12)
				(type solid)
			)
			(layer "F.SilkS")
		)
		(fp_rect
			(start -1.55 -1.85)
			(end 1.55 1.75)
			(stroke
				(width 0.05)
				(type solid)
			)
			(fill no)
			(layer "F.CrtYd")
		)
		(fp_line
			(start 1.5 -0.757)
			(end 1.5 0.643)
			(stroke
				(width 0.1)
				(type solid)
			)
			(layer "F.Fab")
		)
		(fp_line
			(start -1.5 -0.757)
			(end 1.5 -0.757)
			(stroke
				(width 0.1)
				(type solid)
			)
			(layer "F.Fab")
		)
		(fp_line
			(start 1.5 0.643)
			(end -1.5 0.643)
			(stroke
				(width 0.1)
				(type solid)
			)
			(layer "F.Fab")
		)
		(fp_line
			(start -1.5 0.643)
			(end -1.5 -0.757)
			(stroke
				(width 0.1)
				(type solid)
			)
			(layer "F.Fab")
		)
		(fp_text user "."
			(at -1.4 1.143001 90)
			(layer "F.SilkS")
			(effects
				(font
					(size 1 1)
					(thickness 0.15)
				)
			)
		)
		(fp_text user "Author: Antmicro"
			(at -1.829 5.25 90)
			(layer "F.Fab")
			(effects
				(font
					(size 0.7 0.7)
					(thickness 0.15)
				)
				(justify left bottom)
			)
		)
		(fp_text user "${REFERENCE}"
			(at 0 -0.05 90)
			(layer "F.Fab")
			(effects
				(font
					(size 0.7 0.7)
					(thickness 0.15)
				)
				(justify left bottom)
			)
		)
		(fp_text user "License: Apache-2.0"
			(at -1.75 6.5 90)
			(layer "F.Fab")
			(effects
				(font
					(size 0.7 0.7)
					(thickness 0.15)
				)
				(justify left bottom)
			)
		)
		(pad "1" smd roundrect
			(at -0.954 1.1 90)
			(size 0.55 1)
			(layers "F.Cu" "F.Mask" "F.Paste")
			(roundrect_rratio 0.15)
			(net 116 "/Power/Ideal-diode-2/VIN")
			(pinfunction "IN")
			(pintype "power_in")
		)
		(pad "2" smd roundrect
			(at -0.003 1.1 90)
			(size 0.55 1)
			(layers "F.Cu" "F.Mask" "F.Paste")
			(roundrect_rratio 0.15)
			(net 66 "GND")
			(pinfunction "GND")
			(pintype "power_in")
		)
		(pad "3" smd roundrect
			(at 0.947 1.1 90)
			(size 0.55 1)
			(layers "F.Cu" "F.Mask" "F.Paste")
			(roundrect_rratio 0.15)
			(net 66 "GND")
			(pinfunction "CTL")
			(pintype "input")
		)
		(pad "4" smd roundrect
			(at 0.947 -1.214 90)
			(size 0.55 1)
			(layers "F.Cu" "F.Mask" "F.Paste")
			(roundrect_rratio 0.15)
			(net 180 "unconnected-(U2-STAT-Pad4)")
			(pinfunction "STAT")
			(pintype "output+no_connect")
		)
		(pad "5" smd roundrect
			(at -0.003 -1.214 90)
			(size 0.55 1)
			(layers "F.Cu" "F.Mask" "F.Paste")
			(roundrect_rratio 0.15)
			(net 175 "Net-(Q7-G)")
			(pinfunction "GATE")
			(pintype "output")
		)
		(pad "6" smd roundrect
			(at -0.954 -1.214 90)
			(size 0.55 1)
			(layers "F.Cu" "F.Mask" "F.Paste")
			(roundrect_rratio 0.15)
			(net 87 "+12V")
			(pinfunction "SENSE")
			(pintype "input")
		)
	)
	(footprint "antmicro-footprints:SOT-23-3"
		(layer "F.Cu")
		(at 140.1005 71.35 90)
		(property "Reference" "Q4"
			(at 2.406999 -1.474 90)
			(layer "F.SilkS")
			(effects
				(font
					(size 0.7 0.7)
					(thickness 0.15)
				)
				(justify right top)
			)
		)
		(property "Value" "BSS138-7-F"
			(at -1.9 2.7 90)
			(layer "F.Fab")
			(effects
				(font
					(size 0.7 0.7)
					(thickness 0.15)
				)
				(justify left bottom)
			)
		)
		(property "Datasheet" "https://www.diodes.com/assets/Datasheets/ds30144.pdf"
			(at 0 0 90)
			(layer "F.Fab")
			(hide yes)
			(effects
				(font
					(size 1.27 1.27)
					(thickness 0.15)
				)
			)
		)
		(property "Description" "Power MOSFET, N Channel, 50 V, 200 mA, 1.4 ohm, SOT-23, Surface Mount"
			(at 0 0 90)
			(layer "F.Fab")
			(hide yes)
			(effects
				(font
					(size 1.27 1.27)
					(thickness 0.15)
				)
			)
		)
		(property "MPN" "BSS138-7-F"
			(at 0 0 90)
			(unlocked yes)
			(layer "F.Fab")
			(hide yes)
			(effects
				(font
					(size 1 1)
					(thickness 0.15)
				)
			)
		)
		(property "Manufacturer" "Diodes Incorporated"
			(at 0 0 90)
			(unlocked yes)
			(layer "F.Fab")
			(hide yes)
			(effects
				(font
					(size 1 1)
					(thickness 0.15)
				)
			)
		)
		(property "Author" "Antmicro"
			(at 0 0 90)
			(unlocked yes)
			(layer "F.Fab")
			(hide yes)
			(effects
				(font
					(size 1 1)
					(thickness 0.15)
				)
			)
		)
		(property "License" "Apache-2.0"
			(at 0 0 90)
			(unlocked yes)
			(layer "F.Fab")
			(hide yes)
			(effects
				(font
					(size 1 1)
					(thickness 0.15)
				)
			)
		)
		(sheetname "/USB-PD/")
		(sheetfile "usb-pd.kicad_sch")
		(attr smd)
		(fp_line
			(start 0.7 -1.5)
			(end -0.7 -1.5)
			(stroke
				(width 0.15)
				(type solid)
			)
			(layer "F.SilkS")
		)
		(fp_line
			(start -0.85 -1.35)
			(end -0.7 -1.5)
			(stroke
				(width 0.15)
				(type solid)
			)
			(layer "F.SilkS")
		)
		(fp_line
			(start -1.45 -1.35)
			(end -0.85 -1.35)
			(stroke
				(width 0.15)
				(type solid)
			)
			(layer "F.SilkS")
		)
		(fp_line
			(start 0.7 -0.4)
			(end 0.7 -1.5)
			(stroke
				(width 0.15)
				(type solid)
			)
			(layer "F.SilkS")
		)
		(fp_line
			(start 0.7 0.4)
			(end 0.7 1.5)
			(stroke
				(width 0.15)
				(type solid)
			)
			(layer "F.SilkS")
		)
		(fp_line
			(start 0.7 1.5)
			(end -0.7 1.5)
			(stroke
				(width 0.15)
				(type solid)
			)
			(layer "F.SilkS")
		)
		(fp_line
			(start -0.7 1.5)
			(end -0.7 1.35)
			(stroke
				(width 0.15)
				(type solid)
			)
			(layer "F.SilkS")
		)
		(fp_line
			(start 0.825 -1.6)
			(end 0.825 -0.45)
			(stroke
				(width 0.05)
				(type solid)
			)
			(layer "F.CrtYd")
		)
		(fp_line
			(start -0.9 -1.6)
			(end 0.825 -1.6)
			(stroke
				(width 0.05)
				(type solid)
			)
			(layer "F.CrtYd")
		)
		(fp_line
			(start -0.9 -1.6)
			(end -0.9 -1.4)
			(stroke
				(width 0.05)
				(type solid)
			)
			(layer "F.CrtYd")
		)
		(fp_line
			(start -0.9 -1.4)
			(end -1.75 -1.4)
			(stroke
				(width 0.05)
				(type solid)
			)
			(layer "F.CrtYd")
		)
		(fp_line
			(start -0.85 -0.5)
			(end -1.75 -0.5)
			(stroke
				(width 0.05)
				(type solid)
			)
			(layer "F.CrtYd")
		)
		(fp_line
			(start -1.75 -0.5)
			(end -1.75 -1.4)
			(stroke
				(width 0.05)
				(type solid)
			)
			(layer "F.CrtYd")
		)
		(fp_line
			(start 1.75 -0.45)
			(end 1.75 0.45)
			(stroke
				(width 0.05)
				(type solid)
			)
			(layer "F.CrtYd")
		)
		(fp_line
			(start 0.825 -0.45)
			(end 1.75 -0.45)
			(stroke
				(width 0.05)
				(type solid)
			)
			(layer "F.CrtYd")
		)
		(fp_line
			(start 1.75 0.45)
			(end 0.85 0.45)
			(stroke
				(width 0.05)
				(type solid)
			)
			(layer "F.CrtYd")
		)
		(fp_line
			(start 0.85 0.45)
			(end 0.85 1.65)
			(stroke
				(width 0.05)
				(type solid)
			)
			(layer "F.CrtYd")
		)
		(fp_line
			(start -0.85 0.5)
			(end -0.85 -0.5)
			(stroke
				(width 0.05)
				(type solid)
			)
			(layer "F.CrtYd")
		)
		(fp_line
			(start -1.75 0.5)
			(end -0.85 0.5)
			(stroke
				(width 0.05)
				(type solid)
			)
			(layer "F.CrtYd")
		)
		(fp_line
			(start -0.85 1.4)
			(end -1.75 1.4)
			(stroke
				(width 0.05)
				(type solid)
			)
			(layer "F.CrtYd")
		)
		(fp_line
			(start -1.75 1.4)
			(end -1.75 0.5)
			(stroke
				(width 0.05)
				(type solid)
			)
			(layer "F.CrtYd")
		)
		(fp_line
			(start 0.85 1.65)
			(end -0.85 1.65)
			(stroke
				(width 0.05)
				(type solid)
			)
			(layer "F.CrtYd")
		)
		(fp_line
			(start -0.85 1.65)
			(end -0.85 1.4)
			(stroke
				(width 0.05)
				(type solid)
			)
			(layer "F.CrtYd")
		)
		(fp_line
			(start -0.437 -1.526)
			(end 0.688 -1.526)
			(stroke
				(width 0.15)
				(type solid)
			)
			(layer "F.Fab")
		)
		(fp_line
			(start -0.437 -1.526)
			(end -0.712 -1.325)
			(stroke
				(width 0.15)
				(type solid)
			)
			(layer "F.Fab")
		)
		(fp_line
			(start -0.712 -1.325)
			(end -0.712 1.523)
			(stroke
				(width 0.15)
				(type solid)
			)
			(layer "F.Fab")
		)
		(fp_line
			(start 0.688 1.519)
			(end 0.688 -1.52)
			(stroke
				(width 0.15)
				(type solid)
			)
			(layer "F.Fab")
		)
		(fp_line
			(start -0.712 1.519)
			(end 0.688 1.519)
			(stroke
				(width 0.15)
				(type solid)
			)
			(layer "F.Fab")
		)
		(fp_text user "${REFERENCE}"
			(at 0 0.025 270)
			(layer "F.Fab")
			(effects
				(font
					(size 0.7 0.7)
					(thickness 0.15)
				)
				(justify right top)
			)
		)
		(fp_text user "Author: Antmicro"
			(at -1.837 5.3 90)
			(layer "F.Fab")
			(effects
				(font
					(size 0.7 0.7)
					(thickness 0.15)
				)
				(justify left bottom)
			)
		)
		(fp_text user "License: Apache-2.0"
			(at -1.8 6.8 90)
			(layer "F.Fab")
			(effects
				(font
					(size 0.7 0.7)
					(thickness 0.15)
				)
				(justify left bottom)
			)
		)
		(pad "1" smd roundrect
			(at -1.1 -0.951 90)
			(size 1 0.6)
			(layers "F.Cu" "F.Mask" "F.Paste")
			(roundrect_rratio 0.15)
			(net 173 "/USB-PD/~{FAULT}")
			(pinfunction "G")
			(pintype "input")
		)
		(pad "2" smd roundrect
			(at -1.1 0.949 90)
			(size 1 0.6)
			(layers "F.Cu" "F.Mask" "F.Paste")
			(roundrect_rratio 0.15)
			(net 66 "GND")
			(pinfunction "S")
			(pintype "passive")
		)
		(pad "3" smd roundrect
			(at 1.1 -0.0005 90)
			(size 1 0.6)
			(layers "F.Cu" "F.Mask" "F.Paste")
			(roundrect_rratio 0.15)
			(net 174 "Net-(Q4-D)")
			(pinfunction "D")
			(pintype "passive")
		)
	)
	(footprint "antmicro-footprints:R_0402_1005Metric"
		(layer "F.Cu")
		(at 151.737 57.376001 90)
		(descr "Resistor SMD 0402")
		(tags "resistor SMD 0402")
		(property "Reference" "R28"
			(at -3.273999 0.439001 90)
			(layer "F.SilkS")
			(effects
				(font
					(size 0.7 0.7)
					(thickness 0.15)
				)
				(justify left bottom)
			)
		)
		(property "Value" "R_1k_0402"
			(at -1.011843 1.772046 90)
			(layer "F.Fab")
			(effects
				(font
					(size 0.7 0.7)
					(thickness 0.15)
				)
				(justify left bottom)
			)
		)
		(property "Datasheet" "https://www.bourns.com/docs/product-datasheets/cr.pdf"
			(at 0 0 90)
			(layer "F.Fab")
			(hide yes)
			(effects
				(font
					(size 1.27 1.27)
					(thickness 0.15)
				)
			)
		)
		(property "Description" "SMD Chip Resistor, 1 kohm, ± 1%, 63 mW, 0402 [1005 Metric], Thick Film, General Purpose"
			(at 0 0 90)
			(layer "F.Fab")
			(hide yes)
			(effects
				(font
					(size 1.27 1.27)
					(thickness 0.15)
				)
			)
		)
		(property "MPN" "CR0402-FX-1001GLF"
			(at 0 0 90)
			(unlocked yes)
			(layer "F.Fab")
			(hide yes)
			(effects
				(font
					(size 1 1)
					(thickness 0.15)
				)
			)
		)
		(property "Manufacturer" "Bourns"
			(at 0 0 90)
			(unlocked yes)
			(layer "F.Fab")
			(hide yes)
			(effects
				(font
					(size 1 1)
					(thickness 0.15)
				)
			)
		)
		(property "License" "Apache-2.0"
			(at 0 0 90)
			(unlocked yes)
			(layer "F.Fab")
			(hide yes)
			(effects
				(font
					(size 1 1)
					(thickness 0.15)
				)
			)
		)
		(property "Author" "Antmicro"
			(at 0 0 90)
			(unlocked yes)
			(layer "F.Fab")
			(hide yes)
			(effects
				(font
					(size 1 1)
					(thickness 0.15)
				)
			)
		)
		(property "Val" "1k"
			(at 0 0 90)
			(unlocked yes)
			(layer "F.Fab")
			(hide yes)
			(effects
				(font
					(size 1 1)
					(thickness 0.15)
				)
			)
		)
		(property "Tolerance" "1%"
			(at 0 0 90)
			(unlocked yes)
			(layer "F.Fab")
			(hide yes)
			(effects
				(font
					(size 1 1)
					(thickness 0.15)
				)
			)
		)
		(sheetname "/USB-PD/")
		(sheetfile "usb-pd.kicad_sch")
		(attr smd exclude_from_bom dnp)
		(fp_rect
			(start -0.925 -0.47)
			(end 0.925 0.47)
			(stroke
				(width 0.05)
				(type default)
			)
			(fill no)
			(layer "F.CrtYd")
		)
		(fp_rect
			(start -0.5 -0.25)
			(end 0.5 0.25)
			(stroke
				(width 0.15)
				(type solid)
			)
			(fill no)
			(layer "F.Fab")
		)
		(fp_text user "Author: Antmicro"
			(at -0.95 4.169 90)
			(layer "F.Fab")
			(effects
				(font
					(size 0.7 0.7)
					(thickness 0.15)
				)
				(justify left bottom)
			)
		)
		(fp_text user "${REFERENCE}"
			(at 0 0 90)
			(layer "F.Fab")
			(effects
				(font
					(size 0.7 0.7)
					(thickness 0.15)
				)
				(justify left bottom)
			)
		)
		(fp_text user "License: Apache-2.0"
			(at -0.949999 5.169 90)
			(layer "F.Fab")
			(effects
				(font
					(size 0.7 0.7)
					(thickness 0.15)
				)
				(justify left bottom)
			)
		)
		(pad "1" smd roundrect
			(at -0.48 0 90)
			(size 0.59 0.64)
			(layers "F.Cu" "F.Mask" "F.Paste")
			(roundrect_rratio 0.25)
			(net 66 "GND")
			(pintype "passive")
		)
		(pad "2" smd roundrect
			(at 0.48 0 90)
			(size 0.59 0.64)
			(layers "F.Cu" "F.Mask" "F.Paste")
			(roundrect_rratio 0.25)
			(net 138 "/USB-PD/ISNK_COARSE")
			(pintype "passive")
		)
	)
	(footprint "antmicro-footprints:C_0402_1005Metric"
		(layer "F.Cu")
		(at 148.151999 90 180)
		(descr "Capacitor SMD 0402")
		(tags "capacitor SMD 0402")
		(property "Reference" "C20"
			(at -3.448001 0.5 180)
			(layer "F.SilkS")
			(effects
				(font
					(size 0.7 0.7)
					(thickness 0.15)
				)
				(justify right top)
			)
		)
		(property "Value" "C_1u_25V_0402"
			(at -1.022927 2.155213 0)
			(layer "F.Fab")
			(effects
				(font
					(size 0.7 0.7)
					(thickness 0.15)
				)
				(justify right top)
			)
		)
		(property "Datasheet" "https://www.murata.com/products/productdetail?partno=GRM155R61E105KE11%23"
			(at 0 0 0)
			(layer "F.Fab")
			(hide yes)
			(effects
				(font
					(size 1.27 1.27)
					(thickness 0.15)
				)
			)
		)
		(property "Description" "SMD Multilayer Ceramic Capacitor, 1 µF, 25 V, 0402 [1005 Metric], ± 10%, X5R, GRM Series"
			(at 0 0 0)
			(layer "F.Fab")
			(hide yes)
			(effects
				(font
					(size 1.27 1.27)
					(thickness 0.15)
				)
			)
		)
		(property "MPN" "GRM155R61E105KE11J"
			(at 0 0 180)
			(unlocked yes)
			(layer "F.Fab")
			(hide yes)
			(effects
				(font
					(size 1 1)
					(thickness 0.15)
				)
			)
		)
		(property "Manufacturer" "Murata"
			(at 0 0 180)
			(unlocked yes)
			(layer "F.Fab")
			(hide yes)
			(effects
				(font
					(size 1 1)
					(thickness 0.15)
				)
			)
		)
		(property "License" "Apache-2.0"
			(at 0 0 180)
			(unlocked yes)
			(layer "F.Fab")
			(hide yes)
			(effects
				(font
					(size 1 1)
					(thickness 0.15)
				)
			)
		)
		(property "Author" "Antmicro"
			(at 0 0 180)
			(unlocked yes)
			(layer "F.Fab")
			(hide yes)
			(effects
				(font
					(size 1 1)
					(thickness 0.15)
				)
			)
		)
		(property "Val" "1u"
			(at 0 0 180)
			(unlocked yes)
			(layer "F.Fab")
			(hide yes)
			(effects
				(font
					(size 1 1)
					(thickness 0.15)
				)
			)
		)
		(property "Voltage" "25V"
			(at 0 0 180)
			(unlocked yes)
			(layer "F.Fab")
			(hide yes)
			(effects
				(font
					(size 1 1)
					(thickness 0.15)
				)
			)
		)
		(property "Dielectric" "X5R"
			(at 0 0 180)
			(unlocked yes)
			(layer "F.Fab")
			(hide yes)
			(effects
				(font
					(size 1 1)
					(thickness 0.15)
				)
			)
		)
		(sheetname "/USB-PD/")
		(sheetfile "usb-pd.kicad_sch")
		(attr smd)
		(fp_rect
			(start -0.925 -0.47)
			(end 0.925 0.47)
			(stroke
				(width 0.05)
				(type default)
			)
			(fill no)
			(layer "F.CrtYd")
		)
		(fp_line
			(start 0.504 0.248)
			(end -0.494 0.248)
			(stroke
				(width 0.15)
				(type solid)
			)
			(layer "F.Fab")
		)
		(fp_line
			(start 0.504 -0.25)
			(end 0.504 0.248)
			(stroke
				(width 0.15)
				(type solid)
			)
			(layer "F.Fab")
		)
		(fp_line
			(start -0.494 0.248)
			(end -0.494 -0.25)
			(stroke
				(width 0.15)
				(type solid)
			)
			(layer "F.Fab")
		)
		(fp_line
			(start -0.494 -0.25)
			(end 0.504 -0.25)
			(stroke
				(width 0.15)
				(type solid)
			)
			(layer "F.Fab")
		)
		(fp_text user "License: Apache-2.0"
			(at -0.939 5.799 0)
			(layer "F.Fab")
			(effects
				(font
					(size 0.7 0.7)
					(thickness 0.15)
				)
				(justify right top)
			)
		)
		(fp_text user "Author: Antmicro"
			(at -0.939 3.399 0)
			(layer "F.Fab")
			(effects
				(font
					(size 0.7 0.7)
					(thickness 0.15)
				)
				(justify right top)
			)
		)
		(fp_text user "${REFERENCE}"
			(at 0 0 0)
			(layer "F.Fab")
			(effects
				(font
					(size 0.7 0.7)
					(thickness 0.15)
				)
				(justify right top)
			)
		)
		(pad "1" smd roundrect
			(at -0.48 0 180)
			(size 0.59 0.64)
			(layers "F.Cu" "F.Mask" "F.Paste")
			(roundrect_rratio 0.25)
			(net 66 "GND")
			(pintype "passive")
		)
		(pad "2" smd roundrect
			(at 0.48 0 180)
			(size 0.59 0.64)
			(layers "F.Cu" "F.Mask" "F.Paste")
			(roundrect_rratio 0.25)
			(net 121 "/USB-PD/12V_VDD")
			(pintype "passive")
		)
	)
	(footprint "antmicro-footprints:C_0805_2012Metric"
		(layer "F.Cu")
		(at 138.2 93.5 -90)
		(descr "Capacitor SMD 0805")
		(tags "capacitor SMD 0805")
		(property "Reference" "C16"
			(at -2.5 5.6 90)
			(layer "F.SilkS")
			(effects
				(font
					(size 0.7 0.7)
					(thickness 0.15)
				)
				(justify right top)
			)
		)
		(property "Value" "C_22u_25V_0805"
			(at -2.055717 1.963153 90)
			(layer "F.Fab")
			(effects
				(font
					(size 0.7 0.7)
					(thickness 0.15)
				)
				(justify right top)
			)
		)
		(property "Datasheet" "https://product.samsungsem.com/mlcc/CL21A226MAYNNN.do"
			(at 0 0 90)
			(layer "F.Fab")
			(hide yes)
			(effects
				(font
					(size 1.27 1.27)
					(thickness 0.15)
				)
			)
		)
		(property "Description" "SMT Multilayer Ceramic Capacitor, 22uF, +/-20%, 25V, X5R, 0805 [2012 Metric]"
			(at 0 0 90)
			(layer "F.Fab")
			(hide yes)
			(effects
				(font
					(size 1.27 1.27)
					(thickness 0.15)
				)
			)
		)
		(property "MPN" "CL21A226MAYNNNE"
			(at 0 0 270)
			(unlocked yes)
			(layer "F.Fab")
			(hide yes)
			(effects
				(font
					(size 1 1)
					(thickness 0.15)
				)
			)
		)
		(property "Manufacturer" "Samsung Electro-Mechanics"
			(at 0 0 270)
			(unlocked yes)
			(layer "F.Fab")
			(hide yes)
			(effects
				(font
					(size 1 1)
					(thickness 0.15)
				)
			)
		)
		(property "License" "Apache-2.0"
			(at 0 0 270)
			(unlocked yes)
			(layer "F.Fab")
			(hide yes)
			(effects
				(font
					(size 1 1)
					(thickness 0.15)
				)
			)
		)
		(property "Author" "Antmicro"
			(at 0 0 270)
			(unlocked yes)
			(layer "F.Fab")
			(hide yes)
			(effects
				(font
					(size 1 1)
					(thickness 0.15)
				)
			)
		)
		(property "Val" "22u"
			(at 0 0 270)
			(unlocked yes)
			(layer "F.Fab")
			(hide yes)
			(effects
				(font
					(size 1 1)
					(thickness 0.15)
				)
			)
		)
		(property "Voltage" "25V"
			(at 0 0 270)
			(unlocked yes)
			(layer "F.Fab")
			(hide yes)
			(effects
				(font
					(size 1 1)
					(thickness 0.15)
				)
			)
		)
		(property "Dielectric" "X5R"
			(at 0 0 270)
			(unlocked yes)
			(layer "F.Fab")
			(hide yes)
			(effects
				(font
					(size 1 1)
					(thickness 0.15)
				)
			)
		)
		(property "Public" "False"
			(at 0 0 270)
			(unlocked yes)
			(layer "F.Fab")
			(hide yes)
			(effects
				(font
					(size 1 1)
					(thickness 0.15)
				)
			)
		)
		(sheetname "/USB-PD/")
		(sheetfile "usb-pd.kicad_sch")
		(attr smd)
		(fp_line
			(start -0.3 0.7)
			(end 0.3 0.7)
			(stroke
				(width 0.15)
				(type solid)
			)
			(layer "F.SilkS")
		)
		(fp_line
			(start -0.3 -0.7)
			(end 0.3 -0.7)
			(stroke
				(width 0.15)
				(type solid)
			)
			(layer "F.SilkS")
		)
		(fp_rect
			(start 1.95 -0.9)
			(end -1.95 0.9)
			(stroke
				(width 0.05)
				(type default)
			)
			(fill no)
			(layer "F.CrtYd")
		)
		(fp_rect
			(start -0.95 -0.675)
			(end 0.95 0.675)
			(stroke
				(width 0.15)
				(type solid)
			)
			(fill no)
			(layer "F.Fab")
		)
		(fp_text user "License: Apache-2.0"
			(at -1.9 4.947 90)
			(layer "F.Fab")
			(effects
				(font
					(size 0.7 0.7)
					(thickness 0.15)
				)
				(justify right top)
			)
		)
		(fp_text user "Author: Antmicro"
			(at -1.9 5.947 90)
			(layer "F.Fab")
			(effects
				(font
					(size 0.7 0.7)
					(thickness 0.15)
				)
				(justify right top)
			)
		)
		(fp_text user "${REFERENCE}"
			(at 0 0 90)
			(layer "F.Fab")
			(effects
				(font
					(size 0.7 0.7)
					(thickness 0.15)
				)
				(justify right top)
			)
		)
		(pad "1" smd roundrect
			(at -1.1 0 270)
			(size 1.2 1.3)
			(layers "F.Cu" "F.Mask" "F.Paste")
			(roundrect_rratio 0.25)
			(net 66 "GND")
			(pintype "passive")
		)
		(pad "2" smd roundrect
			(at 1.1 0 270)
			(size 1.2 1.3)
			(layers "F.Cu" "F.Mask" "F.Paste")
			(roundrect_rratio 0.25)
			(net 187 "/USB-PD/12V_CONV")
			(pintype "passive")
		)
	)
	(footprint "antmicro-footprints:R_0402_1005Metric"
		(layer "F.Cu")
		(at 120.5 132.8 180)
		(descr "Resistor SMD 0402")
		(tags "resistor SMD 0402")
		(property "Reference" "R5"
			(at 3.3 0.4 180)
			(layer "F.SilkS")
			(effects
				(font
					(size 0.7 0.7)
					(thickness 0.15)
				)
				(justify left top)
			)
		)
		(property "Value" "R_68k_0402"
			(at -1.011843 1.772046 0)
			(layer "F.Fab")
			(effects
				(font
					(size 0.7 0.7)
					(thickness 0.15)
				)
				(justify right top)
			)
		)
		(property "Datasheet" "https://www.bourns.com/docs/product-datasheets/cr.pdf"
			(at 0 0 0)
			(layer "F.Fab")
			(hide yes)
			(effects
				(font
					(size 1.27 1.27)
					(thickness 0.15)
				)
			)
		)
		(property "Description" "SMD Chip Resistor"
			(at 0 0 0)
			(layer "F.Fab")
			(hide yes)
			(effects
				(font
					(size 1.27 1.27)
					(thickness 0.15)
				)
			)
		)
		(property "MPN" "CR0402-FX-6802GLF"
			(at 0 0 180)
			(unlocked yes)
			(layer "F.Fab")
			(hide yes)
			(effects
				(font
					(size 1 1)
					(thickness 0.15)
				)
			)
		)
		(property "Manufacturer" "Bourns"
			(at 0 0 180)
			(unlocked yes)
			(layer "F.Fab")
			(hide yes)
			(effects
				(font
					(size 1 1)
					(thickness 0.15)
				)
			)
		)
		(property "License" "Apache-2.0"
			(at 0 0 180)
			(unlocked yes)
			(layer "F.Fab")
			(hide yes)
			(effects
				(font
					(size 1 1)
					(thickness 0.15)
				)
			)
		)
		(property "Author" "Antmicro"
			(at 0 0 180)
			(unlocked yes)
			(layer "F.Fab")
			(hide yes)
			(effects
				(font
					(size 1 1)
					(thickness 0.15)
				)
			)
		)
		(property "Val" "68k"
			(at 0 0 180)
			(unlocked yes)
			(layer "F.Fab")
			(hide yes)
			(effects
				(font
					(size 1 1)
					(thickness 0.15)
				)
			)
		)
		(property "Tolerance" "1%"
			(at 0 0 180)
			(unlocked yes)
			(layer "F.Fab")
			(hide yes)
			(effects
				(font
					(size 1 1)
					(thickness 0.15)
				)
			)
		)
		(sheetname "/Power/")
		(sheetfile "power.kicad_sch")
		(attr smd exclude_from_bom dnp)
		(fp_rect
			(start -0.925 -0.47)
			(end 0.925 0.47)
			(stroke
				(width 0.05)
				(type default)
			)
			(fill no)
			(layer "F.CrtYd")
		)
		(fp_rect
			(start -0.5 -0.25)
			(end 0.5 0.25)
			(stroke
				(width 0.15)
				(type solid)
			)
			(fill no)
			(layer "F.Fab")
		)
		(fp_text user "License: Apache-2.0"
			(at -0.949999 5.169 0)
			(layer "F.Fab")
			(effects
				(font
					(size 0.7 0.7)
					(thickness 0.15)
				)
				(justify right top)
			)
		)
		(fp_text user "Author: Antmicro"
			(at -0.95 4.169 0)
			(layer "F.Fab")
			(effects
				(font
					(size 0.7 0.7)
					(thickness 0.15)
				)
				(justify right top)
			)
		)
		(fp_text user "${REFERENCE}"
			(at 0 0 0)
			(layer "F.Fab")
			(effects
				(font
					(size 0.7 0.7)
					(thickness 0.15)
				)
				(justify right top)
			)
		)
		(pad "1" smd roundrect
			(at -0.48 0 180)
			(size 0.59 0.64)
			(layers "F.Cu" "F.Mask" "F.Paste")
			(roundrect_rratio 0.25)
			(net 107 "/Power/3V3_MODE")
			(pintype "passive")
		)
		(pad "2" smd roundrect
			(at 0.48 0 180)
			(size 0.59 0.64)
			(layers "F.Cu" "F.Mask" "F.Paste")
			(roundrect_rratio 0.25)
			(net 88 "/Power/3V3_VCC")
			(pintype "passive")
		)
	)
	(footprint "antmicro-footprints:C_0402_1005Metric"
		(layer "F.Cu")
		(at 154.9 47.62 90)
		(descr "Capacitor SMD 0402")
		(tags "capacitor SMD 0402")
		(property "Reference" "C38"
			(at 1.02 1.699999 90)
			(layer "F.SilkS")
			(effects
				(font
					(size 0.7 0.7)
					(thickness 0.15)
				)
				(justify right top)
			)
		)
		(property "Value" "C_1u_25V_0402"
			(at -1.022927 2.155213 90)
			(layer "F.Fab")
			(effects
				(font
					(size 0.7 0.7)
					(thickness 0.15)
				)
				(justify left bottom)
			)
		)
		(property "Datasheet" "https://www.murata.com/products/productdetail?partno=GRM155R61E105KE11%23"
			(at 0 0 90)
			(layer "F.Fab")
			(hide yes)
			(effects
				(font
					(size 1.27 1.27)
					(thickness 0.15)
				)
			)
		)
		(property "Description" "SMD Multilayer Ceramic Capacitor, 1 µF, 25 V, 0402 [1005 Metric], ± 10%, X5R, GRM Series"
			(at 0 0 90)
			(layer "F.Fab")
			(hide yes)
			(effects
				(font
					(size 1.27 1.27)
					(thickness 0.15)
				)
			)
		)
		(property "MPN" "GRM155R61E105KE11J"
			(at 0 0 90)
			(unlocked yes)
			(layer "F.Fab")
			(hide yes)
			(effects
				(font
					(size 1 1)
					(thickness 0.15)
				)
			)
		)
		(property "Manufacturer" "Murata"
			(at 0 0 90)
			(unlocked yes)
			(layer "F.Fab")
			(hide yes)
			(effects
				(font
					(size 1 1)
					(thickness 0.15)
				)
			)
		)
		(property "License" "Apache-2.0"
			(at 0 0 90)
			(unlocked yes)
			(layer "F.Fab")
			(hide yes)
			(effects
				(font
					(size 1 1)
					(thickness 0.15)
				)
			)
		)
		(property "Author" "Antmicro"
			(at 0 0 90)
			(unlocked yes)
			(layer "F.Fab")
			(hide yes)
			(effects
				(font
					(size 1 1)
					(thickness 0.15)
				)
			)
		)
		(property "Val" "1u"
			(at 0 0 90)
			(unlocked yes)
			(layer "F.Fab")
			(hide yes)
			(effects
				(font
					(size 1 1)
					(thickness 0.15)
				)
			)
		)
		(property "Voltage" "25V"
			(at 0 0 90)
			(unlocked yes)
			(layer "F.Fab")
			(hide yes)
			(effects
				(font
					(size 1 1)
					(thickness 0.15)
				)
			)
		)
		(property "Dielectric" "X5R"
			(at 0 0 90)
			(unlocked yes)
			(layer "F.Fab")
			(hide yes)
			(effects
				(font
					(size 1 1)
					(thickness 0.15)
				)
			)
		)
		(sheetname "/USB-PD/")
		(sheetfile "usb-pd.kicad_sch")
		(attr smd dnp)
		(fp_rect
			(start -0.925 -0.47)
			(end 0.925 0.47)
			(stroke
				(width 0.05)
				(type default)
			)
			(fill no)
			(layer "F.CrtYd")
		)
		(fp_line
			(start 0.504 -0.25)
			(end 0.504 0.248)
			(stroke
				(width 0.15)
				(type solid)
			)
			(layer "F.Fab")
		)
		(fp_line
			(start -0.494 -0.25)
			(end 0.504 -0.25)
			(stroke
				(width 0.15)
				(type solid)
			)
			(layer "F.Fab")
		)
		(fp_line
			(start 0.504 0.248)
			(end -0.494 0.248)
			(stroke
				(width 0.15)
				(type solid)
			)
			(layer "F.Fab")
		)
		(fp_line
			(start -0.494 0.248)
			(end -0.494 -0.25)
			(stroke
				(width 0.15)
				(type solid)
			)
			(layer "F.Fab")
		)
		(fp_text user "License: Apache-2.0"
			(at -0.939 5.799 90)
			(layer "F.Fab")
			(effects
				(font
					(size 0.7 0.7)
					(thickness 0.15)
				)
				(justify left bottom)
			)
		)
		(fp_text user "${REFERENCE}"
			(at 0 0 270)
			(layer "F.Fab")
			(effects
				(font
					(size 0.7 0.7)
					(thickness 0.15)
				)
				(justify right top)
			)
		)
		(fp_text user "Author: Antmicro"
			(at -0.939 3.399 90)
			(layer "F.Fab")
			(effects
				(font
					(size 0.7 0.7)
					(thickness 0.15)
				)
				(justify left bottom)
			)
		)
		(pad "1" smd roundrect
			(at -0.48 0 90)
			(size 0.59 0.64)
			(layers "F.Cu" "F.Mask" "F.Paste")
			(roundrect_rratio 0.25)
			(net 84 "Net-(Q6-G)")
			(pintype "passive")
		)
		(pad "2" smd roundrect
			(at 0.48 0 90)
			(size 0.59 0.64)
			(layers "F.Cu" "F.Mask" "F.Paste")
			(roundrect_rratio 0.25)
			(net 115 "/USB-PD/VCC")
			(pintype "passive")
		)
	)
	(footprint "antmicro-footprints:C_Pol_Vishay-T59-EE"
		(layer "F.Cu")
		(at 127.9 110 180)
		(property "Reference" "C29"
			(at -4.9 -0.2 180)
			(layer "F.SilkS")
			(effects
				(font
					(size 0.7 0.7)
					(thickness 0.15)
				)
				(justify left bottom)
			)
		)
		(property "Value" "C_Pol_150u_30V_Vishay-T59-EE"
			(at -5.08 5.08 180)
			(unlocked yes)
			(layer "F.Fab")
			(effects
				(font
					(size 0.7 0.7)
					(thickness 0.15)
				)
				(justify left bottom)
			)
		)
		(property "Datasheet" "https://www.vishay.com/docs/40191/t59.pdf"
			(at 0 0 0)
			(layer "F.Fab")
			(hide yes)
			(effects
				(font
					(size 1.27 1.27)
					(thickness 0.15)
				)
			)
		)
		(property "Description" "Tantalum Capacitors - Polymer 150uF 30volts 20% 75mohms maxESR"
			(at 0 0 0)
			(layer "F.Fab")
			(hide yes)
			(effects
				(font
					(size 1.27 1.27)
					(thickness 0.15)
				)
			)
		)
		(property "MPN" "T59EE157M030C0075"
			(at 0 0 180)
			(unlocked yes)
			(layer "F.Fab")
			(hide yes)
			(effects
				(font
					(size 1 1)
					(thickness 0.15)
				)
			)
		)
		(property "Manufacturer" "Vishay"
			(at 0 0 180)
			(unlocked yes)
			(layer "F.Fab")
			(hide yes)
			(effects
				(font
					(size 1 1)
					(thickness 0.15)
				)
			)
		)
		(property "Voltage" "30V"
			(at 0 0 180)
			(unlocked yes)
			(layer "F.Fab")
			(hide yes)
			(effects
				(font
					(size 1 1)
					(thickness 0.15)
				)
			)
		)
		(property "Val" "150u"
			(at 0 0 180)
			(unlocked yes)
			(layer "F.Fab")
			(hide yes)
			(effects
				(font
					(size 1 1)
					(thickness 0.15)
				)
			)
		)
		(property "Author" "Antmicro"
			(at 0 0 180)
			(unlocked yes)
			(layer "F.Fab")
			(hide yes)
			(effects
				(font
					(size 1 1)
					(thickness 0.15)
				)
			)
		)
		(property "License" "Apache-2.0"
			(at 0 0 180)
			(unlocked yes)
			(layer "F.Fab")
			(hide yes)
			(effects
				(font
					(size 1 1)
					(thickness 0.15)
				)
			)
		)
		(property "Dielectric" "template_dielectric"
			(at 0 0 180)
			(unlocked yes)
			(layer "F.Fab")
			(hide yes)
			(effects
				(font
					(size 1 1)
					(thickness 0.15)
				)
			)
		)
		(sheetname "/Power/")
		(sheetfile "power.kicad_sch")
		(attr smd)
		(fp_line
			(start -2 2.25)
			(end 2 2.25)
			(stroke
				(width 0.15)
				(type solid)
			)
			(layer "F.SilkS")
		)
		(fp_line
			(start -2 -2.25)
			(end 2 -2.25)
			(stroke
				(width 0.15)
				(type solid)
			)
			(layer "F.SilkS")
		)
		(fp_line
			(start -3.5 -2.8)
			(end -3.5 -3.2)
			(stroke
				(width 0.15)
				(type solid)
			)
			(layer "F.SilkS")
		)
		(fp_line
			(start -3.7 -3)
			(end -3.3 -3)
			(stroke
				(width 0.15)
				(type solid)
			)
			(layer "F.SilkS")
		)
		(fp_rect
			(start -4.9 -2.9)
			(end 4.9 2.9)
			(stroke
				(width 0.05)
				(type solid)
			)
			(fill no)
			(layer "F.CrtYd")
		)
		(fp_rect
			(start -3.75 -2.25)
			(end 3.75 2.25)
			(stroke
				(width 0.15)
				(type solid)
			)
			(fill no)
			(layer "F.Fab")
		)
		(fp_text user "Author: Antmicro"
			(at -5.079999 7.08 0)
			(layer "F.Fab")
			(effects
				(font
					(size 0.7 0.7)
					(thickness 0.15)
				)
				(justify right top)
			)
		)
		(fp_text user "License: Apache-2.0"
			(at -5.08 9.48 0)
			(layer "F.Fab")
			(effects
				(font
					(size 0.7 0.7)
					(thickness 0.15)
				)
				(justify right top)
			)
		)
		(fp_text user "${REFERENCE}"
			(at 0 -0.175 180)
			(layer "F.Fab")
			(effects
				(font
					(size 0.7 0.7)
					(thickness 0.15)
				)
				(justify left bottom)
			)
		)
		(pad "1" smd trapezoid
			(at -3.4 0 180)
			(size 2.5 5.3)
			(layers "F.Cu" "F.Mask" "F.Paste")
			(net 87 "+12V")
			(pintype "passive")
		)
		(pad "2" smd trapezoid
			(at 3.4 0 180)
			(size 2.5 5.3)
			(layers "F.Cu" "F.Mask" "F.Paste")
			(net 66 "GND")
			(pintype "passive")
		)
	)
	(footprint "antmicro-footprints:C_0402_1005Metric"
		(layer "F.Cu")
		(at 142.502 87.95 180)
		(descr "Capacitor SMD 0402")
		(tags "capacitor SMD 0402")
		(property "Reference" "C27"
			(at 0.902 0.35 180)
			(layer "F.SilkS")
			(effects
				(font
					(size 0.7 0.7)
					(thickness 0.15)
				)
				(justify right top)
			)
		)
		(property "Value" "C_100n_0402"
			(at -1.022927 2.155213 0)
			(layer "F.Fab")
			(effects
				(font
					(size 0.7 0.7)
					(thickness 0.15)
				)
				(justify right top)
			)
		)
		(property "Datasheet" "https://www.murata.com/products/productdetail?partno=GRM155R61H104KE14%23"
			(at 0 0 0)
			(layer "F.Fab")
			(hide yes)
			(effects
				(font
					(size 1.27 1.27)
					(thickness 0.15)
				)
			)
		)
		(property "Description" "SMD Multilayer Ceramic Capacitor, 0.1 µF, 50 V, 0402 [1005 Metric], ± 10%, X5R, GRM Series"
			(at 0 0 0)
			(layer "F.Fab")
			(hide yes)
			(effects
				(font
					(size 1.27 1.27)
					(thickness 0.15)
				)
			)
		)
		(property "MPN" "GRM155R61H104KE14D"
			(at 0 0 180)
			(unlocked yes)
			(layer "F.Fab")
			(hide yes)
			(effects
				(font
					(size 1 1)
					(thickness 0.15)
				)
			)
		)
		(property "Val" "100n"
			(at 0 0 180)
			(unlocked yes)
			(layer "F.Fab")
			(hide yes)
			(effects
				(font
					(size 1 1)
					(thickness 0.15)
				)
			)
		)
		(property "Voltage" "50V"
			(at 0 0 180)
			(unlocked yes)
			(layer "F.Fab")
			(hide yes)
			(effects
				(font
					(size 1 1)
					(thickness 0.15)
				)
			)
		)
		(property "Dielectric" "X5R"
			(at 0 0 180)
			(unlocked yes)
			(layer "F.Fab")
			(hide yes)
			(effects
				(font
					(size 1 1)
					(thickness 0.15)
				)
			)
		)
		(property "Manufacturer" "Murata"
			(at 0 0 180)
			(unlocked yes)
			(layer "F.Fab")
			(hide yes)
			(effects
				(font
					(size 1 1)
					(thickness 0.15)
				)
			)
		)
		(property "License" "Apache-2.0"
			(at 0 0 180)
			(unlocked yes)
			(layer "F.Fab")
			(hide yes)
			(effects
				(font
					(size 1 1)
					(thickness 0.15)
				)
			)
		)
		(property "Author" "Antmicro"
			(at 0 0 180)
			(unlocked yes)
			(layer "F.Fab")
			(hide yes)
			(effects
				(font
					(size 1 1)
					(thickness 0.15)
				)
			)
		)
		(sheetname "/USB-PD/")
		(sheetfile "usb-pd.kicad_sch")
		(attr smd)
		(fp_rect
			(start -0.925 -0.47)
			(end 0.925 0.47)
			(stroke
				(width 0.05)
				(type default)
			)
			(fill no)
			(layer "F.CrtYd")
		)
		(fp_line
			(start 0.504 0.248)
			(end -0.494 0.248)
			(stroke
				(width 0.15)
				(type solid)
			)
			(layer "F.Fab")
		)
		(fp_line
			(start 0.504 -0.25)
			(end 0.504 0.248)
			(stroke
				(width 0.15)
				(type solid)
			)
			(layer "F.Fab")
		)
		(fp_line
			(start -0.494 0.248)
			(end -0.494 -0.25)
			(stroke
				(width 0.15)
				(type solid)
			)
			(layer "F.Fab")
		)
		(fp_line
			(start -0.494 -0.25)
			(end 0.504 -0.25)
			(stroke
				(width 0.15)
				(type solid)
			)
			(layer "F.Fab")
		)
		(fp_text user "License: Apache-2.0"
			(at -0.939 5.799 0)
			(layer "F.Fab")
			(effects
				(font
					(size 0.7 0.7)
					(thickness 0.15)
				)
				(justify right top)
			)
		)
		(fp_text user "Author: Antmicro"
			(at -0.939 3.399 0)
			(layer "F.Fab")
			(effects
				(font
					(size 0.7 0.7)
					(thickness 0.15)
				)
				(justify right top)
			)
		)
		(fp_text user "${REFERENCE}"
			(at 0 0 0)
			(layer "F.Fab")
			(effects
				(font
					(size 0.7 0.7)
					(thickness 0.15)
				)
				(justify right top)
			)
		)
		(pad "1" smd roundrect
			(at -0.48 0 180)
			(size 0.59 0.64)
			(layers "F.Cu" "F.Mask" "F.Paste")
			(roundrect_rratio 0.25)
			(net 122 "/USB-PD/12V_BOOT")
			(pintype "passive")
		)
		(pad "2" smd roundrect
			(at 0.48 0 180)
			(size 0.59 0.64)
			(layers "F.Cu" "F.Mask" "F.Paste")
			(roundrect_rratio 0.25)
			(net 120 "Net-(C27-Pad2)")
			(pintype "passive")
		)
	)
	(footprint "antmicro-footprints:C_0402_1005Metric"
		(layer "F.Cu")
		(at 139.75 91 90)
		(descr "Capacitor SMD 0402")
		(tags "capacitor SMD 0402")
		(property "Reference" "C26"
			(at -3.2 0.45 90)
			(layer "F.SilkS")
			(effects
				(font
					(size 0.7 0.7)
					(thickness 0.15)
				)
				(justify left bottom)
			)
		)
		(property "Value" "C_100n_0402"
			(at -1.022927 2.155213 90)
			(layer "F.Fab")
			(effects
				(font
					(size 0.7 0.7)
					(thickness 0.15)
				)
				(justify left bottom)
			)
		)
		(property "Datasheet" "https://www.murata.com/products/productdetail?partno=GRM155R61H104KE14%23"
			(at 0 0 90)
			(layer "F.Fab")
			(hide yes)
			(effects
				(font
					(size 1.27 1.27)
					(thickness 0.15)
				)
			)
		)
		(property "Description" "SMD Multilayer Ceramic Capacitor, 0.1 µF, 50 V, 0402 [1005 Metric], ± 10%, X5R, GRM Series"
			(at 0 0 90)
			(layer "F.Fab")
			(hide yes)
			(effects
				(font
					(size 1.27 1.27)
					(thickness 0.15)
				)
			)
		)
		(property "MPN" "GRM155R61H104KE14D"
			(at 0 0 90)
			(unlocked yes)
			(layer "F.Fab")
			(hide yes)
			(effects
				(font
					(size 1 1)
					(thickness 0.15)
				)
			)
		)
		(property "Val" "100n"
			(at 0 0 90)
			(unlocked yes)
			(layer "F.Fab")
			(hide yes)
			(effects
				(font
					(size 1 1)
					(thickness 0.15)
				)
			)
		)
		(property "Voltage" "50V"
			(at 0 0 90)
			(unlocked yes)
			(layer "F.Fab")
			(hide yes)
			(effects
				(font
					(size 1 1)
					(thickness 0.15)
				)
			)
		)
		(property "Dielectric" "X5R"
			(at 0 0 90)
			(unlocked yes)
			(layer "F.Fab")
			(hide yes)
			(effects
				(font
					(size 1 1)
					(thickness 0.15)
				)
			)
		)
		(property "Manufacturer" "Murata"
			(at 0 0 90)
			(unlocked yes)
			(layer "F.Fab")
			(hide yes)
			(effects
				(font
					(size 1 1)
					(thickness 0.15)
				)
			)
		)
		(property "License" "Apache-2.0"
			(at 0 0 90)
			(unlocked yes)
			(layer "F.Fab")
			(hide yes)
			(effects
				(font
					(size 1 1)
					(thickness 0.15)
				)
			)
		)
		(property "Author" "Antmicro"
			(at 0 0 90)
			(unlocked yes)
			(layer "F.Fab")
			(hide yes)
			(effects
				(font
					(size 1 1)
					(thickness 0.15)
				)
			)
		)
		(sheetname "/USB-PD/")
		(sheetfile "usb-pd.kicad_sch")
		(attr smd)
		(fp_rect
			(start -0.925 -0.47)
			(end 0.925 0.47)
			(stroke
				(width 0.05)
				(type default)
			)
			(fill no)
			(layer "F.CrtYd")
		)
		(fp_line
			(start 0.504 -0.25)
			(end 0.504 0.248)
			(stroke
				(width 0.15)
				(type solid)
			)
			(layer "F.Fab")
		)
		(fp_line
			(start -0.494 -0.25)
			(end 0.504 -0.25)
			(stroke
				(width 0.15)
				(type solid)
			)
			(layer "F.Fab")
		)
		(fp_line
			(start 0.504 0.248)
			(end -0.494 0.248)
			(stroke
				(width 0.15)
				(type solid)
			)
			(layer "F.Fab")
		)
		(fp_line
			(start -0.494 0.248)
			(end -0.494 -0.25)
			(stroke
				(width 0.15)
				(type solid)
			)
			(layer "F.Fab")
		)
		(fp_text user "License: Apache-2.0"
			(at -0.939 5.799 90)
			(layer "F.Fab")
			(effects
				(font
					(size 0.7 0.7)
					(thickness 0.15)
				)
				(justify left bottom)
			)
		)
		(fp_text user "${REFERENCE}"
			(at 0 0 90)
			(layer "F.Fab")
			(effects
				(font
					(size 0.7 0.7)
					(thickness 0.15)
				)
				(justify left bottom)
			)
		)
		(fp_text user "Author: Antmicro"
			(at -0.939 3.399 90)
			(layer "F.Fab")
			(effects
				(font
					(size 0.7 0.7)
					(thickness 0.15)
				)
				(justify left bottom)
			)
		)
		(pad "1" smd roundrect
			(at -0.48 0 90)
			(size 0.59 0.64)
			(layers "F.Cu" "F.Mask" "F.Paste")
			(roundrect_rratio 0.25)
			(net 66 "GND")
			(pintype "passive")
		)
		(pad "2" smd roundrect
			(at 0.48 0 90)
			(size 0.59 0.64)
			(layers "F.Cu" "F.Mask" "F.Paste")
			(roundrect_rratio 0.25)
			(net 115 "/USB-PD/VCC")
			(pintype "passive")
		)
	)
	(footprint "antmicro-footprints:LED_0603_1608Metric_G"
		(layer "F.Cu")
		(at 151.5 159.71)
		(descr "LED SMD 0603 Green")
		(tags "LED SMD 0603 Green")
		(property "Reference" "D3"
			(at -0.75 1.58 0)
			(layer "F.SilkS")
			(effects
				(font
					(size 0.7 0.7)
					(thickness 0.15)
				)
				(justify left bottom)
			)
		)
		(property "Value" "LED_G_0603_LTST-C190GKT"
			(at -0.001 1.599 0)
			(layer "F.Fab")
			(effects
				(font
					(size 0.7 0.7)
					(thickness 0.15)
				)
				(justify left bottom)
			)
		)
		(property "Datasheet" "https://media.digikey.com/pdf/Data%20Sheets/Lite-On%20PDFs/LTST-C190GKT.pdf"
			(at 0 0 0)
			(layer "F.Fab")
			(hide yes)
			(effects
				(font
					(size 1.27 1.27)
					(thickness 0.15)
				)
			)
		)
		(property "Description" "LED, Green, SMD, 0603, 20 mA, 2.1 V, 569 nm"
			(at 0 0 0)
			(layer "F.Fab")
			(hide yes)
			(effects
				(font
					(size 1.27 1.27)
					(thickness 0.15)
				)
			)
		)
		(property "MPN" "LTST-C190GKT"
			(at 0 0 0)
			(unlocked yes)
			(layer "F.Fab")
			(hide yes)
			(effects
				(font
					(size 1 1)
					(thickness 0.15)
				)
			)
		)
		(property "Manufacturer" "Lite-On"
			(at 0 0 0)
			(unlocked yes)
			(layer "F.Fab")
			(hide yes)
			(effects
				(font
					(size 1 1)
					(thickness 0.15)
				)
			)
		)
		(property "Color" "Green"
			(at 0 0 0)
			(unlocked yes)
			(layer "F.Fab")
			(hide yes)
			(effects
				(font
					(size 1 1)
					(thickness 0.15)
				)
			)
		)
		(property "Author" "Antmicro"
			(at 0 0 0)
			(unlocked yes)
			(layer "F.Fab")
			(hide yes)
			(effects
				(font
					(size 1 1)
					(thickness 0.15)
				)
			)
		)
		(property "License" "Apache-2.0"
			(at 0 0 0)
			(unlocked yes)
			(layer "F.Fab")
			(hide yes)
			(effects
				(font
					(size 1 1)
					(thickness 0.15)
				)
			)
		)
		(sheetname "/Power/")
		(sheetfile "power.kicad_sch")
		(attr smd)
		(fp_line
			(start -1.18 -0.319)
			(end -1.18 0.321)
			(stroke
				(width 0.15)
				(type solid)
			)
			(layer "F.SilkS")
		)
		(fp_line
			(start -0.094672 0.001008)
			(end -0.24 0.001008)
			(stroke
				(width 0.1)
				(type solid)
			)
			(layer "F.SilkS")
		)
		(fp_line
			(start -0.094672 0.001008)
			(end 0.105328 -0.198992)
			(stroke
				(width 0.1)
				(type solid)
			)
			(layer "F.SilkS")
		)
		(fp_line
			(start -0.094672 0.201008)
			(end -0.094672 -0.198992)
			(stroke
				(width 0.1)
				(type solid)
			)
			(layer "F.SilkS")
		)
		(fp_line
			(start 0.105328 0.001008)
			(end 0.24 0.001)
			(stroke
				(width 0.1)
				(type solid)
			)
			(layer "F.SilkS")
		)
		(fp_line
			(start 0.105328 0.201008)
			(end -0.094672 0.001008)
			(stroke
				(width 0.1)
				(type solid)
			)
			(layer "F.SilkS")
		)
		(fp_line
			(start 0.105328 0.201008)
			(end 0.105328 -0.198992)
			(stroke
				(width 0.1)
				(type solid)
			)
			(layer "F.SilkS")
		)
		(fp_line
			(start 0.22 -0.35)
			(end -0.22 -0.35)
			(stroke
				(width 0.15)
				(type solid)
			)
			(layer "F.SilkS")
		)
		(fp_line
			(start 0.22 0.35)
			(end -0.22 0.35)
			(stroke
				(width 0.15)
				(type solid)
			)
			(layer "F.SilkS")
		)
		(fp_rect
			(start 1.25 0.65)
			(end -1.25 -0.65)
			(stroke
				(width 0.05)
				(type solid)
			)
			(fill no)
			(layer "F.CrtYd")
		)
		(fp_line
			(start -0.199 -0.202)
			(end -0.199 0.1)
			(stroke
				(width 0.15)
				(type solid)
			)
			(layer "F.Fab")
		)
		(fp_line
			(start -0.199 0)
			(end -0.597 0)
			(stroke
				(width 0.15)
				(type solid)
			)
			(layer "F.Fab")
		)
		(fp_line
			(start -0.199 0.2)
			(end -0.199 0.1)
			(stroke
				(width 0.15)
				(type solid)
			)
			(layer "F.Fab")
		)
		(fp_line
			(start -0.101 0)
			(end 0.201 0.2)
			(stroke
				(width 0.15)
				(type solid)
			)
			(layer "F.Fab")
		)
		(fp_line
			(start 0.201 -0.202)
			(end -0.101 0)
			(stroke
				(width 0.15)
				(type solid)
			)
			(layer "F.Fab")
		)
		(fp_line
			(start 0.201 0)
			(end 0.201 -0.202)
			(stroke
				(width 0.15)
				(type solid)
			)
			(layer "F.Fab")
		)
		(fp_line
			(start 0.201 0.2)
			(end 0.201 0)
			(stroke
				(width 0.15)
				(type solid)
			)
			(layer "F.Fab")
		)
		(fp_line
			(start 0.599 0)
			(end 0.201 0)
			(stroke
				(width 0.15)
				(type solid)
			)
			(layer "F.Fab")
		)
		(fp_rect
			(start 0.848 0.4)
			(end -0.85 -0.402)
			(stroke
				(width 0.15)
				(type solid)
			)
			(fill no)
			(layer "F.Fab")
		)
		(fp_text user "Author: Antmicro"
			(at -1.4224 4.799 0)
			(layer "F.Fab")
			(effects
				(font
					(size 0.7 0.7)
					(thickness 0.15)
				)
				(justify left bottom)
			)
		)
		(fp_text user "License: Apache-2.0"
			(at -1.4224 3.599 0)
			(layer "F.Fab")
			(effects
				(font
					(size 0.7 0.7)
					(thickness 0.15)
				)
				(justify left bottom)
			)
		)
		(fp_text user "${REFERENCE}"
			(at 0 0 0)
			(layer "F.Fab")
			(effects
				(font
					(size 0.7 0.7)
					(thickness 0.15)
				)
				(justify left bottom)
			)
		)
		(pad "1" smd roundrect
			(at -0.7 0 180)
			(size 0.8 1)
			(layers "F.Cu" "F.Mask" "F.Paste")
			(roundrect_rratio 0.2)
			(net 91 "Net-(D3-C)")
			(pinfunction "C")
			(pintype "passive")
		)
		(pad "2" smd roundrect
			(at 0.7 0 180)
			(size 0.8 1)
			(layers "F.Cu" "F.Mask" "F.Paste")
			(roundrect_rratio 0.2)
			(net 134 "+3V3")
			(pinfunction "A")
			(pintype "passive")
		)
	)
	(footprint "antmicro-footprints:MP_Pad6mm_Drill3.2mm"
		(layer "F.Cu")
		(at 104.8 34.2 -90)
		(property "Reference" "MP3"
			(at 0 0 90)
			(layer "F.SilkS")
			(hide yes)
			(effects
				(font
					(size 0.7 0.7)
					(thickness 0.15)
				)
				(justify right top)
			)
		)
		(property "Value" "MP_Pad6mm_Drill3.2mm"
			(at 0 3.899999 90)
			(layer "F.Fab")
			(effects
				(font
					(size 0.7 0.7)
					(thickness 0.15)
				)
				(justify right top)
			)
		)
		(property "Description" "Mechanical part"
			(at 0 0 90)
			(layer "F.Fab")
			(hide yes)
			(effects
				(font
					(size 1.27 1.27)
					(thickness 0.15)
				)
			)
		)
		(property "Author" "Antmicro"
			(at 0 0 270)
			(unlocked yes)
			(layer "F.Fab")
			(hide yes)
			(effects
				(font
					(size 1 1)
					(thickness 0.15)
				)
			)
		)
		(property "License" "Apache-2.0"
			(at 0 0 270)
			(unlocked yes)
			(layer "F.Fab")
			(hide yes)
			(effects
				(font
					(size 1 1)
					(thickness 0.15)
				)
			)
		)
		(sheetname "/")
		(sheetfile "oculink-to-pcie-adapter.kicad_sch")
		(attr exclude_from_pos_files exclude_from_bom)
		(fp_circle
			(center 0 0)
			(end 3.25 0)
			(stroke
				(width 0.05)
				(type default)
			)
			(fill no)
			(layer "F.CrtYd")
		)
		(fp_text user "Author: Antmicro"
			(at -0.178001 7.225 90)
			(layer "F.Fab")
			(effects
				(font
					(size 0.7 0.7)
					(thickness 0.15)
				)
				(justify right top)
			)
		)
		(fp_text user "License: Apache-2.0"
			(at -0.178 8.425001 90)
			(layer "F.Fab")
			(effects
				(font
					(size 0.7 0.7)
					(thickness 0.15)
				)
				(justify right top)
			)
		)
		(fp_text user "${REFERENCE}"
			(at 0 0 90)
			(layer "F.Fab")
			(effects
				(font
					(size 0.7 0.7)
					(thickness 0.15)
				)
				(justify right top)
			)
		)
		(pad "1" thru_hole circle
			(at 0 0 270)
			(size 6 6)
			(drill 3.2)
			(layers "*.Cu" "*.Mask")
			(remove_unused_layers no)
			(net 66 "GND")
			(pintype "passive")
		)
	)
	(footprint "antmicro-footprints:L_Abracon_ASPIAIG-Q8080"
		(layer "F.Cu")
		(at 140 100.75 180)
		(property "Reference" "L2"
			(at -2.2 -5.85 180)
			(layer "F.SilkS")
			(effects
				(font
					(size 0.7 0.7)
					(thickness 0.15)
				)
				(justify left bottom)
			)
		)
		(property "Value" "L_4u7_14.6A_Abracon-Q8080"
			(at 0 10.16 180)
			(unlocked yes)
			(layer "F.Fab")
			(effects
				(font
					(size 0.7 0.7)
					(thickness 0.15)
				)
				(justify left bottom)
			)
		)
		(property "Datasheet" "https://www.mouser.com/datasheet/2/3/ASPIAIG_Q8080-2256550.pdf"
			(at 0 0 0)
			(layer "F.Fab")
			(hide yes)
			(effects
				(font
					(size 1.27 1.27)
					(thickness 0.15)
				)
			)
		)
		(property "Description" "Power Inductors - SMD 4.7 UH 20%"
			(at 0 0 0)
			(layer "F.Fab")
			(hide yes)
			(effects
				(font
					(size 1.27 1.27)
					(thickness 0.15)
				)
			)
		)
		(property "MPN" "ASPIAIG-Q8080-4R7M-T"
			(at 0 0 180)
			(unlocked yes)
			(layer "F.Fab")
			(hide yes)
			(effects
				(font
					(size 1 1)
					(thickness 0.15)
				)
			)
		)
		(property "ISat" "17A"
			(at 0 0 180)
			(unlocked yes)
			(layer "F.Fab")
			(hide yes)
			(effects
				(font
					(size 1 1)
					(thickness 0.15)
				)
			)
		)
		(property "IMax" "14.6A"
			(at 0 0 180)
			(unlocked yes)
			(layer "F.Fab")
			(hide yes)
			(effects
				(font
					(size 1 1)
					(thickness 0.15)
				)
			)
		)
		(property "Size" "8.9x8.5"
			(at 0 0 180)
			(unlocked yes)
			(layer "F.Fab")
			(hide yes)
			(effects
				(font
					(size 1 1)
					(thickness 0.15)
				)
			)
		)
		(property "Val" "4.7u/14.6A"
			(at 0 0 180)
			(unlocked yes)
			(layer "F.Fab")
			(hide yes)
			(effects
				(font
					(size 1 1)
					(thickness 0.15)
				)
			)
		)
		(property "Author" "Antmicro"
			(at 0 0 180)
			(unlocked yes)
			(layer "F.Fab")
			(hide yes)
			(effects
				(font
					(size 1 1)
					(thickness 0.15)
				)
			)
		)
		(property "License" "Apache-2.0"
			(at 0 0 180)
			(unlocked yes)
			(layer "F.Fab")
			(hide yes)
			(effects
				(font
					(size 1 1)
					(thickness 0.15)
				)
			)
		)
		(property "Manufacturer" "Abracon"
			(at 0 0 180)
			(unlocked yes)
			(layer "F.Fab")
			(hide yes)
			(effects
				(font
					(size 1 1)
					(thickness 0.15)
				)
			)
		)
		(sheetname "/USB-PD/")
		(sheetfile "usb-pd.kicad_sch")
		(attr smd)
		(fp_rect
			(start -4.6 -4.4)
			(end 4.6 4.4)
			(stroke
				(width 0.15)
				(type default)
			)
			(fill no)
			(layer "F.SilkS")
		)
		(fp_rect
			(start -4.85 -4.64)
			(end 4.85 4.64)
			(stroke
				(width 0.05)
				(type solid)
			)
			(fill no)
			(layer "F.CrtYd")
		)
		(fp_rect
			(start -4.597 -4.394)
			(end 4.597 4.394)
			(stroke
				(width 0.15)
				(type default)
			)
			(fill no)
			(layer "F.Fab")
		)
		(fp_text user "${REFERENCE}"
			(at 0 0 180)
			(layer "F.Fab")
			(effects
				(font
					(size 0.7 0.7)
					(thickness 0.15)
				)
				(justify left bottom)
			)
		)
		(fp_text user "Author: Antmicro"
			(at -5.2 13.36 0)
			(layer "F.Fab")
			(effects
				(font
					(size 0.7 0.7)
					(thickness 0.15)
				)
				(justify right top)
			)
		)
		(fp_text user "License: Apache-2.0"
			(at -5.2 14.56 0)
			(layer "F.Fab")
			(effects
				(font
					(size 0.7 0.7)
					(thickness 0.15)
				)
				(justify right top)
			)
		)
		(pad "1" smd roundrect
			(at -2.675 0 180)
			(size 2.65 7.8)
			(layers "F.Cu" "F.Mask" "F.Paste")
			(roundrect_rratio 0.05)
			(net 143 "/USB-PD/12V_SW")
			(pintype "passive")
		)
		(pad "2" smd roundrect
			(at 2.675 0 180)
			(size 2.65 7.8)
			(layers "F.Cu" "F.Mask" "F.Paste")
			(roundrect_rratio 0.05)
			(net 187 "/USB-PD/12V_CONV")
			(pintype "passive")
		)
	)
	(footprint "antmicro-footprints:C_0805_2012Metric"
		(layer "F.Cu")
		(at 132 98.5)
		(descr "Capacitor SMD 0805")
		(tags "capacitor SMD 0805")
		(property "Reference" "C28"
			(at -4.2 0.5 180)
			(layer "F.SilkS")
			(effects
				(font
					(size 0.7 0.7)
					(thickness 0.15)
				)
				(justify left bottom)
			)
		)
		(property "Value" "C_22u_25V_0805"
			(at -2.055717 1.963153 0)
			(layer "F.Fab")
			(effects
				(font
					(size 0.7 0.7)
					(thickness 0.15)
				)
				(justify left bottom)
			)
		)
		(property "Datasheet" "https://product.samsungsem.com/mlcc/CL21A226MAYNNN.do"
			(at 0 0 0)
			(layer "F.Fab")
			(hide yes)
			(effects
				(font
					(size 1.27 1.27)
					(thickness 0.15)
				)
			)
		)
		(property "Description" "SMT Multilayer Ceramic Capacitor, 22uF, +/-20%, 25V, X5R, 0805 [2012 Metric]"
			(at 0 0 0)
			(layer "F.Fab")
			(hide yes)
			(effects
				(font
					(size 1.27 1.27)
					(thickness 0.15)
				)
			)
		)
		(property "MPN" "CL21A226MAYNNNE"
			(at 0 0 0)
			(unlocked yes)
			(layer "F.Fab")
			(hide yes)
			(effects
				(font
					(size 1 1)
					(thickness 0.15)
				)
			)
		)
		(property "Manufacturer" "Samsung Electro-Mechanics"
			(at 0 0 0)
			(unlocked yes)
			(layer "F.Fab")
			(hide yes)
			(effects
				(font
					(size 1 1)
					(thickness 0.15)
				)
			)
		)
		(property "License" "Apache-2.0"
			(at 0 0 0)
			(unlocked yes)
			(layer "F.Fab")
			(hide yes)
			(effects
				(font
					(size 1 1)
					(thickness 0.15)
				)
			)
		)
		(property "Author" "Antmicro"
			(at 0 0 0)
			(unlocked yes)
			(layer "F.Fab")
			(hide yes)
			(effects
				(font
					(size 1 1)
					(thickness 0.15)
				)
			)
		)
		(property "Val" "22u"
			(at 0 0 0)
			(unlocked yes)
			(layer "F.Fab")
			(hide yes)
			(effects
				(font
					(size 1 1)
					(thickness 0.15)
				)
			)
		)
		(property "Voltage" "25V"
			(at 0 0 0)
			(unlocked yes)
			(layer "F.Fab")
			(hide yes)
			(effects
				(font
					(size 1 1)
					(thickness 0.15)
				)
			)
		)
		(property "Dielectric" "X5R"
			(at 0 0 0)
			(unlocked yes)
			(layer "F.Fab")
			(hide yes)
			(effects
				(font
					(size 1 1)
					(thickness 0.15)
				)
			)
		)
		(property "Public" "False"
			(at 0 0 0)
			(unlocked yes)
			(layer "F.Fab")
			(hide yes)
			(effects
				(font
					(size 1 1)
					(thickness 0.15)
				)
			)
		)
		(sheetname "/USB-PD/")
		(sheetfile "usb-pd.kicad_sch")
		(attr smd)
		(fp_line
			(start -0.3 -0.7)
			(end 0.3 -0.7)
			(stroke
				(width 0.15)
				(type solid)
			)
			(layer "F.SilkS")
		)
		(fp_line
			(start -0.3 0.7)
			(end 0.3 0.7)
			(stroke
				(width 0.15)
				(type solid)
			)
			(layer "F.SilkS")
		)
		(fp_rect
			(start 1.95 -0.9)
			(end -1.95 0.9)
			(stroke
				(width 0.05)
				(type default)
			)
			(fill no)
			(layer "F.CrtYd")
		)
		(fp_rect
			(start -0.95 -0.675)
			(end 0.95 0.675)
			(stroke
				(width 0.15)
				(type solid)
			)
			(fill no)
			(layer "F.Fab")
		)
		(fp_text user "Author: Antmicro"
			(at -1.9 5.947 0)
			(layer "F.Fab")
			(effects
				(font
					(size 0.7 0.7)
					(thickness 0.15)
				)
				(justify left bottom)
			)
		)
		(fp_text user "License: Apache-2.0"
			(at -1.9 4.947 0)
			(layer "F.Fab")
			(effects
				(font
					(size 0.7 0.7)
					(thickness 0.15)
				)
				(justify left bottom)
			)
		)
		(fp_text user "${REFERENCE}"
			(at 0 0 0)
			(layer "F.Fab")
			(effects
				(font
					(size 0.7 0.7)
					(thickness 0.15)
				)
				(justify left bottom)
			)
		)
		(pad "1" smd roundrect
			(at -1.1 0)
			(size 1.2 1.3)
			(layers "F.Cu" "F.Mask" "F.Paste")
			(roundrect_rratio 0.25)
			(net 66 "GND")
			(pintype "passive")
		)
		(pad "2" smd roundrect
			(at 1.1 0)
			(size 1.2 1.3)
			(layers "F.Cu" "F.Mask" "F.Paste")
			(roundrect_rratio 0.25)
			(net 187 "/USB-PD/12V_CONV")
			(pintype "passive")
		)
	)
	(footprint "antmicro-footprints:R_0402_1005Metric"
		(layer "F.Cu")
		(at 135.7005 68.050001 90)
		(descr "Resistor SMD 0402")
		(tags "resistor SMD 0402")
		(property "Reference" "R36"
			(at 1.3 -5.45 90)
			(layer "F.SilkS")
			(effects
				(font
					(size 0.7 0.7)
					(thickness 0.15)
				)
				(justify right top)
			)
		)
		(property "Value" "R_10k_0402"
			(at -1.011843 1.772046 90)
			(layer "F.Fab")
			(effects
				(font
					(size 0.7 0.7)
					(thickness 0.15)
				)
				(justify left bottom)
			)
		)
		(property "Datasheet" "https://www.bourns.com/docs/product-datasheets/cr.pdf"
			(at 0 0 90)
			(layer "F.Fab")
			(hide yes)
			(effects
				(font
					(size 1.27 1.27)
					(thickness 0.15)
				)
			)
		)
		(property "Description" "SMD Chip Resistor, 10 kohm, ± 1%, 62.5 mW, 0402 [1005 Metric], Thick Film, General Purpose"
			(at 0 0 90)
			(layer "F.Fab")
			(hide yes)
			(effects
				(font
					(size 1.27 1.27)
					(thickness 0.15)
				)
			)
		)
		(property "MPN" "CR0402-FX-1002GLF"
			(at 0 0 90)
			(unlocked yes)
			(layer "F.Fab")
			(hide yes)
			(effects
				(font
					(size 1 1)
					(thickness 0.15)
				)
			)
		)
		(property "Manufacturer" "Bourns"
			(at 0 0 90)
			(unlocked yes)
			(layer "F.Fab")
			(hide yes)
			(effects
				(font
					(size 1 1)
					(thickness 0.15)
				)
			)
		)
		(property "License" "Apache-2.0"
			(at 0 0 90)
			(unlocked yes)
			(layer "F.Fab")
			(hide yes)
			(effects
				(font
					(size 1 1)
					(thickness 0.15)
				)
			)
		)
		(property "Author" "Antmicro"
			(at 0 0 90)
			(unlocked yes)
			(layer "F.Fab")
			(hide yes)
			(effects
				(font
					(size 1 1)
					(thickness 0.15)
				)
			)
		)
		(property "Val" "10k"
			(at 0 0 90)
			(unlocked yes)
			(layer "F.Fab")
			(hide yes)
			(effects
				(font
					(size 1 1)
					(thickness 0.15)
				)
			)
		)
		(property "Tolerance" "1%"
			(at 0 0 90)
			(unlocked yes)
			(layer "F.Fab")
			(hide yes)
			(effects
				(font
					(size 1 1)
					(thickness 0.15)
				)
			)
		)
		(sheetname "/USB-PD/")
		(sheetfile "usb-pd.kicad_sch")
		(attr smd)
		(fp_rect
			(start -0.925 -0.47)
			(end 0.925 0.47)
			(stroke
				(width 0.05)
				(type default)
			)
			(fill no)
			(layer "F.CrtYd")
		)
		(fp_rect
			(start -0.5 -0.25)
			(end 0.5 0.25)
			(stroke
				(width 0.15)
				(type solid)
			)
			(fill no)
			(layer "F.Fab")
		)
		(fp_text user "${REFERENCE}"
			(at 0 0 270)
			(layer "F.Fab")
			(effects
				(font
					(size 0.7 0.7)
					(thickness 0.15)
				)
				(justify right top)
			)
		)
		(fp_text user "Author: Antmicro"
			(at -0.95 4.169 90)
			(layer "F.Fab")
			(effects
				(font
					(size 0.7 0.7)
					(thickness 0.15)
				)
				(justify left bottom)
			)
		)
		(fp_text user "License: Apache-2.0"
			(at -0.949999 5.169 90)
			(layer "F.Fab")
			(effects
				(font
					(size 0.7 0.7)
					(thickness 0.15)
				)
				(justify left bottom)
			)
		)
		(pad "1" smd roundrect
			(at -0.48 0 90)
			(size 0.59 0.64)
			(layers "F.Cu" "F.Mask" "F.Paste")
			(roundrect_rratio 0.25)
			(net 176 "Net-(Q8-D)")
			(pintype "passive")
		)
		(pad "2" smd roundrect
			(at 0.48 0 90)
			(size 0.59 0.64)
			(layers "F.Cu" "F.Mask" "F.Paste")
			(roundrect_rratio 0.25)
			(net 167 "Net-(D4-C_{R})")
			(pintype "passive")
		)
	)
	(footprint "antmicro-footprints:SOD-123FL"
		(layer "F.Cu")
		(at 143 110.4)
		(property "Reference" "D7"
			(at -4 0.4 180)
			(layer "F.SilkS")
			(effects
				(font
					(size 0.7 0.7)
					(thickness 0.15)
				)
				(justify left bottom)
			)
		)
		(property "Value" "SZSMF4L14AT3G"
			(at 0 1.967 0)
			(layer "F.Fab")
			(effects
				(font
					(size 0.7 0.7)
					(thickness 0.15)
				)
				(justify left bottom)
			)
		)
		(property "Datasheet" "https://www.mouser.com/datasheet/2/240/media-3320461.pdf"
			(at 0 0 0)
			(layer "F.Fab")
			(hide yes)
			(effects
				(font
					(size 1.27 1.27)
					(thickness 0.15)
				)
			)
		)
		(property "Description" "ESD, TVS Diode, 14V, UNI, 400W, SOD-123FL"
			(at 0 0 0)
			(layer "F.Fab")
			(hide yes)
			(effects
				(font
					(size 1.27 1.27)
					(thickness 0.15)
				)
			)
		)
		(property "MPN" "SZSMF4L12AT3G"
			(at 0 0 0)
			(unlocked yes)
			(layer "F.Fab")
			(hide yes)
			(effects
				(font
					(size 1 1)
					(thickness 0.15)
				)
			)
		)
		(property "Author" "Antmicro"
			(at 0 0 0)
			(unlocked yes)
			(layer "F.Fab")
			(hide yes)
			(effects
				(font
					(size 1 1)
					(thickness 0.15)
				)
			)
		)
		(property "License" "Apache-2.0"
			(at 0 0 0)
			(unlocked yes)
			(layer "F.Fab")
			(hide yes)
			(effects
				(font
					(size 1 1)
					(thickness 0.15)
				)
			)
		)
		(property "Manufacturer" "Littelfuse"
			(at 0 0 0)
			(unlocked yes)
			(layer "F.Fab")
			(hide yes)
			(effects
				(font
					(size 1 1)
					(thickness 0.15)
				)
			)
		)
		(sheetname "/Power/")
		(sheetfile "power.kicad_sch")
		(attr smd)
		(fp_line
			(start -2.3 -1.1)
			(end -2.3 1.1)
			(stroke
				(width 0.15)
				(type solid)
			)
			(layer "F.SilkS")
		)
		(fp_line
			(start -2.3 1.1)
			(end 0 1.1)
			(stroke
				(width 0.15)
				(type solid)
			)
			(layer "F.SilkS")
		)
		(fp_line
			(start 0 -1.1)
			(end -2.3 -1.1)
			(stroke
				(width 0.15)
				(type solid)
			)
			(layer "F.SilkS")
		)
		(fp_rect
			(start -2.35 -1.125)
			(end 2.35 1.125)
			(stroke
				(width 0.05)
				(type solid)
			)
			(fill no)
			(layer "F.CrtYd")
		)
		(fp_rect
			(start -1.825 -0.875)
			(end 1.824 0.873)
			(stroke
				(width 0.15)
				(type solid)
			)
			(fill no)
			(layer "F.Fab")
		)
		(fp_rect
			(start -0.775 -0.875)
			(end -0.525 0.875)
			(stroke
				(width 0.15)
				(type solid)
			)
			(fill yes)
			(layer "F.Fab")
		)
		(fp_text user "License: Apache-2.0"
			(at -2.406 6.368 0)
			(layer "F.Fab")
			(effects
				(font
					(size 0.7 0.7)
					(thickness 0.15)
				)
				(justify left bottom)
			)
		)
		(fp_text user "Author: Antmicro"
			(at -2.406 5.168 0)
			(layer "F.Fab")
			(effects
				(font
					(size 0.7 0.7)
					(thickness 0.15)
				)
				(justify left bottom)
			)
		)
		(fp_text user "${REFERENCE}"
			(at 0 0 0)
			(layer "F.Fab")
			(effects
				(font
					(size 0.7 0.7)
					(thickness 0.15)
				)
				(justify left bottom)
			)
		)
		(pad "1" smd roundrect
			(at -1.43 0)
			(size 1.34 1.8)
			(layers "F.Cu" "F.Mask" "F.Paste")
			(roundrect_rratio 0.14)
			(net 118 "/Power/Ideal-diode-1/VIN")
			(pinfunction "C")
			(pintype "passive")
		)
		(pad "2" smd roundrect
			(at 1.429 0)
			(size 1.34 1.8)
			(layers "F.Cu" "F.Mask" "F.Paste")
			(roundrect_rratio 0.14)
			(net 66 "GND")
			(pinfunction "A")
			(pintype "passive")
		)
	)
	(footprint "antmicro-footprints:LED_0603_1608Metric_G"
		(layer "F.Cu")
		(at 151.5 157.17)
		(descr "LED SMD 0603 Green")
		(tags "LED SMD 0603 Green")
		(property "Reference" "D2"
			(at -0.75 1.58 0)
			(layer "F.SilkS")
			(effects
				(font
					(size 0.7 0.7)
					(thickness 0.15)
				)
				(justify left bottom)
			)
		)
		(property "Value" "LED_G_0603_LTST-C190GKT"
			(at -0.001 1.599 0)
			(layer "F.Fab")
			(effects
				(font
					(size 0.7 0.7)
					(thickness 0.15)
				)
				(justify left bottom)
			)
		)
		(property "Datasheet" "https://media.digikey.com/pdf/Data%20Sheets/Lite-On%20PDFs/LTST-C190GKT.pdf"
			(at 0 0 0)
			(layer "F.Fab")
			(hide yes)
			(effects
				(font
					(size 1.27 1.27)
					(thickness 0.15)
				)
			)
		)
		(property "Description" "LED, Green, SMD, 0603, 20 mA, 2.1 V, 569 nm"
			(at 0 0 0)
			(layer "F.Fab")
			(hide yes)
			(effects
				(font
					(size 1.27 1.27)
					(thickness 0.15)
				)
			)
		)
		(property "MPN" "LTST-C190GKT"
			(at 0 0 0)
			(unlocked yes)
			(layer "F.Fab")
			(hide yes)
			(effects
				(font
					(size 1 1)
					(thickness 0.15)
				)
			)
		)
		(property "Manufacturer" "Lite-On"
			(at 0 0 0)
			(unlocked yes)
			(layer "F.Fab")
			(hide yes)
			(effects
				(font
					(size 1 1)
					(thickness 0.15)
				)
			)
		)
		(property "Color" "Green"
			(at 0 0 0)
			(unlocked yes)
			(layer "F.Fab")
			(hide yes)
			(effects
				(font
					(size 1 1)
					(thickness 0.15)
				)
			)
		)
		(property "Author" "Antmicro"
			(at 0 0 0)
			(unlocked yes)
			(layer "F.Fab")
			(hide yes)
			(effects
				(font
					(size 1 1)
					(thickness 0.15)
				)
			)
		)
		(property "License" "Apache-2.0"
			(at 0 0 0)
			(unlocked yes)
			(layer "F.Fab")
			(hide yes)
			(effects
				(font
					(size 1 1)
					(thickness 0.15)
				)
			)
		)
		(sheetname "/Power/")
		(sheetfile "power.kicad_sch")
		(attr smd)
		(fp_line
			(start -1.18 -0.319)
			(end -1.18 0.321)
			(stroke
				(width 0.15)
				(type solid)
			)
			(layer "F.SilkS")
		)
		(fp_line
			(start -0.094672 0.001008)
			(end -0.24 0.001008)
			(stroke
				(width 0.1)
				(type solid)
			)
			(layer "F.SilkS")
		)
		(fp_line
			(start -0.094672 0.001008)
			(end 0.105328 -0.198992)
			(stroke
				(width 0.1)
				(type solid)
			)
			(layer "F.SilkS")
		)
		(fp_line
			(start -0.094672 0.201008)
			(end -0.094672 -0.198992)
			(stroke
				(width 0.1)
				(type solid)
			)
			(layer "F.SilkS")
		)
		(fp_line
			(start 0.105328 0.001008)
			(end 0.24 0.001)
			(stroke
				(width 0.1)
				(type solid)
			)
			(layer "F.SilkS")
		)
		(fp_line
			(start 0.105328 0.201008)
			(end -0.094672 0.001008)
			(stroke
				(width 0.1)
				(type solid)
			)
			(layer "F.SilkS")
		)
		(fp_line
			(start 0.105328 0.201008)
			(end 0.105328 -0.198992)
			(stroke
				(width 0.1)
				(type solid)
			)
			(layer "F.SilkS")
		)
		(fp_line
			(start 0.22 -0.35)
			(end -0.22 -0.35)
			(stroke
				(width 0.15)
				(type solid)
			)
			(layer "F.SilkS")
		)
		(fp_line
			(start 0.22 0.35)
			(end -0.22 0.35)
			(stroke
				(width 0.15)
				(type solid)
			)
			(layer "F.SilkS")
		)
		(fp_rect
			(start 1.25 0.65)
			(end -1.25 -0.65)
			(stroke
				(width 0.05)
				(type solid)
			)
			(fill no)
			(layer "F.CrtYd")
		)
		(fp_line
			(start -0.199 -0.202)
			(end -0.199 0.1)
			(stroke
				(width 0.15)
				(type solid)
			)
			(layer "F.Fab")
		)
		(fp_line
			(start -0.199 0)
			(end -0.597 0)
			(stroke
				(width 0.15)
				(type solid)
			)
			(layer "F.Fab")
		)
		(fp_line
			(start -0.199 0.2)
			(end -0.199 0.1)
			(stroke
				(width 0.15)
				(type solid)
			)
			(layer "F.Fab")
		)
		(fp_line
			(start -0.101 0)
			(end 0.201 0.2)
			(stroke
				(width 0.15)
				(type solid)
			)
			(layer "F.Fab")
		)
		(fp_line
			(start 0.201 -0.202)
			(end -0.101 0)
			(stroke
				(width 0.15)
				(type solid)
			)
			(layer "F.Fab")
		)
		(fp_line
			(start 0.201 0)
			(end 0.201 -0.202)
			(stroke
				(width 0.15)
				(type solid)
			)
			(layer "F.Fab")
		)
		(fp_line
			(start 0.201 0.2)
			(end 0.201 0)
			(stroke
				(width 0.15)
				(type solid)
			)
			(layer "F.Fab")
		)
		(fp_line
			(start 0.599 0)
			(end 0.201 0)
			(stroke
				(width 0.15)
				(type solid)
			)
			(layer "F.Fab")
		)
		(fp_rect
			(start 0.848 0.4)
			(end -0.85 -0.402)
			(stroke
				(width 0.15)
				(type solid)
			)
			(fill no)
			(layer "F.Fab")
		)
		(fp_text user "${REFERENCE}"
			(at 0 0 0)
			(layer "F.Fab")
			(effects
				(font
					(size 0.7 0.7)
					(thickness 0.15)
				)
				(justify left bottom)
			)
		)
		(fp_text user "License: Apache-2.0"
			(at -1.4224 3.599 0)
			(layer "F.Fab")
			(effects
				(font
					(size 0.7 0.7)
					(thickness 0.15)
				)
				(justify left bottom)
			)
		)
		(fp_text user "Author: Antmicro"
			(at -1.4224 4.799 0)
			(layer "F.Fab")
			(effects
				(font
					(size 0.7 0.7)
					(thickness 0.15)
				)
				(justify left bottom)
			)
		)
		(pad "1" smd roundrect
			(at -0.7 0 180)
			(size 0.8 1)
			(layers "F.Cu" "F.Mask" "F.Paste")
			(roundrect_rratio 0.2)
			(net 90 "Net-(D2-C)")
			(pinfunction "C")
			(pintype "passive")
		)
		(pad "2" smd roundrect
			(at 0.7 0 180)
			(size 0.8 1)
			(layers "F.Cu" "F.Mask" "F.Paste")
			(roundrect_rratio 0.2)
			(net 134 "+3V3")
			(pinfunction "A")
			(pintype "passive")
		)
	)
	(footprint "antmicro-footprints:C_0402_1005Metric"
		(layer "F.Cu")
		(at 140.900001 122.152999 180)
		(descr "Capacitor SMD 0402")
		(tags "capacitor SMD 0402")
		(property "Reference" "C35"
			(at -0.999999 -0.647001 180)
			(layer "F.SilkS")
			(effects
				(font
					(size 0.7 0.7)
					(thickness 0.15)
				)
				(justify right top)
			)
		)
		(property "Value" "C_1u_25V_0402"
			(at -1.022927 2.155213 0)
			(layer "F.Fab")
			(effects
				(font
					(size 0.7 0.7)
					(thickness 0.15)
				)
				(justify right top)
			)
		)
		(property "Datasheet" "https://www.murata.com/products/productdetail?partno=GRM155R61E105KE11%23"
			(at 0 0 0)
			(layer "F.Fab")
			(hide yes)
			(effects
				(font
					(size 1.27 1.27)
					(thickness 0.15)
				)
			)
		)
		(property "Description" "SMD Multilayer Ceramic Capacitor, 1 µF, 25 V, 0402 [1005 Metric], ± 10%, X5R, GRM Series"
			(at 0 0 0)
			(layer "F.Fab")
			(hide yes)
			(effects
				(font
					(size 1.27 1.27)
					(thickness 0.15)
				)
			)
		)
		(property "MPN" "GRM155R61E105KE11J"
			(at 0 0 180)
			(unlocked yes)
			(layer "F.Fab")
			(hide yes)
			(effects
				(font
					(size 1 1)
					(thickness 0.15)
				)
			)
		)
		(property "Manufacturer" "Murata"
			(at 0 0 180)
			(unlocked yes)
			(layer "F.Fab")
			(hide yes)
			(effects
				(font
					(size 1 1)
					(thickness 0.15)
				)
			)
		)
		(property "License" "Apache-2.0"
			(at 0 0 180)
			(unlocked yes)
			(layer "F.Fab")
			(hide yes)
			(effects
				(font
					(size 1 1)
					(thickness 0.15)
				)
			)
		)
		(property "Author" "Antmicro"
			(at 0 0 180)
			(unlocked yes)
			(layer "F.Fab")
			(hide yes)
			(effects
				(font
					(size 1 1)
					(thickness 0.15)
				)
			)
		)
		(property "Val" "1u"
			(at 0 0 180)
			(unlocked yes)
			(layer "F.Fab")
			(hide yes)
			(effects
				(font
					(size 1 1)
					(thickness 0.15)
				)
			)
		)
		(property "Voltage" "25V"
			(at 0 0 180)
			(unlocked yes)
			(layer "F.Fab")
			(hide yes)
			(effects
				(font
					(size 1 1)
					(thickness 0.15)
				)
			)
		)
		(property "Dielectric" "X5R"
			(at 0 0 180)
			(unlocked yes)
			(layer "F.Fab")
			(hide yes)
			(effects
				(font
					(size 1 1)
					(thickness 0.15)
				)
			)
		)
		(sheetname "/Power/Ideal-diode-1/")
		(sheetfile "ideal-diode.kicad_sch")
		(attr smd)
		(fp_rect
			(start -0.925 -0.47)
			(end 0.925 0.47)
			(stroke
				(width 0.05)
				(type default)
			)
			(fill no)
			(layer "F.CrtYd")
		)
		(fp_line
			(start 0.504 0.248)
			(end -0.494 0.248)
			(stroke
				(width 0.15)
				(type solid)
			)
			(layer "F.Fab")
		)
		(fp_line
			(start 0.504 -0.25)
			(end 0.504 0.248)
			(stroke
				(width 0.15)
				(type solid)
			)
			(layer "F.Fab")
		)
		(fp_line
			(start -0.494 0.248)
			(end -0.494 -0.25)
			(stroke
				(width 0.15)
				(type solid)
			)
			(layer "F.Fab")
		)
		(fp_line
			(start -0.494 -0.25)
			(end 0.504 -0.25)
			(stroke
				(width 0.15)
				(type solid)
			)
			(layer "F.Fab")
		)
		(fp_text user "License: Apache-2.0"
			(at -0.939 5.799 0)
			(layer "F.Fab")
			(effects
				(font
					(size 0.7 0.7)
					(thickness 0.15)
				)
				(justify right top)
			)
		)
		(fp_text user "Author: Antmicro"
			(at -0.939 3.399 0)
			(layer "F.Fab")
			(effects
				(font
					(size 0.7 0.7)
					(thickness 0.15)
				)
				(justify right top)
			)
		)
		(fp_text user "${REFERENCE}"
			(at 0 0 0)
			(layer "F.Fab")
			(effects
				(font
					(size 0.7 0.7)
					(thickness 0.15)
				)
				(justify right top)
			)
		)
		(pad "1" smd roundrect
			(at -0.48 0 180)
			(size 0.59 0.64)
			(layers "F.Cu" "F.Mask" "F.Paste")
			(roundrect_rratio 0.25)
			(net 66 "GND")
			(pintype "passive")
		)
		(pad "2" smd roundrect
			(at 0.48 0 180)
			(size 0.59 0.64)
			(layers "F.Cu" "F.Mask" "F.Paste")
			(roundrect_rratio 0.25)
			(net 87 "+12V")
			(pintype "passive")
		)
	)
	(footprint "antmicro-footprints:R_0402_1005Metric"
		(layer "F.Cu")
		(at 119.55 45.75 -90)
		(descr "Resistor SMD 0402")
		(tags "resistor SMD 0402")
		(property "Reference" "R46"
			(at -3.15 0.35 270)
			(layer "F.SilkS")
			(effects
				(font
					(size 0.7 0.7)
					(thickness 0.15)
				)
				(justify right top)
			)
		)
		(property "Value" "R_0R_0402"
			(at -1.011843 1.772046 90)
			(layer "F.Fab")
			(effects
				(font
					(size 0.7 0.7)
					(thickness 0.15)
				)
				(justify right top)
			)
		)
		(property "Datasheet" "https://industrial.panasonic.com/cdbs/www-data/pdf/RDA0000/AOA0000C301.pdf"
			(at 0 0 90)
			(layer "F.Fab")
			(hide yes)
			(effects
				(font
					(size 1.27 1.27)
					(thickness 0.15)
				)
			)
		)
		(property "Description" "SMD Chip Resistor, Jumper, 0 ohm, 100 mW, 0402 [1005 Metric], Thick Film, General Purpose"
			(at 0 0 90)
			(layer "F.Fab")
			(hide yes)
			(effects
				(font
					(size 1.27 1.27)
					(thickness 0.15)
				)
			)
		)
		(property "MPN" "ERJ2GE0R00X"
			(at 0 0 270)
			(unlocked yes)
			(layer "F.Fab")
			(hide yes)
			(effects
				(font
					(size 1 1)
					(thickness 0.15)
				)
			)
		)
		(property "Manufacturer" "Panasonic"
			(at 0 0 270)
			(unlocked yes)
			(layer "F.Fab")
			(hide yes)
			(effects
				(font
					(size 1 1)
					(thickness 0.15)
				)
			)
		)
		(property "License" "Apache-2.0"
			(at 0 0 270)
			(unlocked yes)
			(layer "F.Fab")
			(hide yes)
			(effects
				(font
					(size 1 1)
					(thickness 0.15)
				)
			)
		)
		(property "Author" "Antmicro"
			(at 0 0 270)
			(unlocked yes)
			(layer "F.Fab")
			(hide yes)
			(effects
				(font
					(size 1 1)
					(thickness 0.15)
				)
			)
		)
		(property "Val" "0R"
			(at 0 0 270)
			(unlocked yes)
			(layer "F.Fab")
			(hide yes)
			(effects
				(font
					(size 1 1)
					(thickness 0.15)
				)
			)
		)
		(property "Tolerance" ""
			(at 0 0 270)
			(unlocked yes)
			(layer "F.Fab")
			(hide yes)
			(effects
				(font
					(size 1 1)
					(thickness 0.15)
				)
			)
		)
		(property "Current" "1A"
			(at 0 0 270)
			(unlocked yes)
			(layer "F.Fab")
			(hide yes)
			(effects
				(font
					(size 1 1)
					(thickness 0.15)
				)
			)
		)
		(sheetname "/OCuLink/")
		(sheetfile "oculink.kicad_sch")
		(attr smd)
		(fp_rect
			(start -0.925 -0.47)
			(end 0.925 0.47)
			(stroke
				(width 0.05)
				(type default)
			)
			(fill no)
			(layer "F.CrtYd")
		)
		(fp_rect
			(start -0.5 -0.25)
			(end 0.5 0.25)
			(stroke
				(width 0.15)
				(type solid)
			)
			(fill no)
			(layer "F.Fab")
		)
		(fp_text user "${REFERENCE}"
			(at 0 0 90)
			(layer "F.Fab")
			(effects
				(font
					(size 0.7 0.7)
					(thickness 0.15)
				)
				(justify right top)
			)
		)
		(fp_text user "License: Apache-2.0"
			(at -0.949999 5.169 90)
			(layer "F.Fab")
			(effects
				(font
					(size 0.7 0.7)
					(thickness 0.15)
				)
				(justify right top)
			)
		)
		(fp_text user "Author: Antmicro"
			(at -0.95 4.169 90)
			(layer "F.Fab")
			(effects
				(font
					(size 0.7 0.7)
					(thickness 0.15)
				)
				(justify right top)
			)
		)
		(pad "1" smd roundrect
			(at -0.48 0 270)
			(size 0.59 0.64)
			(layers "F.Cu" "F.Mask" "F.Paste")
			(roundrect_rratio 0.25)
			(net 170 "/OCuLink/PCIe_{REF0}_R.CK+")
			(pintype "passive")
		)
		(pad "2" smd roundrect
			(at 0.48 0 270)
			(size 0.59 0.64)
			(layers "F.Cu" "F.Mask" "F.Paste")
			(roundrect_rratio 0.25)
			(net 96 "/OCuLink/PCIe_{REF0}.CK+")
			(pintype "passive")
		)
	)
	(footprint "antmicro-footprints:USON-10_2.5x1mm_P0.5mm"
		(layer "F.Cu")
		(at 138.579 47.014 -90)
		(descr "USON-10 2.5x1mm_ Pitch 0.5mm")
		(tags "USON-10 2.5x1mm Pitch 0.5mm")
		(property "Reference" "D12"
			(at 1.048001 -0.262467 180)
			(layer "F.SilkS")
			(effects
				(font
					(size 0.7 0.7)
					(thickness 0.15)
				)
				(justify right top)
			)
		)
		(property "Value" "ESD204DQAR"
			(at 0.018 2.499 90)
			(layer "F.Fab")
			(effects
				(font
					(size 0.7 0.7)
					(thickness 0.15)
				)
				(justify right top)
			)
		)
		(property "Datasheet" "https://www.ti.com/lit/ds/symlink/esd204.pdf?ts=1706004844383&ref_url=https%253A%252F%252Fwww.ti.com%252Finterface%252Fdiodes%252Fesd-protection-diodes%252Fproducts.html"
			(at 0 0 90)
			(layer "F.Fab")
			(hide yes)
			(effects
				(font
					(size 1.27 1.27)
					(thickness 0.15)
				)
			)
		)
		(property "Description" "TVS diode array, 30 kV, USON-10, 3.6 V, 0.55 pF"
			(at 0 0 90)
			(layer "F.Fab")
			(hide yes)
			(effects
				(font
					(size 1.27 1.27)
					(thickness 0.15)
				)
			)
		)
		(property "MPN" "ESD204DQAR"
			(at 0 0 270)
			(unlocked yes)
			(layer "F.Fab")
			(hide yes)
			(effects
				(font
					(size 1 1)
					(thickness 0.15)
				)
			)
		)
		(property "Manufacturer" "Texas Instruments"
			(at 0 0 270)
			(unlocked yes)
			(layer "F.Fab")
			(hide yes)
			(effects
				(font
					(size 1 1)
					(thickness 0.15)
				)
			)
		)
		(property "Author" "Antmicro"
			(at 0 0 270)
			(unlocked yes)
			(layer "F.Fab")
			(hide yes)
			(effects
				(font
					(size 1 1)
					(thickness 0.15)
				)
			)
		)
		(property "License" "Apache-2.0"
			(at 0 0 270)
			(unlocked yes)
			(layer "F.Fab")
			(hide yes)
			(effects
				(font
					(size 1 1)
					(thickness 0.15)
				)
			)
		)
		(sheetname "/OCuLink/")
		(sheetfile "oculink.kicad_sch")
		(attr smd)
		(fp_line
			(start 0.498 1.398)
			(end -0.5 1.398)
			(stroke
				(width 0.15)
				(type solid)
			)
			(layer "F.SilkS")
		)
		(fp_line
			(start 0.498 -1.401)
			(end -0.5 -1.401)
			(stroke
				(width 0.15)
				(type solid)
			)
			(layer "F.SilkS")
		)
		(fp_circle
			(center -0.68 -1.27)
			(end -0.63 -1.27)
			(stroke
				(width 0.15)
				(type solid)
			)
			(fill yes)
			(layer "F.SilkS")
		)
		(fp_rect
			(start -0.8 -1.5)
			(end 0.8 1.499)
			(stroke
				(width 0.05)
				(type solid)
			)
			(fill no)
			(layer "F.CrtYd")
		)
		(fp_line
			(start -0.5 1.249)
			(end 0.498 1.249)
			(stroke
				(width 0.15)
				(type solid)
			)
			(layer "F.Fab")
		)
		(fp_line
			(start -0.5 -1)
			(end -0.5 1.249)
			(stroke
				(width 0.15)
				(type solid)
			)
			(layer "F.Fab")
		)
		(fp_line
			(start -0.25 -1.25)
			(end -0.5 -1)
			(stroke
				(width 0.15)
				(type solid)
			)
			(layer "F.Fab")
		)
		(fp_line
			(start 0.498 -1.25)
			(end 0.498 1.249)
			(stroke
				(width 0.15)
				(type solid)
			)
			(layer "F.Fab")
		)
		(fp_line
			(start 0.498 -1.25)
			(end -0.25 -1.25)
			(stroke
				(width 0.15)
				(type solid)
			)
			(layer "F.Fab")
		)
		(fp_text user "License: Apache-2.0"
			(at -0.802 6.9 90)
			(layer "F.Fab")
			(effects
				(font
					(size 0.7 0.7)
					(thickness 0.15)
				)
				(justify right top)
			)
		)
		(fp_text user "Author: Antmicro"
			(at -0.802 5.7 90)
			(layer "F.Fab")
			(effects
				(font
					(size 0.7 0.7)
					(thickness 0.15)
				)
				(justify right top)
			)
		)
		(fp_text user "${REFERENCE}"
			(at 0 -0.000501 90)
			(layer "F.Fab")
			(effects
				(font
					(size 0.7 0.7)
					(thickness 0.15)
				)
				(justify right top)
			)
		)
		(pad "1" smd roundrect
			(at -0.387 -1 180)
			(size 0.25 0.55)
			(layers "F.Cu" "F.Mask" "F.Paste")
			(roundrect_rratio 0.25)
			(net 72 "/OCuLink/PCIe_{x4}.TX0+")
			(pintype "passive")
		)
		(pad "2" smd roundrect
			(at -0.387 -0.5 180)
			(size 0.25 0.55)
			(layers "F.Cu" "F.Mask" "F.Paste")
			(roundrect_rratio 0.25)
			(net 74 "/OCuLink/PCIe_{x4}.TX0-")
			(pintype "passive")
		)
		(pad "3" smd roundrect
			(at -0.387 0 180)
			(size 0.4 0.55)
			(layers "F.Cu" "F.Mask" "F.Paste")
			(roundrect_rratio 0.25)
			(net 66 "GND")
			(pintype "power_in")
		)
		(pad "4" smd roundrect
			(at -0.387 0.498 180)
			(size 0.25 0.55)
			(layers "F.Cu" "F.Mask" "F.Paste")
			(roundrect_rratio 0.25)
			(net 77 "/OCuLink/PCIe_{x4}.TX1+")
			(pintype "passive")
		)
		(pad "5" smd roundrect
			(at -0.387 0.998 180)
			(size 0.25 0.55)
			(layers "F.Cu" "F.Mask" "F.Paste")
			(roundrect_rratio 0.25)
			(net 69 "/OCuLink/PCIe_{x4}.TX1-")
			(pintype "passive")
		)
		(pad "6" smd roundrect
			(at 0.385 0.998 180)
			(size 0.25 0.55)
			(layers "F.Cu" "F.Mask" "F.Paste")
			(roundrect_rratio 0.25)
			(net 69 "/OCuLink/PCIe_{x4}.TX1-")
			(pintype "passive")
		)
		(pad "7" smd roundrect
			(at 0.385 0.498 180)
			(size 0.25 0.55)
			(layers "F.Cu" "F.Mask" "F.Paste")
			(roundrect_rratio 0.25)
			(net 77 "/OCuLink/PCIe_{x4}.TX1+")
			(pintype "passive")
		)
		(pad "8" smd roundrect
			(at 0.385 0 180)
			(size 0.4 0.55)
			(layers "F.Cu" "F.Mask" "F.Paste")
			(roundrect_rratio 0.25)
			(net 66 "GND")
			(pintype "passive")
		)
		(pad "9" smd roundrect
			(at 0.385 -0.5 180)
			(size 0.25 0.55)
			(layers "F.Cu" "F.Mask" "F.Paste")
			(roundrect_rratio 0.25)
			(net 74 "/OCuLink/PCIe_{x4}.TX0-")
			(pintype "passive")
		)
		(pad "10" smd roundrect
			(at 0.385 -1 180)
			(size 0.25 0.55)
			(layers "F.Cu" "F.Mask" "F.Paste")
			(roundrect_rratio 0.25)
			(net 72 "/OCuLink/PCIe_{x4}.TX0+")
			(pintype "passive")
		)
	)
	(footprint "antmicro-footprints:USON-10_2.5x1mm_P0.5mm"
		(layer "F.Cu")
		(at 124.298 43.387 -90)
		(descr "USON-10 2.5x1mm_ Pitch 0.5mm")
		(tags "USON-10 2.5x1mm Pitch 0.5mm")
		(property "Reference" "D11"
			(at 1.113 -0.452 180)
			(layer "F.SilkS")
			(effects
				(font
					(size 0.7 0.7)
					(thickness 0.15)
				)
				(justify right top)
			)
		)
		(property "Value" "ESD204DQAR"
			(at 0.018 2.499 90)
			(layer "F.Fab")
			(effects
				(font
					(size 0.7 0.7)
					(thickness 0.15)
				)
				(justify right top)
			)
		)
		(property "Datasheet" "https://www.ti.com/lit/ds/symlink/esd204.pdf?ts=1706004844383&ref_url=https%253A%252F%252Fwww.ti.com%252Finterface%252Fdiodes%252Fesd-protection-diodes%252Fproducts.html"
			(at 0 0 90)
			(layer "F.Fab")
			(hide yes)
			(effects
				(font
					(size 1.27 1.27)
					(thickness 0.15)
				)
			)
		)
		(property "Description" "TVS diode array, 30 kV, USON-10, 3.6 V, 0.55 pF"
			(at 0 0 90)
			(layer "F.Fab")
			(hide yes)
			(effects
				(font
					(size 1.27 1.27)
					(thickness 0.15)
				)
			)
		)
		(property "MPN" "ESD204DQAR"
			(at 0 0 270)
			(unlocked yes)
			(layer "F.Fab")
			(hide yes)
			(effects
				(font
					(size 1 1)
					(thickness 0.15)
				)
			)
		)
		(property "Manufacturer" "Texas Instruments"
			(at 0 0 270)
			(unlocked yes)
			(layer "F.Fab")
			(hide yes)
			(effects
				(font
					(size 1 1)
					(thickness 0.15)
				)
			)
		)
		(property "Author" "Antmicro"
			(at 0 0 270)
			(unlocked yes)
			(layer "F.Fab")
			(hide yes)
			(effects
				(font
					(size 1 1)
					(thickness 0.15)
				)
			)
		)
		(property "License" "Apache-2.0"
			(at 0 0 270)
			(unlocked yes)
			(layer "F.Fab")
			(hide yes)
			(effects
				(font
					(size 1 1)
					(thickness 0.15)
				)
			)
		)
		(sheetname "/OCuLink/")
		(sheetfile "oculink.kicad_sch")
		(attr smd)
		(fp_line
			(start 0.498 1.398)
			(end -0.5 1.398)
			(stroke
				(width 0.15)
				(type solid)
			)
			(layer "F.SilkS")
		)
		(fp_line
			(start 0.498 -1.401)
			(end -0.5 -1.401)
			(stroke
				(width 0.15)
				(type solid)
			)
			(layer "F.SilkS")
		)
		(fp_circle
			(center -0.68 -1.27)
			(end -0.63 -1.27)
			(stroke
				(width 0.15)
				(type solid)
			)
			(fill yes)
			(layer "F.SilkS")
		)
		(fp_rect
			(start -0.8 -1.5)
			(end 0.8 1.499)
			(stroke
				(width 0.05)
				(type solid)
			)
			(fill no)
			(layer "F.CrtYd")
		)
		(fp_line
			(start -0.5 1.249)
			(end 0.498 1.249)
			(stroke
				(width 0.15)
				(type solid)
			)
			(layer "F.Fab")
		)
		(fp_line
			(start -0.5 -1)
			(end -0.5 1.249)
			(stroke
				(width 0.15)
				(type solid)
			)
			(layer "F.Fab")
		)
		(fp_line
			(start -0.25 -1.25)
			(end -0.5 -1)
			(stroke
				(width 0.15)
				(type solid)
			)
			(layer "F.Fab")
		)
		(fp_line
			(start 0.498 -1.25)
			(end 0.498 1.249)
			(stroke
				(width 0.15)
				(type solid)
			)
			(layer "F.Fab")
		)
		(fp_line
			(start 0.498 -1.25)
			(end -0.25 -1.25)
			(stroke
				(width 0.15)
				(type solid)
			)
			(layer "F.Fab")
		)
		(fp_text user "${REFERENCE}"
			(at 0 -0.000501 90)
			(layer "F.Fab")
			(effects
				(font
					(size 0.7 0.7)
					(thickness 0.15)
				)
				(justify right top)
			)
		)
		(fp_text user "License: Apache-2.0"
			(at -0.802 6.9 90)
			(layer "F.Fab")
			(effects
				(font
					(size 0.7 0.7)
					(thickness 0.15)
				)
				(justify right top)
			)
		)
		(fp_text user "Author: Antmicro"
			(at -0.802 5.7 90)
			(layer "F.Fab")
			(effects
				(font
					(size 0.7 0.7)
					(thickness 0.15)
				)
				(justify right top)
			)
		)
		(pad "1" smd roundrect
			(at -0.387 -1 180)
			(size 0.25 0.55)
			(layers "F.Cu" "F.Mask" "F.Paste")
			(roundrect_rratio 0.25)
			(net 81 "/OCuLink/PCIe_{x4}.RX2+")
			(pintype "passive")
		)
		(pad "2" smd roundrect
			(at -0.387 -0.5 180)
			(size 0.25 0.55)
			(layers "F.Cu" "F.Mask" "F.Paste")
			(roundrect_rratio 0.25)
			(net 79 "/OCuLink/PCIe_{x4}.RX2-")
			(pintype "passive")
		)
		(pad "3" smd roundrect
			(at -0.387 0 180)
			(size 0.4 0.55)
			(layers "F.Cu" "F.Mask" "F.Paste")
			(roundrect_rratio 0.25)
			(net 66 "GND")
			(pintype "power_in")
		)
		(pad "4" smd roundrect
			(at -0.387 0.498 180)
			(size 0.25 0.55)
			(layers "F.Cu" "F.Mask" "F.Paste")
			(roundrect_rratio 0.25)
			(net 68 "/OCuLink/PCIe_{x4}.RX3+")
			(pintype "passive")
		)
		(pad "5" smd roundrect
			(at -0.387 0.998 180)
			(size 0.25 0.55)
			(layers "F.Cu" "F.Mask" "F.Paste")
			(roundrect_rratio 0.25)
			(net 67 "/OCuLink/PCIe_{x4}.RX3-")
			(pintype "passive")
		)
		(pad "6" smd roundrect
			(at 0.385 0.998 180)
			(size 0.25 0.55)
			(layers "F.Cu" "F.Mask" "F.Paste")
			(roundrect_rratio 0.25)
			(net 67 "/OCuLink/PCIe_{x4}.RX3-")
			(pintype "passive")
		)
		(pad "7" smd roundrect
			(at 0.385 0.498 180)
			(size 0.25 0.55)
			(layers "F.Cu" "F.Mask" "F.Paste")
			(roundrect_rratio 0.25)
			(net 68 "/OCuLink/PCIe_{x4}.RX3+")
			(pintype "passive")
		)
		(pad "8" smd roundrect
			(at 0.385 0 180)
			(size 0.4 0.55)
			(layers "F.Cu" "F.Mask" "F.Paste")
			(roundrect_rratio 0.25)
			(net 66 "GND")
			(pintype "passive")
		)
		(pad "9" smd roundrect
			(at 0.385 -0.5 180)
			(size 0.25 0.55)
			(layers "F.Cu" "F.Mask" "F.Paste")
			(roundrect_rratio 0.25)
			(net 79 "/OCuLink/PCIe_{x4}.RX2-")
			(pintype "passive")
		)
		(pad "10" smd roundrect
			(at 0.385 -1 180)
			(size 0.25 0.55)
			(layers "F.Cu" "F.Mask" "F.Paste")
			(roundrect_rratio 0.25)
			(net 81 "/OCuLink/PCIe_{x4}.RX2+")
			(pintype "passive")
		)
	)
	(footprint "antmicro-footprints:R_0402_1005Metric"
		(layer "F.Cu")
		(at 118.55 48.2 90)
		(descr "Resistor SMD 0402")
		(tags "resistor SMD 0402")
		(property "Reference" "R44"
			(at -3.2 0.45 90)
			(layer "F.SilkS")
			(effects
				(font
					(size 0.7 0.7)
					(thickness 0.15)
				)
				(justify left bottom)
			)
		)
		(property "Value" "R_0R_0402"
			(at -1.011843 1.772046 90)
			(layer "F.Fab")
			(effects
				(font
					(size 0.7 0.7)
					(thickness 0.15)
				)
				(justify left bottom)
			)
		)
		(property "Datasheet" "https://industrial.panasonic.com/cdbs/www-data/pdf/RDA0000/AOA0000C301.pdf"
			(at 0 0 90)
			(layer "F.Fab")
			(hide yes)
			(effects
				(font
					(size 1.27 1.27)
					(thickness 0.15)
				)
			)
		)
		(property "Description" "SMD Chip Resistor, Jumper, 0 ohm, 100 mW, 0402 [1005 Metric], Thick Film, General Purpose"
			(at 0 0 90)
			(layer "F.Fab")
			(hide yes)
			(effects
				(font
					(size 1.27 1.27)
					(thickness 0.15)
				)
			)
		)
		(property "MPN" "ERJ2GE0R00X"
			(at 0 0 90)
			(unlocked yes)
			(layer "F.Fab")
			(hide yes)
			(effects
				(font
					(size 1 1)
					(thickness 0.15)
				)
			)
		)
		(property "Manufacturer" "Panasonic"
			(at 0 0 90)
			(unlocked yes)
			(layer "F.Fab")
			(hide yes)
			(effects
				(font
					(size 1 1)
					(thickness 0.15)
				)
			)
		)
		(property "License" "Apache-2.0"
			(at 0 0 90)
			(unlocked yes)
			(layer "F.Fab")
			(hide yes)
			(effects
				(font
					(size 1 1)
					(thickness 0.15)
				)
			)
		)
		(property "Author" "Antmicro"
			(at 0 0 90)
			(unlocked yes)
			(layer "F.Fab")
			(hide yes)
			(effects
				(font
					(size 1 1)
					(thickness 0.15)
				)
			)
		)
		(property "Val" "0R"
			(at 0 0 90)
			(unlocked yes)
			(layer "F.Fab")
			(hide yes)
			(effects
				(font
					(size 1 1)
					(thickness 0.15)
				)
			)
		)
		(property "Tolerance" ""
			(at 0 0 90)
			(unlocked yes)
			(layer "F.Fab")
			(hide yes)
			(effects
				(font
					(size 1 1)
					(thickness 0.15)
				)
			)
		)
		(property "Current" "1A"
			(at 0 0 90)
			(unlocked yes)
			(layer "F.Fab")
			(hide yes)
			(effects
				(font
					(size 1 1)
					(thickness 0.15)
				)
			)
		)
		(sheetname "/PCIe-clock-generator/")
		(sheetfile "pcie-clock-generator.kicad_sch")
		(attr smd exclude_from_bom dnp)
		(fp_poly
			(pts
				(xy -0.925 -0.47) (xy 0.925 -0.47) (xy 0.925 0.47) (xy -0.925 0.47)
			)
			(stroke
				(width 0.05)
				(type default)
			)
			(fill no)
			(layer "F.CrtYd")
		)
		(fp_poly
			(pts
				(xy -0.5 -0.25) (xy 0.5 -0.25) (xy 0.5 0.25) (xy -0.5 0.25)
			)
			(stroke
				(width 0.15)
				(type solid)
			)
			(fill no)
			(layer "F.Fab")
		)
		(fp_text user "License: Apache-2.0"
			(at -0.949999 5.169 90)
			(layer "F.Fab")
			(effects
				(font
					(size 0.7 0.7)
					(thickness 0.15)
				)
				(justify left bottom)
			)
		)
		(fp_text user "${REFERENCE}"
			(at -0.95 3.168 90)
			(layer "F.Fab")
			(effects
				(font
					(size 0.7 0.7)
					(thickness 0.15)
				)
				(justify left bottom)
			)
		)
		(fp_text user "Author: Antmicro"
			(at -0.95 4.169 90)
			(layer "F.Fab")
			(effects
				(font
					(size 0.7 0.7)
					(thickness 0.15)
				)
				(justify left bottom)
			)
		)
		(pad "1" smd roundrect
			(at -0.48 0 90)
			(size 0.59 0.64)
			(layers "F.Cu" "F.Mask" "F.Paste")
			(roundrect_rratio 0.25)
			(net 179 "/PCIe-clock-generator/PCIe_{REF1}_R.CK-")
			(pintype "passive")
		)
		(pad "2" smd roundrect
			(at 0.48 0 90)
			(size 0.59 0.64)
			(layers "F.Cu" "F.Mask" "F.Paste")
			(roundrect_rratio 0.25)
			(net 97 "/OCuLink/PCIe_{REF0}.CK-")
			(pintype "passive")
		)
	)
	(footprint "antmicro-footprints:R_0402_1005Metric"
		(layer "F.Cu")
		(at 143.8 63)
		(descr "Resistor SMD 0402")
		(tags "resistor SMD 0402")
		(property "Reference" "R56"
			(at -1.1 -0.6 0)
			(layer "F.SilkS")
			(effects
				(font
					(size 0.7 0.7)
					(thickness 0.15)
				)
				(justify left bottom)
			)
		)
		(property "Value" "R_22R_0402"
			(at -1.011843 1.772047 0)
			(layer "F.Fab")
			(effects
				(font
					(size 0.7 0.7)
					(thickness 0.15)
				)
				(justify left bottom)
			)
		)
		(property "Datasheet" "https://www.bourns.com/docs/product-datasheets/cr.pdf"
			(at 0 0 0)
			(layer "F.Fab")
			(hide yes)
			(effects
				(font
					(size 1.27 1.27)
					(thickness 0.15)
				)
			)
		)
		(property "Description" "SMD Chip Resistor, 22 ohm, ± 1%, 62.5 mW, 0402 [1005 Metric], Thick Film, General Purpose"
			(at 0 0 0)
			(layer "F.Fab")
			(hide yes)
			(effects
				(font
					(size 1.27 1.27)
					(thickness 0.15)
				)
			)
		)
		(property "MPN" "CR0402-FX-22R0GLF"
			(at 0 0 0)
			(unlocked yes)
			(layer "F.Fab")
			(hide yes)
			(effects
				(font
					(size 1 1)
					(thickness 0.15)
				)
			)
		)
		(property "Manufacturer" "Bourns"
			(at 0 0 0)
			(unlocked yes)
			(layer "F.Fab")
			(hide yes)
			(effects
				(font
					(size 1 1)
					(thickness 0.15)
				)
			)
		)
		(property "License" "Apache-2.0"
			(at 0 0 0)
			(unlocked yes)
			(layer "F.Fab")
			(hide yes)
			(effects
				(font
					(size 1 1)
					(thickness 0.15)
				)
			)
		)
		(property "Author" "Antmicro"
			(at 0 0 0)
			(unlocked yes)
			(layer "F.Fab")
			(hide yes)
			(effects
				(font
					(size 1 1)
					(thickness 0.15)
				)
			)
		)
		(property "Val" "22R"
			(at 0 0 0)
			(unlocked yes)
			(layer "F.Fab")
			(hide yes)
			(effects
				(font
					(size 1 1)
					(thickness 0.15)
				)
			)
		)
		(property "Tolerance" "1%"
			(at 0 0 0)
			(unlocked yes)
			(layer "F.Fab")
			(hide yes)
			(effects
				(font
					(size 1 1)
					(thickness 0.15)
				)
			)
		)
		(sheetname "/PCIe-clock-generator/")
		(sheetfile "pcie-clock-generator.kicad_sch")
		(attr smd exclude_from_bom dnp)
		(fp_rect
			(start -0.925 -0.47)
			(end 0.925 0.47)
			(stroke
				(width 0.05)
				(type default)
			)
			(fill no)
			(layer "F.CrtYd")
		)
		(fp_rect
			(start -0.5 -0.25)
			(end 0.5 0.25)
			(stroke
				(width 0.15)
				(type solid)
			)
			(fill no)
			(layer "F.Fab")
		)
		(fp_text user "License: Apache-2.0"
			(at -0.95 5.169 0)
			(layer "F.Fab")
			(effects
				(font
					(size 0.7 0.7)
					(thickness 0.15)
				)
				(justify left bottom)
			)
		)
		(fp_text user "Author: Antmicro"
			(at -0.95 4.169 0)
			(layer "F.Fab")
			(effects
				(font
					(size 0.7 0.7)
					(thickness 0.15)
				)
				(justify left bottom)
			)
		)
		(fp_text user "${REFERENCE}"
			(at -0.95 3.168 0)
			(layer "F.Fab")
			(effects
				(font
					(size 0.7 0.7)
					(thickness 0.15)
				)
				(justify left bottom)
			)
		)
		(pad "1" smd roundrect
			(at -0.48 0)
			(size 0.59 0.64)
			(layers "F.Cu" "F.Mask" "F.Paste")
			(roundrect_rratio 0.25)
			(net 198 "/PCIe-clock-generator/PCIe_{REF1}_R2.CK-")
			(pintype "passive")
		)
		(pad "2" smd roundrect
			(at 0.48 0)
			(size 0.59 0.64)
			(layers "F.Cu" "F.Mask" "F.Paste")
			(roundrect_rratio 0.25)
			(net 179 "/PCIe-clock-generator/PCIe_{REF1}_R.CK-")
			(pintype "passive")
		)
	)
	(footprint "antmicro-footprints:SOT-23-3"
		(layer "F.Cu")
		(at 131.72 156.499998)
		(property "Reference" "Q3"
			(at 1.08 -0.699998 180)
			(layer "F.SilkS")
			(effects
				(font
					(size 0.7 0.7)
					(thickness 0.15)
				)
				(justify left bottom)
			)
		)
		(property "Value" "BSS138-7-F"
			(at -1.9 2.7 0)
			(layer "F.Fab")
			(effects
				(font
					(size 0.7 0.7)
					(thickness 0.15)
				)
				(justify left bottom)
			)
		)
		(property "Datasheet" "https://www.diodes.com/assets/Datasheets/ds30144.pdf"
			(at 0 0 0)
			(layer "F.Fab")
			(hide yes)
			(effects
				(font
					(size 1.27 1.27)
					(thickness 0.15)
				)
			)
		)
		(property "Description" "Power MOSFET, N Channel, 50 V, 200 mA, 1.4 ohm, SOT-23, Surface Mount"
			(at 0 0 0)
			(layer "F.Fab")
			(hide yes)
			(effects
				(font
					(size 1.27 1.27)
					(thickness 0.15)
				)
			)
		)
		(property "MPN" "BSS138-7-F"
			(at 0 0 0)
			(unlocked yes)
			(layer "F.Fab")
			(hide yes)
			(effects
				(font
					(size 1 1)
					(thickness 0.15)
				)
			)
		)
		(property "Manufacturer" "Diodes Incorporated"
			(at 0 0 0)
			(unlocked yes)
			(layer "F.Fab")
			(hide yes)
			(effects
				(font
					(size 1 1)
					(thickness 0.15)
				)
			)
		)
		(property "Author" "Antmicro"
			(at 0 0 0)
			(unlocked yes)
			(layer "F.Fab")
			(hide yes)
			(effects
				(font
					(size 1 1)
					(thickness 0.15)
				)
			)
		)
		(property "License" "Apache-2.0"
			(at 0 0 0)
			(unlocked yes)
			(layer "F.Fab")
			(hide yes)
			(effects
				(font
					(size 1 1)
					(thickness 0.15)
				)
			)
		)
		(sheetname "/Power/")
		(sheetfile "power.kicad_sch")
		(attr smd)
		(fp_line
			(start -1.45 -1.35)
			(end -0.85 -1.35)
			(stroke
				(width 0.15)
				(type solid)
			)
			(layer "F.SilkS")
		)
		(fp_line
			(start -0.85 -1.35)
			(end -0.7 -1.5)
			(stroke
				(width 0.15)
				(type solid)
			)
			(layer "F.SilkS")
		)
		(fp_line
			(start -0.7 1.5)
			(end -0.7 1.35)
			(stroke
				(width 0.15)
				(type solid)
			)
			(layer "F.SilkS")
		)
		(fp_line
			(start 0.7 -1.5)
			(end -0.7 -1.5)
			(stroke
				(width 0.15)
				(type solid)
			)
			(layer "F.SilkS")
		)
		(fp_line
			(start 0.7 -0.4)
			(end 0.7 -1.5)
			(stroke
				(width 0.15)
				(type solid)
			)
			(layer "F.SilkS")
		)
		(fp_line
			(start 0.7 0.4)
			(end 0.7 1.5)
			(stroke
				(width 0.15)
				(type solid)
			)
			(layer "F.SilkS")
		)
		(fp_line
			(start 0.7 1.5)
			(end -0.7 1.5)
			(stroke
				(width 0.15)
				(type solid)
			)
			(layer "F.SilkS")
		)
		(fp_line
			(start -1.75 -0.5)
			(end -1.75 -1.4)
			(stroke
				(width 0.05)
				(type solid)
			)
			(layer "F.CrtYd")
		)
		(fp_line
			(start -1.75 0.5)
			(end -0.85 0.5)
			(stroke
				(width 0.05)
				(type solid)
			)
			(layer "F.CrtYd")
		)
		(fp_line
			(start -1.75 1.4)
			(end -1.75 0.5)
			(stroke
				(width 0.05)
				(type solid)
			)
			(layer "F.CrtYd")
		)
		(fp_line
			(start -0.9 -1.6)
			(end -0.9 -1.4)
			(stroke
				(width 0.05)
				(type solid)
			)
			(layer "F.CrtYd")
		)
		(fp_line
			(start -0.9 -1.6)
			(end 0.825 -1.6)
			(stroke
				(width 0.05)
				(type solid)
			)
			(layer "F.CrtYd")
		)
		(fp_line
			(start -0.9 -1.4)
			(end -1.75 -1.4)
			(stroke
				(width 0.05)
				(type solid)
			)
			(layer "F.CrtYd")
		)
		(fp_line
			(start -0.85 -0.5)
			(end -1.75 -0.5)
			(stroke
				(width 0.05)
				(type solid)
			)
			(layer "F.CrtYd")
		)
		(fp_line
			(start -0.85 0.5)
			(end -0.85 -0.5)
			(stroke
				(width 0.05)
				(type solid)
			)
			(layer "F.CrtYd")
		)
		(fp_line
			(start -0.85 1.4)
			(end -1.75 1.4)
			(stroke
				(width 0.05)
				(type solid)
			)
			(layer "F.CrtYd")
		)
		(fp_line
			(start -0.85 1.65)
			(end -0.85 1.4)
			(stroke
				(width 0.05)
				(type solid)
			)
			(layer "F.CrtYd")
		)
		(fp_line
			(start 0.825 -1.6)
			(end 0.825 -0.45)
			(stroke
				(width 0.05)
				(type solid)
			)
			(layer "F.CrtYd")
		)
		(fp_line
			(start 0.825 -0.45)
			(end 1.75 -0.45)
			(stroke
				(width 0.05)
				(type solid)
			)
			(layer "F.CrtYd")
		)
		(fp_line
			(start 0.85 0.45)
			(end 0.85 1.65)
			(stroke
				(width 0.05)
				(type solid)
			)
			(layer "F.CrtYd")
		)
		(fp_line
			(start 0.85 1.65)
			(end -0.85 1.65)
			(stroke
				(width 0.05)
				(type solid)
			)
			(layer "F.CrtYd")
		)
		(fp_line
			(start 1.75 -0.45)
			(end 1.75 0.45)
			(stroke
				(width 0.05)
				(type solid)
			)
			(layer "F.CrtYd")
		)
		(fp_line
			(start 1.75 0.45)
			(end 0.85 0.45)
			(stroke
				(width 0.05)
				(type solid)
			)
			(layer "F.CrtYd")
		)
		(fp_line
			(start -0.712 -1.325)
			(end -0.712 1.523)
			(stroke
				(width 0.15)
				(type solid)
			)
			(layer "F.Fab")
		)
		(fp_line
			(start -0.712 1.519)
			(end 0.688 1.519)
			(stroke
				(width 0.15)
				(type solid)
			)
			(layer "F.Fab")
		)
		(fp_line
			(start -0.437 -1.526)
			(end -0.712 -1.325)
			(stroke
				(width 0.15)
				(type solid)
			)
			(layer "F.Fab")
		)
		(fp_line
			(start -0.437 -1.526)
			(end 0.688 -1.526)
			(stroke
				(width 0.15)
				(type solid)
			)
			(layer "F.Fab")
		)
		(fp_line
			(start 0.688 1.519)
			(end 0.688 -1.52)
			(stroke
				(width 0.15)
				(type solid)
			)
			(layer "F.Fab")
		)
		(fp_text user "License: Apache-2.0"
			(at -1.8 6.8 0)
			(layer "F.Fab")
			(effects
				(font
					(size 0.7 0.7)
					(thickness 0.15)
				)
				(justify left bottom)
			)
		)
		(fp_text user "Author: Antmicro"
			(at -1.837 5.3 0)
			(layer "F.Fab")
			(effects
				(font
					(size 0.7 0.7)
					(thickness 0.15)
				)
				(justify left bottom)
			)
		)
		(fp_text user "${REFERENCE}"
			(at 0.000001 0.025 0)
			(layer "F.Fab")
			(effects
				(font
					(size 0.7 0.7)
					(thickness 0.15)
				)
				(justify left bottom)
			)
		)
		(pad "1" smd roundrect
			(at -1.1 -0.951)
			(size 1 0.6)
			(layers "F.Cu" "F.Mask" "F.Paste")
			(roundrect_rratio 0.15)
			(net 172 "/Power/~{PERST}")
			(pinfunction "G")
			(pintype "input")
		)
		(pad "2" smd roundrect
			(at -1.1 0.949)
			(size 1 0.6)
			(layers "F.Cu" "F.Mask" "F.Paste")
			(roundrect_rratio 0.15)
			(net 66 "GND")
			(pinfunction "S")
			(pintype "passive")
		)
		(pad "3" smd roundrect
			(at 1.1 -0.0005)
			(size 1 0.6)
			(layers "F.Cu" "F.Mask" "F.Paste")
			(roundrect_rratio 0.15)
			(net 161 "Net-(Q3-D)")
			(pinfunction "D")
			(pintype "passive")
		)
	)
	(footprint "antmicro-footprints:C_0402_1005Metric"
		(layer "F.Cu")
		(at 120.5 134.8)
		(descr "Capacitor SMD 0402")
		(tags "capacitor SMD 0402")
		(property "Reference" "C7"
			(at -3.3 0.4 180)
			(layer "F.SilkS")
			(effects
				(font
					(size 0.7 0.7)
					(thickness 0.15)
				)
				(justify left bottom)
			)
		)
		(property "Value" "C_1u_25V_0402"
			(at -1.022927 2.155213 0)
			(layer "F.Fab")
			(effects
				(font
					(size 0.7 0.7)
					(thickness 0.15)
				)
				(justify left bottom)
			)
		)
		(property "Datasheet" "https://www.murata.com/products/productdetail?partno=GRM155R61E105KE11%23"
			(at 0 0 0)
			(layer "F.Fab")
			(hide yes)
			(effects
				(font
					(size 1.27 1.27)
					(thickness 0.15)
				)
			)
		)
		(property "Description" "SMD Multilayer Ceramic Capacitor, 1 µF, 25 V, 0402 [1005 Metric], ± 10%, X5R, GRM Series"
			(at 0 0 0)
			(layer "F.Fab")
			(hide yes)
			(effects
				(font
					(size 1.27 1.27)
					(thickness 0.15)
				)
			)
		)
		(property "MPN" "GRM155R61E105KE11J"
			(at 0 0 0)
			(unlocked yes)
			(layer "F.Fab")
			(hide yes)
			(effects
				(font
					(size 1 1)
					(thickness 0.15)
				)
			)
		)
		(property "Manufacturer" "Murata"
			(at 0 0 0)
			(unlocked yes)
			(layer "F.Fab")
			(hide yes)
			(effects
				(font
					(size 1 1)
					(thickness 0.15)
				)
			)
		)
		(property "License" "Apache-2.0"
			(at 0 0 0)
			(unlocked yes)
			(layer "F.Fab")
			(hide yes)
			(effects
				(font
					(size 1 1)
					(thickness 0.15)
				)
			)
		)
		(property "Author" "Antmicro"
			(at 0 0 0)
			(unlocked yes)
			(layer "F.Fab")
			(hide yes)
			(effects
				(font
					(size 1 1)
					(thickness 0.15)
				)
			)
		)
		(property "Val" "1u"
			(at 0 0 0)
			(unlocked yes)
			(layer "F.Fab")
			(hide yes)
			(effects
				(font
					(size 1 1)
					(thickness 0.15)
				)
			)
		)
		(property "Voltage" "25V"
			(at 0 0 0)
			(unlocked yes)
			(layer "F.Fab")
			(hide yes)
			(effects
				(font
					(size 1 1)
					(thickness 0.15)
				)
			)
		)
		(property "Dielectric" "X5R"
			(at 0 0 0)
			(unlocked yes)
			(layer "F.Fab")
			(hide yes)
			(effects
				(font
					(size 1 1)
					(thickness 0.15)
				)
			)
		)
		(sheetname "/Power/")
		(sheetfile "power.kicad_sch")
		(attr smd)
		(fp_rect
			(start -0.925 -0.47)
			(end 0.925 0.47)
			(stroke
				(width 0.05)
				(type default)
			)
			(fill no)
			(layer "F.CrtYd")
		)
		(fp_line
			(start -0.494 -0.25)
			(end 0.504 -0.25)
			(stroke
				(width 0.15)
				(type solid)
			)
			(layer "F.Fab")
		)
		(fp_line
			(start -0.494 0.248)
			(end -0.494 -0.25)
			(stroke
				(width 0.15)
				(type solid)
			)
			(layer "F.Fab")
		)
		(fp_line
			(start 0.504 -0.25)
			(end 0.504 0.248)
			(stroke
				(width 0.15)
				(type solid)
			)
			(layer "F.Fab")
		)
		(fp_line
			(start 0.504 0.248)
			(end -0.494 0.248)
			(stroke
				(width 0.15)
				(type solid)
			)
			(layer "F.Fab")
		)
		(fp_text user "License: Apache-2.0"
			(at -0.939 5.799 0)
			(layer "F.Fab")
			(effects
				(font
					(size 0.7 0.7)
					(thickness 0.15)
				)
				(justify left bottom)
			)
		)
		(fp_text user "${REFERENCE}"
			(at 0 0 0)
			(layer "F.Fab")
			(effects
				(font
					(size 0.7 0.7)
					(thickness 0.15)
				)
				(justify left bottom)
			)
		)
		(fp_text user "Author: Antmicro"
			(at -0.939 3.399 0)
			(layer "F.Fab")
			(effects
				(font
					(size 0.7 0.7)
					(thickness 0.15)
				)
				(justify left bottom)
			)
		)
		(pad "1" smd roundrect
			(at -0.48 0)
			(size 0.59 0.64)
			(layers "F.Cu" "F.Mask" "F.Paste")
			(roundrect_rratio 0.25)
			(net 66 "GND")
			(pintype "passive")
		)
		(pad "2" smd roundrect
			(at 0.48 0)
			(size 0.59 0.64)
			(layers "F.Cu" "F.Mask" "F.Paste")
			(roundrect_rratio 0.25)
			(net 88 "/Power/3V3_VCC")
			(pintype "passive")
		)
	)
	(footprint "antmicro-footprints:C_0402_1005Metric"
		(layer "F.Cu")
		(at 143.5 145 -90)
		(descr "Capacitor SMD 0402")
		(tags "capacitor SMD 0402")
		(property "Reference" "C13"
			(at -1 -0.8 90)
			(layer "F.SilkS")
			(effects
				(font
					(size 0.7 0.7)
					(thickness 0.15)
				)
				(justify right top)
			)
		)
		(property "Value" "C_100n_0402"
			(at -1.022927 2.155213 90)
			(layer "F.Fab")
			(effects
				(font
					(size 0.7 0.7)
					(thickness 0.15)
				)
				(justify right top)
			)
		)
		(property "Datasheet" "https://www.murata.com/products/productdetail?partno=GRM155R61H104KE14%23"
			(at 0 0 90)
			(layer "F.Fab")
			(hide yes)
			(effects
				(font
					(size 1.27 1.27)
					(thickness 0.15)
				)
			)
		)
		(property "Description" "SMD Multilayer Ceramic Capacitor, 0.1 µF, 50 V, 0402 [1005 Metric], ± 10%, X5R, GRM Series"
			(at 0 0 90)
			(layer "F.Fab")
			(hide yes)
			(effects
				(font
					(size 1.27 1.27)
					(thickness 0.15)
				)
			)
		)
		(property "MPN" "GRM155R61H104KE14D"
			(at 0 0 270)
			(unlocked yes)
			(layer "F.Fab")
			(hide yes)
			(effects
				(font
					(size 1 1)
					(thickness 0.15)
				)
			)
		)
		(property "Manufacturer" "Murata"
			(at 0 0 270)
			(unlocked yes)
			(layer "F.Fab")
			(hide yes)
			(effects
				(font
					(size 1 1)
					(thickness 0.15)
				)
			)
		)
		(property "License" "Apache-2.0"
			(at 0 0 270)
			(unlocked yes)
			(layer "F.Fab")
			(hide yes)
			(effects
				(font
					(size 1 1)
					(thickness 0.15)
				)
			)
		)
		(property "Author" "Antmicro"
			(at 0 0 270)
			(unlocked yes)
			(layer "F.Fab")
			(hide yes)
			(effects
				(font
					(size 1 1)
					(thickness 0.15)
				)
			)
		)
		(property "Val" "100n"
			(at 0 0 270)
			(unlocked yes)
			(layer "F.Fab")
			(hide yes)
			(effects
				(font
					(size 1 1)
					(thickness 0.15)
				)
			)
		)
		(property "Voltage" "50V"
			(at 0 0 270)
			(unlocked yes)
			(layer "F.Fab")
			(hide yes)
			(effects
				(font
					(size 1 1)
					(thickness 0.15)
				)
			)
		)
		(property "Dielectric" "X5R"
			(at 0 0 270)
			(unlocked yes)
			(layer "F.Fab")
			(hide yes)
			(effects
				(font
					(size 1 1)
					(thickness 0.15)
				)
			)
		)
		(sheetname "/Power/Ideal-diode-2/")
		(sheetfile "ideal-diode.kicad_sch")
		(attr smd)
		(fp_rect
			(start -0.925 -0.47)
			(end 0.925 0.47)
			(stroke
				(width 0.05)
				(type default)
			)
			(fill no)
			(layer "F.CrtYd")
		)
		(fp_line
			(start -0.494 0.248)
			(end -0.494 -0.25)
			(stroke
				(width 0.15)
				(type solid)
			)
			(layer "F.Fab")
		)
		(fp_line
			(start 0.504 0.248)
			(end -0.494 0.248)
			(stroke
				(width 0.15)
				(type solid)
			)
			(layer "F.Fab")
		)
		(fp_line
			(start -0.494 -0.25)
			(end 0.504 -0.25)
			(stroke
				(width 0.15)
				(type solid)
			)
			(layer "F.Fab")
		)
		(fp_line
			(start 0.504 -0.25)
			(end 0.504 0.248)
			(stroke
				(width 0.15)
				(type solid)
			)
			(layer "F.Fab")
		)
		(fp_text user "${REFERENCE}"
			(at 0 0 90)
			(layer "F.Fab")
			(effects
				(font
					(size 0.7 0.7)
					(thickness 0.15)
				)
				(justify right top)
			)
		)
		(fp_text user "License: Apache-2.0"
			(at -0.939 5.799 90)
			(layer "F.Fab")
			(effects
				(font
					(size 0.7 0.7)
					(thickness 0.15)
				)
				(justify right top)
			)
		)
		(fp_text user "Author: Antmicro"
			(at -0.939 3.399 90)
			(layer "F.Fab")
			(effects
				(font
					(size 0.7 0.7)
					(thickness 0.15)
				)
				(justify right top)
			)
		)
		(pad "1" smd roundrect
			(at -0.48 0 270)
			(size 0.59 0.64)
			(layers "F.Cu" "F.Mask" "F.Paste")
			(roundrect_rratio 0.25)
			(net 66 "GND")
			(pintype "passive")
		)
		(pad "2" smd roundrect
			(at 0.48 0 270)
			(size 0.59 0.64)
			(layers "F.Cu" "F.Mask" "F.Paste")
			(roundrect_rratio 0.25)
			(net 116 "/Power/Ideal-diode-2/VIN")
			(pintype "passive")
		)
	)
	(footprint "antmicro-footprints:MP_Pad6mm_Drill3.2mm"
		(layer "F.Cu")
		(at 156.4 162.8 -90)
		(property "Reference" "MP1"
			(at 0 0 90)
			(layer "F.SilkS")
			(hide yes)
			(effects
				(font
					(size 0.7 0.7)
					(thickness 0.15)
				)
				(justify right top)
			)
		)
		(property "Value" "MP_Pad6mm_Drill3.2mm"
			(at 0 3.899999 90)
			(layer "F.Fab")
			(effects
				(font
					(size 0.7 0.7)
					(thickness 0.15)
				)
				(justify right top)
			)
		)
		(property "Description" "Mechanical part"
			(at 0 0 90)
			(layer "F.Fab")
			(hide yes)
			(effects
				(font
					(size 1.27 1.27)
					(thickness 0.15)
				)
			)
		)
		(property "Author" "Antmicro"
			(at 0 0 270)
			(unlocked yes)
			(layer "F.Fab")
			(hide yes)
			(effects
				(font
					(size 1 1)
					(thickness 0.15)
				)
			)
		)
		(property "License" "Apache-2.0"
			(at 0 0 270)
			(unlocked yes)
			(layer "F.Fab")
			(hide yes)
			(effects
				(font
					(size 1 1)
					(thickness 0.15)
				)
			)
		)
		(sheetname "/")
		(sheetfile "oculink-to-pcie-adapter.kicad_sch")
		(attr exclude_from_pos_files exclude_from_bom)
		(fp_circle
			(center 0 0)
			(end 3.25 0)
			(stroke
				(width 0.05)
				(type default)
			)
			(fill no)
			(layer "F.CrtYd")
		)
		(fp_text user "License: Apache-2.0"
			(at -0.178 8.425001 90)
			(layer "F.Fab")
			(effects
				(font
					(size 0.7 0.7)
					(thickness 0.15)
				)
				(justify right top)
			)
		)
		(fp_text user "${REFERENCE}"
			(at 0 0 90)
			(layer "F.Fab")
			(effects
				(font
					(size 0.7 0.7)
					(thickness 0.15)
				)
				(justify right top)
			)
		)
		(fp_text user "Author: Antmicro"
			(at -0.178001 7.225 90)
			(layer "F.Fab")
			(effects
				(font
					(size 0.7 0.7)
					(thickness 0.15)
				)
				(justify right top)
			)
		)
		(pad "1" thru_hole circle
			(at 0 0 270)
			(size 6 6)
			(drill 3.2)
			(layers "*.Cu" "*.Mask")
			(remove_unused_layers no)
			(net 66 "GND")
			(pintype "passive")
		)
	)
	(footprint "antmicro-footprints:C_0402_1005Metric"
		(layer "F.Cu")
		(at 138.499999 108.85 -90)
		(descr "Capacitor SMD 0402")
		(tags "capacitor SMD 0402")
		(property "Reference" "C33"
			(at 0.95 0.499999 90)
			(layer "F.SilkS")
			(effects
				(font
					(size 0.7 0.7)
					(thickness 0.15)
				)
				(justify right top)
			)
		)
		(property "Value" "C_1u_25V_0402"
			(at -1.022927 2.155213 90)
			(layer "F.Fab")
			(effects
				(font
					(size 0.7 0.7)
					(thickness 0.15)
				)
				(justify right top)
			)
		)
		(property "Datasheet" "https://www.murata.com/products/productdetail?partno=GRM155R61E105KE11%23"
			(at 0 0 90)
			(layer "F.Fab")
			(hide yes)
			(effects
				(font
					(size 1.27 1.27)
					(thickness 0.15)
				)
			)
		)
		(property "Description" "SMD Multilayer Ceramic Capacitor, 1 µF, 25 V, 0402 [1005 Metric], ± 10%, X5R, GRM Series"
			(at 0 0 90)
			(layer "F.Fab")
			(hide yes)
			(effects
				(font
					(size 1.27 1.27)
					(thickness 0.15)
				)
			)
		)
		(property "MPN" "GRM155R61E105KE11J"
			(at 0 0 270)
			(unlocked yes)
			(layer "F.Fab")
			(hide yes)
			(effects
				(font
					(size 1 1)
					(thickness 0.15)
				)
			)
		)
		(property "Manufacturer" "Murata"
			(at 0 0 270)
			(unlocked yes)
			(layer "F.Fab")
			(hide yes)
			(effects
				(font
					(size 1 1)
					(thickness 0.15)
				)
			)
		)
		(property "License" "Apache-2.0"
			(at 0 0 270)
			(unlocked yes)
			(layer "F.Fab")
			(hide yes)
			(effects
				(font
					(size 1 1)
					(thickness 0.15)
				)
			)
		)
		(property "Author" "Antmicro"
			(at 0 0 270)
			(unlocked yes)
			(layer "F.Fab")
			(hide yes)
			(effects
				(font
					(size 1 1)
					(thickness 0.15)
				)
			)
		)
		(property "Val" "1u"
			(at 0 0 270)
			(unlocked yes)
			(layer "F.Fab")
			(hide yes)
			(effects
				(font
					(size 1 1)
					(thickness 0.15)
				)
			)
		)
		(property "Voltage" "25V"
			(at 0 0 270)
			(unlocked yes)
			(layer "F.Fab")
			(hide yes)
			(effects
				(font
					(size 1 1)
					(thickness 0.15)
				)
			)
		)
		(property "Dielectric" "X5R"
			(at 0 0 270)
			(unlocked yes)
			(layer "F.Fab")
			(hide yes)
			(effects
				(font
					(size 1 1)
					(thickness 0.15)
				)
			)
		)
		(sheetname "/Power/Ideal-diode-0/")
		(sheetfile "ideal-diode.kicad_sch")
		(attr smd)
		(fp_rect
			(start -0.925 -0.47)
			(end 0.925 0.47)
			(stroke
				(width 0.05)
				(type default)
			)
			(fill no)
			(layer "F.CrtYd")
		)
		(fp_line
			(start -0.494 0.248)
			(end -0.494 -0.25)
			(stroke
				(width 0.15)
				(type solid)
			)
			(layer "F.Fab")
		)
		(fp_line
			(start 0.504 0.248)
			(end -0.494 0.248)
			(stroke
				(width 0.15)
				(type solid)
			)
			(layer "F.Fab")
		)
		(fp_line
			(start -0.494 -0.25)
			(end 0.504 -0.25)
			(stroke
				(width 0.15)
				(type solid)
			)
			(layer "F.Fab")
		)
		(fp_line
			(start 0.504 -0.25)
			(end 0.504 0.248)
			(stroke
				(width 0.15)
				(type solid)
			)
			(layer "F.Fab")
		)
		(fp_text user "Author: Antmicro"
			(at -0.939 3.399 90)
			(layer "F.Fab")
			(effects
				(font
					(size 0.7 0.7)
					(thickness 0.15)
				)
				(justify right top)
			)
		)
		(fp_text user "${REFERENCE}"
			(at 0 0 90)
			(layer "F.Fab")
			(effects
				(font
					(size 0.7 0.7)
					(thickness 0.15)
				)
				(justify right top)
			)
		)
		(fp_text user "License: Apache-2.0"
			(at -0.939 5.799 90)
			(layer "F.Fab")
			(effects
				(font
					(size 0.7 0.7)
					(thickness 0.15)
				)
				(justify right top)
			)
		)
		(pad "1" smd roundrect
			(at -0.48 0 270)
			(size 0.59 0.64)
			(layers "F.Cu" "F.Mask" "F.Paste")
			(roundrect_rratio 0.25)
			(net 66 "GND")
			(pintype "passive")
		)
		(pad "2" smd roundrect
			(at 0.48 0 270)
			(size 0.59 0.64)
			(layers "F.Cu" "F.Mask" "F.Paste")
			(roundrect_rratio 0.25)
			(net 87 "+12V")
			(pintype "passive")
		)
	)
	(footprint "antmicro-footprints:R_0603_1608Metric"
		(layer "F.Cu")
		(at 146.5 124.5 180)
		(descr "Resistor SMD 0603")
		(tags "resistor SMD 0603")
		(property "Reference" "R45"
			(at 1 -1.5 0)
			(layer "F.SilkS")
			(effects
				(font
					(size 0.7 0.7)
					(thickness 0.15)
				)
				(justify left bottom)
			)
		)
		(property "Value" "R_0R_22.4A_0603"
			(at 0 1.6 0)
			(layer "F.Fab")
			(effects
				(font
					(size 0.7 0.7)
					(thickness 0.15)
				)
				(justify right top)
			)
		)
		(property "Datasheet" "https://fscdn.rohm.com/en/products/databook/datasheet/passive/resistor/chip_resistor/pmr-jpw-e.pdf"
			(at 0 0 0)
			(layer "F.Fab")
			(hide yes)
			(effects
				(font
					(size 1.27 1.27)
					(thickness 0.15)
				)
			)
		)
		(property "Description" "SMD Chip Resistor"
			(at 0 0 0)
			(layer "F.Fab")
			(hide yes)
			(effects
				(font
					(size 1.27 1.27)
					(thickness 0.15)
				)
			)
		)
		(property "MPN" "PMR03EZPJ000"
			(at 0 0 180)
			(unlocked yes)
			(layer "F.Fab")
			(hide yes)
			(effects
				(font
					(size 1 1)
					(thickness 0.15)
				)
			)
		)
		(property "Manufacturer" "ROHM Semiconductor"
			(at 0 0 180)
			(unlocked yes)
			(layer "F.Fab")
			(hide yes)
			(effects
				(font
					(size 1 1)
					(thickness 0.15)
				)
			)
		)
		(property "Val" "0R"
			(at 0 0 180)
			(unlocked yes)
			(layer "F.Fab")
			(hide yes)
			(effects
				(font
					(size 1 1)
					(thickness 0.15)
				)
			)
		)
		(property "Max. Curr." "22.4A"
			(at 0 0 180)
			(unlocked yes)
			(layer "F.Fab")
			(hide yes)
			(effects
				(font
					(size 1 1)
					(thickness 0.15)
				)
			)
		)
		(property "Author" "Antmicro"
			(at 0 0 180)
			(unlocked yes)
			(layer "F.Fab")
			(hide yes)
			(effects
				(font
					(size 1 1)
					(thickness 0.15)
				)
			)
		)
		(property "License" "Apache-2.0"
			(at 0 0 180)
			(unlocked yes)
			(layer "F.Fab")
			(hide yes)
			(effects
				(font
					(size 1 1)
					(thickness 0.15)
				)
			)
		)
		(property "Tolerance" "template_tolerance"
			(at 0 0 180)
			(unlocked yes)
			(layer "F.Fab")
			(hide yes)
			(effects
				(font
					(size 1 1)
					(thickness 0.15)
				)
			)
		)
		(sheetname "/")
		(sheetfile "oculink-to-pcie-adapter.kicad_sch")
		(attr smd exclude_from_bom dnp)
		(fp_line
			(start -0.15 0.4)
			(end 0.15 0.4)
			(stroke
				(width 0.15)
				(type solid)
			)
			(layer "F.SilkS")
		)
		(fp_line
			(start -0.15 -0.4)
			(end 0.15 -0.4)
			(stroke
				(width 0.15)
				(type solid)
			)
			(layer "F.SilkS")
		)
		(fp_rect
			(start -1.25 -0.65)
			(end 1.25 0.65)
			(stroke
				(width 0.05)
				(type solid)
			)
			(fill no)
			(layer "F.CrtYd")
		)
		(fp_rect
			(start -0.8 -0.4)
			(end 0.8 0.4)
			(stroke
				(width 0.15)
				(type solid)
			)
			(fill no)
			(layer "F.Fab")
		)
		(fp_text user "License: Apache-2.0"
			(at -1.249999 5.9 0)
			(layer "F.Fab")
			(effects
				(font
					(size 0.7 0.7)
					(thickness 0.15)
				)
				(justify right top)
			)
		)
		(fp_text user "Author: Antmicro"
			(at -1.25 4.9 0)
			(layer "F.Fab")
			(effects
				(font
					(size 0.7 0.7)
					(thickness 0.15)
				)
				(justify right top)
			)
		)
		(fp_text user "${REFERENCE}"
			(at 0 0 0)
			(layer "F.Fab")
			(effects
				(font
					(size 0.7 0.7)
					(thickness 0.15)
				)
				(justify right top)
			)
		)
		(pad "1" smd roundrect
			(at -0.7 0 180)
			(size 0.8 1)
			(layers "F.Cu" "F.Mask" "F.Paste")
			(roundrect_rratio 0.2)
			(net 169 "/Power/VCC_DC_CONN_2")
			(pintype "passive")
		)
		(pad "2" smd roundrect
			(at 0.7 0 180)
			(size 0.8 1)
			(layers "F.Cu" "F.Mask" "F.Paste")
			(roundrect_rratio 0.2)
			(net 168 "/Power/VCC_DC_CONN_1")
			(pintype "passive")
		)
	)
	(footprint "antmicro-footprints:Mech_Lightpipe_Mentor_1296.2013"
		(layer "F.Cu")
		(at 151.5 159.71 180)
		(property "Reference" "H1"
			(at 0 -0.499999 270)
			(layer "F.SilkS")
			(hide yes)
			(effects
				(font
					(size 0.7 0.7)
					(thickness 0.15)
				)
				(justify left bottom)
			)
		)
		(property "Value" "Lightpipe_Mentor_1296.2013"
			(at -1.749999 6.25 180)
			(unlocked yes)
			(layer "F.Fab")
			(effects
				(font
					(size 0.7 0.7)
					(thickness 0.15)
				)
				(justify left bottom)
			)
		)
		(property "Datasheet" "https://docs.rs-online.com/e47b/0900766b813f6efb.pdf"
			(at 0 0 0)
			(layer "F.Fab")
			(hide yes)
			(effects
				(font
					(size 1.27 1.27)
					(thickness 0.15)
				)
			)
		)
		(property "Description" "Light Pipe, Miniature Triple Line, 14.45 mm, 3 Pipes, Circular, PC Board, Transparent"
			(at 0 0 0)
			(layer "F.Fab")
			(hide yes)
			(effects
				(font
					(size 1.27 1.27)
					(thickness 0.15)
				)
			)
		)
		(property "Manufacturer" "Mentor Worldwide"
			(at 0 0 180)
			(unlocked yes)
			(layer "F.Fab")
			(hide yes)
			(effects
				(font
					(size 1 1)
					(thickness 0.15)
				)
			)
		)
		(property "MPN" "1296.2013"
			(at 0 0 180)
			(unlocked yes)
			(layer "F.Fab")
			(hide yes)
			(effects
				(font
					(size 1 1)
					(thickness 0.15)
				)
			)
		)
		(property "Author" "Antmicro"
			(at 0 0 180)
			(unlocked yes)
			(layer "F.Fab")
			(hide yes)
			(effects
				(font
					(size 1 1)
					(thickness 0.15)
				)
			)
		)
		(property "License" "Apache-2.0"
			(at 0 0 180)
			(unlocked yes)
			(layer "F.Fab")
			(hide yes)
			(effects
				(font
					(size 1 1)
					(thickness 0.15)
				)
			)
		)
		(sheetname "/Power/")
		(sheetfile "power.kicad_sch")
		(attr dnp)
		(fp_rect
			(start -1.508 -6.335)
			(end 1.507 5.289)
			(stroke
				(width 0.15)
				(type solid)
			)
			(fill no)
			(layer "F.SilkS")
		)
		(fp_text user "Author: Antmicro"
			(at -1.75 8.75 0)
			(layer "F.Fab")
			(effects
				(font
					(size 0.7 0.7)
					(thickness 0.15)
				)
				(justify right top)
			)
		)
		(fp_text user "${REFERENCE}"
			(at -1.75 7.5 0)
			(layer "F.Fab")
			(effects
				(font
					(size 0.7 0.7)
					(thickness 0.15)
				)
				(justify right top)
			)
		)
		(fp_text user "License: Apache-2.0"
			(at -1.749999 10.25 0)
			(layer "F.Fab")
			(effects
				(font
					(size 0.7 0.7)
					(thickness 0.15)
				)
				(justify right top)
			)
		)
		(pad "" np_thru_hole circle
			(at 0 -4.96 180)
			(size 1.2 1.2)
			(drill 1.2)
			(layers "F&B.Cu" "*.Mask")
		)
		(pad "" np_thru_hole circle
			(at 0 4.24 180)
			(size 1.2 1.2)
			(drill 1.2)
			(layers "F&B.Cu" "*.Mask")
		)
	)
	(footprint "antmicro-footprints:R_0402_1005Metric"
		(layer "F.Cu")
		(at 148.152 87)
		(descr "Resistor SMD 0402")
		(tags "resistor SMD 0402")
		(property "Reference" "R32"
			(at 1.248 0.3 180)
			(layer "F.SilkS")
			(effects
				(font
					(size 0.7 0.7)
					(thickness 0.15)
				)
				(justify left bottom)
			)
		)
		(property "Value" "R_100k_0402"
			(at -1.011843 1.772046 0)
			(layer "F.Fab")
			(effects
				(font
					(size 0.7 0.7)
					(thickness 0.15)
				)
				(justify left bottom)
			)
		)
		(property "Datasheet" "https://www.bourns.com/docs/product-datasheets/cr.pdf"
			(at 0 0 0)
			(layer "F.Fab")
			(hide yes)
			(effects
				(font
					(size 1.27 1.27)
					(thickness 0.15)
				)
			)
		)
		(property "Description" "SMD Chip Resistor, 100 kohm, ± 1%, 62.5 mW, 0402 [1005 Metric], Thick Film, General Purpose"
			(at 0 0 0)
			(layer "F.Fab")
			(hide yes)
			(effects
				(font
					(size 1.27 1.27)
					(thickness 0.15)
				)
			)
		)
		(property "Manufacturer" "Bourns"
			(at 0 0 0)
			(unlocked yes)
			(layer "F.Fab")
			(hide yes)
			(effects
				(font
					(size 1 1)
					(thickness 0.15)
				)
			)
		)
		(property "MPN" "CR0402-FX-1003GLF"
			(at 0 0 0)
			(unlocked yes)
			(layer "F.Fab")
			(hide yes)
			(effects
				(font
					(size 1 1)
					(thickness 0.15)
				)
			)
		)
		(property "Val" "100k"
			(at 0 0 0)
			(unlocked yes)
			(layer "F.Fab")
			(hide yes)
			(effects
				(font
					(size 1 1)
					(thickness 0.15)
				)
			)
		)
		(property "License" "Apache-2.0"
			(at 0 0 0)
			(unlocked yes)
			(layer "F.Fab")
			(hide yes)
			(effects
				(font
					(size 1 1)
					(thickness 0.15)
				)
			)
		)
		(property "Author" "Antmicro"
			(at 0 0 0)
			(unlocked yes)
			(layer "F.Fab")
			(hide yes)
			(effects
				(font
					(size 1 1)
					(thickness 0.15)
				)
			)
		)
		(property "Tolerance" "1%"
			(at 0 0 0)
			(unlocked yes)
			(layer "F.Fab")
			(hide yes)
			(effects
				(font
					(size 1 1)
					(thickness 0.15)
				)
			)
		)
		(sheetname "/USB-PD/")
		(sheetfile "usb-pd.kicad_sch")
		(attr smd)
		(fp_rect
			(start -0.925 -0.47)
			(end 0.925 0.47)
			(stroke
				(width 0.05)
				(type default)
			)
			(fill no)
			(layer "F.CrtYd")
		)
		(fp_rect
			(start -0.5 -0.25)
			(end 0.5 0.25)
			(stroke
				(width 0.15)
				(type solid)
			)
			(fill no)
			(layer "F.Fab")
		)
		(fp_text user "License: Apache-2.0"
			(at -0.949999 5.169 0)
			(layer "F.Fab")
			(effects
				(font
					(size 0.7 0.7)
					(thickness 0.15)
				)
				(justify left bottom)
			)
		)
		(fp_text user "${REFERENCE}"
			(at 0 0 0)
			(layer "F.Fab")
			(effects
				(font
					(size 0.7 0.7)
					(thickness 0.15)
				)
				(justify left bottom)
			)
		)
		(fp_text user "Author: Antmicro"
			(at -0.95 4.169 0)
			(layer "F.Fab")
			(effects
				(font
					(size 0.7 0.7)
					(thickness 0.15)
				)
				(justify left bottom)
			)
		)
		(pad "1" smd roundrect
			(at -0.48 0)
			(size 0.59 0.64)
			(layers "F.Cu" "F.Mask" "F.Paste")
			(roundrect_rratio 0.25)
			(net 156 "/USB-PD/12V_EN")
			(pintype "passive")
		)
		(pad "2" smd roundrect
			(at 0.48 0)
			(size 0.59 0.64)
			(layers "F.Cu" "F.Mask" "F.Paste")
			(roundrect_rratio 0.25)
			(net 115 "/USB-PD/VCC")
			(pintype "passive")
		)
	)
	(footprint "antmicro-footprints:R_0402_1005Metric"
		(layer "F.Cu")
		(at 148.152 91 180)
		(descr "Resistor SMD 0402")
		(tags "resistor SMD 0402")
		(property "Reference" "R30"
			(at -3.448 0.5 180)
			(layer "F.SilkS")
			(effects
				(font
					(size 0.7 0.7)
					(thickness 0.15)
				)
				(justify right top)
			)
		)
		(property "Value" "R_0R_0402"
			(at -1.011843 1.772046 0)
			(layer "F.Fab")
			(effects
				(font
					(size 0.7 0.7)
					(thickness 0.15)
				)
				(justify right top)
			)
		)
		(property "Datasheet" "https://industrial.panasonic.com/cdbs/www-data/pdf/RDA0000/AOA0000C301.pdf"
			(at 0 0 0)
			(layer "F.Fab")
			(hide yes)
			(effects
				(font
					(size 1.27 1.27)
					(thickness 0.15)
				)
			)
		)
		(property "Description" "SMD Chip Resistor, Jumper, 0 ohm, 100 mW, 0402 [1005 Metric], Thick Film, General Purpose"
			(at 0 0 0)
			(layer "F.Fab")
			(hide yes)
			(effects
				(font
					(size 1.27 1.27)
					(thickness 0.15)
				)
			)
		)
		(property "Manufacturer" "Panasonic"
			(at 0 0 180)
			(unlocked yes)
			(layer "F.Fab")
			(hide yes)
			(effects
				(font
					(size 1 1)
					(thickness 0.15)
				)
			)
		)
		(property "MPN" "ERJ2GE0R00X"
			(at 0 0 180)
			(unlocked yes)
			(layer "F.Fab")
			(hide yes)
			(effects
				(font
					(size 1 1)
					(thickness 0.15)
				)
			)
		)
		(property "Val" "0R"
			(at 0 0 180)
			(unlocked yes)
			(layer "F.Fab")
			(hide yes)
			(effects
				(font
					(size 1 1)
					(thickness 0.15)
				)
			)
		)
		(property "License" "Apache-2.0"
			(at 0 0 180)
			(unlocked yes)
			(layer "F.Fab")
			(hide yes)
			(effects
				(font
					(size 1 1)
					(thickness 0.15)
				)
			)
		)
		(property "Author" "Antmicro"
			(at 0 0 180)
			(unlocked yes)
			(layer "F.Fab")
			(hide yes)
			(effects
				(font
					(size 1 1)
					(thickness 0.15)
				)
			)
		)
		(property "Tolerance" ""
			(at 0 0 180)
			(unlocked yes)
			(layer "F.Fab")
			(hide yes)
			(effects
				(font
					(size 1 1)
					(thickness 0.15)
				)
			)
		)
		(property "Current" "1A"
			(at 0 0 180)
			(unlocked yes)
			(layer "F.Fab")
			(hide yes)
			(effects
				(font
					(size 1 1)
					(thickness 0.15)
				)
			)
		)
		(sheetname "/USB-PD/")
		(sheetfile "usb-pd.kicad_sch")
		(attr smd)
		(fp_rect
			(start -0.925 -0.47)
			(end 0.925 0.47)
			(stroke
				(width 0.05)
				(type default)
			)
			(fill no)
			(layer "F.CrtYd")
		)
		(fp_rect
			(start -0.5 -0.25)
			(end 0.5 0.25)
			(stroke
				(width 0.15)
				(type solid)
			)
			(fill no)
			(layer "F.Fab")
		)
		(fp_text user "Author: Antmicro"
			(at -0.95 4.169 0)
			(layer "F.Fab")
			(effects
				(font
					(size 0.7 0.7)
					(thickness 0.15)
				)
				(justify right top)
			)
		)
		(fp_text user "License: Apache-2.0"
			(at -0.949999 5.169 0)
			(layer "F.Fab")
			(effects
				(font
					(size 0.7 0.7)
					(thickness 0.15)
				)
				(justify right top)
			)
		)
		(fp_text user "${REFERENCE}"
			(at 0 0 0)
			(layer "F.Fab")
			(effects
				(font
					(size 0.7 0.7)
					(thickness 0.15)
				)
				(justify right top)
			)
		)
		(pad "1" smd roundrect
			(at -0.48 0 180)
			(size 0.59 0.64)
			(layers "F.Cu" "F.Mask" "F.Paste")
			(roundrect_rratio 0.25)
			(net 121 "/USB-PD/12V_VDD")
			(pintype "passive")
		)
		(pad "2" smd roundrect
			(at 0.48 0 180)
			(size 0.59 0.64)
			(layers "F.Cu" "F.Mask" "F.Paste")
			(roundrect_rratio 0.25)
			(net 155 "/USB-PD/12V_ILIM")
			(pintype "passive")
		)
	)
	(footprint "antmicro-footprints:C_0402_1005Metric"
		(layer "F.Cu")
		(at 141 146.75 180)
		(descr "Capacitor SMD 0402")
		(tags "capacitor SMD 0402")
		(property "Reference" "C14"
			(at -1 -0.65 180)
			(layer "F.SilkS")
			(effects
				(font
					(size 0.7 0.7)
					(thickness 0.15)
				)
				(justify right top)
			)
		)
		(property "Value" "C_1u_25V_0402"
			(at -1.022927 2.155213 0)
			(layer "F.Fab")
			(effects
				(font
					(size 0.7 0.7)
					(thickness 0.15)
				)
				(justify right top)
			)
		)
		(property "Datasheet" "https://www.murata.com/products/productdetail?partno=GRM155R61E105KE11%23"
			(at 0 0 0)
			(layer "F.Fab")
			(hide yes)
			(effects
				(font
					(size 1.27 1.27)
					(thickness 0.15)
				)
			)
		)
		(property "Description" "SMD Multilayer Ceramic Capacitor, 1 µF, 25 V, 0402 [1005 Metric], ± 10%, X5R, GRM Series"
			(at 0 0 0)
			(layer "F.Fab")
			(hide yes)
			(effects
				(font
					(size 1.27 1.27)
					(thickness 0.15)
				)
			)
		)
		(property "MPN" "GRM155R61E105KE11J"
			(at 0 0 180)
			(unlocked yes)
			(layer "F.Fab")
			(hide yes)
			(effects
				(font
					(size 1 1)
					(thickness 0.15)
				)
			)
		)
		(property "Manufacturer" "Murata"
			(at 0 0 180)
			(unlocked yes)
			(layer "F.Fab")
			(hide yes)
			(effects
				(font
					(size 1 1)
					(thickness 0.15)
				)
			)
		)
		(property "License" "Apache-2.0"
			(at 0 0 180)
			(unlocked yes)
			(layer "F.Fab")
			(hide yes)
			(effects
				(font
					(size 1 1)
					(thickness 0.15)
				)
			)
		)
		(property "Author" "Antmicro"
			(at 0 0 180)
			(unlocked yes)
			(layer "F.Fab")
			(hide yes)
			(effects
				(font
					(size 1 1)
					(thickness 0.15)
				)
			)
		)
		(property "Val" "1u"
			(at 0 0 180)
			(unlocked yes)
			(layer "F.Fab")
			(hide yes)
			(effects
				(font
					(size 1 1)
					(thickness 0.15)
				)
			)
		)
		(property "Voltage" "25V"
			(at 0 0 180)
			(unlocked yes)
			(layer "F.Fab")
			(hide yes)
			(effects
				(font
					(size 1 1)
					(thickness 0.15)
				)
			)
		)
		(property "Dielectric" "X5R"
			(at 0 0 180)
			(unlocked yes)
			(layer "F.Fab")
			(hide yes)
			(effects
				(font
					(size 1 1)
					(thickness 0.15)
				)
			)
		)
		(sheetname "/Power/Ideal-diode-2/")
		(sheetfile "ideal-diode.kicad_sch")
		(attr smd)
		(fp_rect
			(start -0.925 -0.47)
			(end 0.925 0.47)
			(stroke
				(width 0.05)
				(type default)
			)
			(fill no)
			(layer "F.CrtYd")
		)
		(fp_line
			(start 0.504 0.248)
			(end -0.494 0.248)
			(stroke
				(width 0.15)
				(type solid)
			)
			(layer "F.Fab")
		)
		(fp_line
			(start 0.504 -0.25)
			(end 0.504 0.248)
			(stroke
				(width 0.15)
				(type solid)
			)
			(layer "F.Fab")
		)
		(fp_line
			(start -0.494 0.248)
			(end -0.494 -0.25)
			(stroke
				(width 0.15)
				(type solid)
			)
			(layer "F.Fab")
		)
		(fp_line
			(start -0.494 -0.25)
			(end 0.504 -0.25)
			(stroke
				(width 0.15)
				(type solid)
			)
			(layer "F.Fab")
		)
		(fp_text user "${REFERENCE}"
			(at 0 0 0)
			(layer "F.Fab")
			(effects
				(font
					(size 0.7 0.7)
					(thickness 0.15)
				)
				(justify right top)
			)
		)
		(fp_text user "Author: Antmicro"
			(at -0.939 3.399 0)
			(layer "F.Fab")
			(effects
				(font
					(size 0.7 0.7)
					(thickness 0.15)
				)
				(justify right top)
			)
		)
		(fp_text user "License: Apache-2.0"
			(at -0.939 5.799 0)
			(layer "F.Fab")
			(effects
				(font
					(size 0.7 0.7)
					(thickness 0.15)
				)
				(justify right top)
			)
		)
		(pad "1" smd roundrect
			(at -0.48 0 180)
			(size 0.59 0.64)
			(layers "F.Cu" "F.Mask" "F.Paste")
			(roundrect_rratio 0.25)
			(net 66 "GND")
			(pintype "passive")
		)
		(pad "2" smd roundrect
			(at 0.48 0 180)
			(size 0.59 0.64)
			(layers "F.Cu" "F.Mask" "F.Paste")
			(roundrect_rratio 0.25)
			(net 87 "+12V")
			(pintype "passive")
		)
	)
	(footprint "antmicro-footprints:USON-10_2.5x1mm_P0.5mm"
		(layer "F.Cu")
		(at 127.298 43.387 -90)
		(descr "USON-10 2.5x1mm_ Pitch 0.5mm")
		(tags "USON-10 2.5x1mm Pitch 0.5mm")
		(property "Reference" "D14"
			(at 1.113 -0.452 180)
			(layer "F.SilkS")
			(effects
				(font
					(size 0.7 0.7)
					(thickness 0.15)
				)
				(justify right top)
			)
		)
		(property "Value" "ESD204DQAR"
			(at 0.018 2.499 90)
			(layer "F.Fab")
			(effects
				(font
					(size 0.7 0.7)
					(thickness 0.15)
				)
				(justify right top)
			)
		)
		(property "Datasheet" "https://www.ti.com/lit/ds/symlink/esd204.pdf?ts=1706004844383&ref_url=https%253A%252F%252Fwww.ti.com%252Finterface%252Fdiodes%252Fesd-protection-diodes%252Fproducts.html"
			(at 0 0 90)
			(layer "F.Fab")
			(hide yes)
			(effects
				(font
					(size 1.27 1.27)
					(thickness 0.15)
				)
			)
		)
		(property "Description" "TVS diode array, 30 kV, USON-10, 3.6 V, 0.55 pF"
			(at 0 0 90)
			(layer "F.Fab")
			(hide yes)
			(effects
				(font
					(size 1.27 1.27)
					(thickness 0.15)
				)
			)
		)
		(property "MPN" "ESD204DQAR"
			(at 0 0 270)
			(unlocked yes)
			(layer "F.Fab")
			(hide yes)
			(effects
				(font
					(size 1 1)
					(thickness 0.15)
				)
			)
		)
		(property "Manufacturer" "Texas Instruments"
			(at 0 0 270)
			(unlocked yes)
			(layer "F.Fab")
			(hide yes)
			(effects
				(font
					(size 1 1)
					(thickness 0.15)
				)
			)
		)
		(property "Author" "Antmicro"
			(at 0 0 270)
			(unlocked yes)
			(layer "F.Fab")
			(hide yes)
			(effects
				(font
					(size 1 1)
					(thickness 0.15)
				)
			)
		)
		(property "License" "Apache-2.0"
			(at 0 0 270)
			(unlocked yes)
			(layer "F.Fab")
			(hide yes)
			(effects
				(font
					(size 1 1)
					(thickness 0.15)
				)
			)
		)
		(sheetname "/OCuLink/")
		(sheetfile "oculink.kicad_sch")
		(attr smd)
		(fp_line
			(start 0.498 1.398)
			(end -0.5 1.398)
			(stroke
				(width 0.15)
				(type solid)
			)
			(layer "F.SilkS")
		)
		(fp_line
			(start 0.498 -1.401)
			(end -0.5 -1.401)
			(stroke
				(width 0.15)
				(type solid)
			)
			(layer "F.SilkS")
		)
		(fp_circle
			(center -0.68 -1.27)
			(end -0.63 -1.27)
			(stroke
				(width 0.15)
				(type solid)
			)
			(fill yes)
			(layer "F.SilkS")
		)
		(fp_rect
			(start -0.8 -1.5)
			(end 0.8 1.499)
			(stroke
				(width 0.05)
				(type solid)
			)
			(fill no)
			(layer "F.CrtYd")
		)
		(fp_line
			(start -0.5 1.249)
			(end 0.498 1.249)
			(stroke
				(width 0.15)
				(type solid)
			)
			(layer "F.Fab")
		)
		(fp_line
			(start -0.5 -1)
			(end -0.5 1.249)
			(stroke
				(width 0.15)
				(type solid)
			)
			(layer "F.Fab")
		)
		(fp_line
			(start -0.25 -1.25)
			(end -0.5 -1)
			(stroke
				(width 0.15)
				(type solid)
			)
			(layer "F.Fab")
		)
		(fp_line
			(start 0.498 -1.25)
			(end 0.498 1.249)
			(stroke
				(width 0.15)
				(type solid)
			)
			(layer "F.Fab")
		)
		(fp_line
			(start 0.498 -1.25)
			(end -0.25 -1.25)
			(stroke
				(width 0.15)
				(type solid)
			)
			(layer "F.Fab")
		)
		(fp_text user "${REFERENCE}"
			(at 0 -0.000501 90)
			(layer "F.Fab")
			(effects
				(font
					(size 0.7 0.7)
					(thickness 0.15)
				)
				(justify right top)
			)
		)
		(fp_text user "Author: Antmicro"
			(at -0.802 5.7 90)
			(layer "F.Fab")
			(effects
				(font
					(size 0.7 0.7)
					(thickness 0.15)
				)
				(justify right top)
			)
		)
		(fp_text user "License: Apache-2.0"
			(at -0.802 6.9 90)
			(layer "F.Fab")
			(effects
				(font
					(size 0.7 0.7)
					(thickness 0.15)
				)
				(justify right top)
			)
		)
		(pad "1" smd roundrect
			(at -0.387 -1 180)
			(size 0.25 0.55)
			(layers "F.Cu" "F.Mask" "F.Paste")
			(roundrect_rratio 0.25)
			(net 132 "unconnected-(D14-Pad1)")
			(pintype "passive+no_connect")
		)
		(pad "2" smd roundrect
			(at -0.387 -0.5 180)
			(size 0.25 0.55)
			(layers "F.Cu" "F.Mask" "F.Paste")
			(roundrect_rratio 0.25)
			(net 184 "/OCuLink/~{WAKEC}")
			(pintype "passive")
		)
		(pad "3" smd roundrect
			(at -0.387 0 180)
			(size 0.4 0.55)
			(layers "F.Cu" "F.Mask" "F.Paste")
			(roundrect_rratio 0.25)
			(net 66 "GND")
			(pintype "power_in")
		)
		(pad "4" smd roundrect
			(at -0.387 0.498 180)
			(size 0.25 0.55)
			(layers "F.Cu" "F.Mask" "F.Paste")
			(roundrect_rratio 0.25)
			(net 170 "/OCuLink/PCIe_{REF0}_R.CK+")
			(pintype "passive")
		)
		(pad "5" smd roundrect
			(at -0.387 0.998 180)
			(size 0.25 0.55)
			(layers "F.Cu" "F.Mask" "F.Paste")
			(roundrect_rratio 0.25)
			(net 171 "/OCuLink/PCIe_{REF0}_R.CK-")
			(pintype "passive")
		)
		(pad "6" smd roundrect
			(at 0.385 0.998 180)
			(size 0.25 0.55)
			(layers "F.Cu" "F.Mask" "F.Paste")
			(roundrect_rratio 0.25)
			(net 171 "/OCuLink/PCIe_{REF0}_R.CK-")
			(pintype "passive")
		)
		(pad "7" smd roundrect
			(at 0.385 0.498 180)
			(size 0.25 0.55)
			(layers "F.Cu" "F.Mask" "F.Paste")
			(roundrect_rratio 0.25)
			(net 170 "/OCuLink/PCIe_{REF0}_R.CK+")
			(pintype "passive")
		)
		(pad "8" smd roundrect
			(at 0.385 0 180)
			(size 0.4 0.55)
			(layers "F.Cu" "F.Mask" "F.Paste")
			(roundrect_rratio 0.25)
			(net 66 "GND")
			(pintype "passive")
		)
		(pad "9" smd roundrect
			(at 0.385 -0.5 180)
			(size 0.25 0.55)
			(layers "F.Cu" "F.Mask" "F.Paste")
			(roundrect_rratio 0.25)
			(net 184 "/OCuLink/~{WAKEC}")
			(pintype "passive")
		)
		(pad "10" smd roundrect
			(at 0.385 -1 180)
			(size 0.25 0.55)
			(layers "F.Cu" "F.Mask" "F.Paste")
			(roundrect_rratio 0.25)
			(net 188 "unconnected-(D14-Pad1)_1")
			(pintype "passive+no_connect")
		)
	)
	(footprint "antmicro-footprints:C_0402_1005Metric"
		(layer "F.Cu")
		(at 127.1 134.4)
		(descr "Capacitor SMD 0402")
		(tags "capacitor SMD 0402")
		(property "Reference" "C1"
			(at 2.5 -0.4 180)
			(layer "F.SilkS")
			(effects
				(font
					(size 0.7 0.7)
					(thickness 0.15)
				)
				(justify left bottom)
			)
		)
		(property "Value" "C_100n_0402"
			(at -1.022927 2.155213 0)
			(layer "F.Fab")
			(effects
				(font
					(size 0.7 0.7)
					(thickness 0.15)
				)
				(justify left bottom)
			)
		)
		(property "Datasheet" "https://www.murata.com/products/productdetail?partno=GRM155R61H104KE14%23"
			(at 0 0 0)
			(layer "F.Fab")
			(hide yes)
			(effects
				(font
					(size 1.27 1.27)
					(thickness 0.15)
				)
			)
		)
		(property "Description" "SMD Multilayer Ceramic Capacitor, 0.1 µF, 50 V, 0402 [1005 Metric], ± 10%, X5R, GRM Series"
			(at 0 0 0)
			(layer "F.Fab")
			(hide yes)
			(effects
				(font
					(size 1.27 1.27)
					(thickness 0.15)
				)
			)
		)
		(property "MPN" "GRM155R61H104KE14D"
			(at 0 0 0)
			(unlocked yes)
			(layer "F.Fab")
			(hide yes)
			(effects
				(font
					(size 1 1)
					(thickness 0.15)
				)
			)
		)
		(property "Manufacturer" "Murata"
			(at 0 0 0)
			(unlocked yes)
			(layer "F.Fab")
			(hide yes)
			(effects
				(font
					(size 1 1)
					(thickness 0.15)
				)
			)
		)
		(property "License" "Apache-2.0"
			(at 0 0 0)
			(unlocked yes)
			(layer "F.Fab")
			(hide yes)
			(effects
				(font
					(size 1 1)
					(thickness 0.15)
				)
			)
		)
		(property "Author" "Antmicro"
			(at 0 0 0)
			(unlocked yes)
			(layer "F.Fab")
			(hide yes)
			(effects
				(font
					(size 1 1)
					(thickness 0.15)
				)
			)
		)
		(property "Val" "100n"
			(at 0 0 0)
			(unlocked yes)
			(layer "F.Fab")
			(hide yes)
			(effects
				(font
					(size 1 1)
					(thickness 0.15)
				)
			)
		)
		(property "Voltage" "50V"
			(at 0 0 0)
			(unlocked yes)
			(layer "F.Fab")
			(hide yes)
			(effects
				(font
					(size 1 1)
					(thickness 0.15)
				)
			)
		)
		(property "Dielectric" "X5R"
			(at 0 0 0)
			(unlocked yes)
			(layer "F.Fab")
			(hide yes)
			(effects
				(font
					(size 1 1)
					(thickness 0.15)
				)
			)
		)
		(sheetname "/Power/")
		(sheetfile "power.kicad_sch")
		(attr smd)
		(fp_rect
			(start -0.925 -0.47)
			(end 0.925 0.47)
			(stroke
				(width 0.05)
				(type default)
			)
			(fill no)
			(layer "F.CrtYd")
		)
		(fp_line
			(start -0.494 -0.25)
			(end 0.504 -0.25)
			(stroke
				(width 0.15)
				(type solid)
			)
			(layer "F.Fab")
		)
		(fp_line
			(start -0.494 0.248)
			(end -0.494 -0.25)
			(stroke
				(width 0.15)
				(type solid)
			)
			(layer "F.Fab")
		)
		(fp_line
			(start 0.504 -0.25)
			(end 0.504 0.248)
			(stroke
				(width 0.15)
				(type solid)
			)
			(layer "F.Fab")
		)
		(fp_line
			(start 0.504 0.248)
			(end -0.494 0.248)
			(stroke
				(width 0.15)
				(type solid)
			)
			(layer "F.Fab")
		)
		(fp_text user "${REFERENCE}"
			(at 0 0 0)
			(layer "F.Fab")
			(effects
				(font
					(size 0.7 0.7)
					(thickness 0.15)
				)
				(justify left bottom)
			)
		)
		(fp_text user "Author: Antmicro"
			(at -0.939 3.399 0)
			(layer "F.Fab")
			(effects
				(font
					(size 0.7 0.7)
					(thickness 0.15)
				)
				(justify left bottom)
			)
		)
		(fp_text user "License: Apache-2.0"
			(at -0.939 5.799 0)
			(layer "F.Fab")
			(effects
				(font
					(size 0.7 0.7)
					(thickness 0.15)
				)
				(justify left bottom)
			)
		)
		(pad "1" smd roundrect
			(at -0.48 0)
			(size 0.59 0.64)
			(layers "F.Cu" "F.Mask" "F.Paste")
			(roundrect_rratio 0.25)
			(net 85 "/Power/3V3_BST")
			(pintype "passive")
		)
		(pad "2" smd roundrect
			(at 0.48 0)
			(size 0.59 0.64)
			(layers "F.Cu" "F.Mask" "F.Paste")
			(roundrect_rratio 0.25)
			(net 86 "/Power/3V3_SW")
			(pintype "passive")
		)
	)
	(footprint "antmicro-footprints:C_0402_1005Metric"
		(layer "F.Cu")
		(at 146.562 54.001)
		(descr "Capacitor SMD 0402")
		(tags "capacitor SMD 0402")
		(property "Reference" "C40"
			(at -3.162 2.999 180)
			(layer "F.SilkS")
			(effects
				(font
					(size 0.7 0.7)
					(thickness 0.15)
				)
				(justify left bottom)
			)
		)
		(property "Value" "C_100n_0402"
			(at -1.022927 2.155213 0)
			(layer "F.Fab")
			(effects
				(font
					(size 0.7 0.7)
					(thickness 0.15)
				)
				(justify left bottom)
			)
		)
		(property "Datasheet" "https://www.murata.com/products/productdetail?partno=GRM155R61H104KE14%23"
			(at 0 0 0)
			(layer "F.Fab")
			(hide yes)
			(effects
				(font
					(size 1.27 1.27)
					(thickness 0.15)
				)
			)
		)
		(property "Description" "SMD Multilayer Ceramic Capacitor, 0.1 µF, 50 V, 0402 [1005 Metric], ± 10%, X5R, GRM Series"
			(at 0 0 0)
			(layer "F.Fab")
			(hide yes)
			(effects
				(font
					(size 1.27 1.27)
					(thickness 0.15)
				)
			)
		)
		(property "MPN" "GRM155R61H104KE14D"
			(at 0 0 0)
			(unlocked yes)
			(layer "F.Fab")
			(hide yes)
			(effects
				(font
					(size 1 1)
					(thickness 0.15)
				)
			)
		)
		(property "Manufacturer" "Murata"
			(at 0 0 0)
			(unlocked yes)
			(layer "F.Fab")
			(hide yes)
			(effects
				(font
					(size 1 1)
					(thickness 0.15)
				)
			)
		)
		(property "License" "Apache-2.0"
			(at 0 0 0)
			(unlocked yes)
			(layer "F.Fab")
			(hide yes)
			(effects
				(font
					(size 1 1)
					(thickness 0.15)
				)
			)
		)
		(property "Author" "Antmicro"
			(at 0 0 0)
			(unlocked yes)
			(layer "F.Fab")
			(hide yes)
			(effects
				(font
					(size 1 1)
					(thickness 0.15)
				)
			)
		)
		(property "Val" "100n"
			(at 0 0 0)
			(unlocked yes)
			(layer "F.Fab")
			(hide yes)
			(effects
				(font
					(size 1 1)
					(thickness 0.15)
				)
			)
		)
		(property "Voltage" "50V"
			(at 0 0 0)
			(unlocked yes)
			(layer "F.Fab")
			(hide yes)
			(effects
				(font
					(size 1 1)
					(thickness 0.15)
				)
			)
		)
		(property "Dielectric" "X5R"
			(at 0 0 0)
			(unlocked yes)
			(layer "F.Fab")
			(hide yes)
			(effects
				(font
					(size 1 1)
					(thickness 0.15)
				)
			)
		)
		(sheetname "/USB-PD/")
		(sheetfile "usb-pd.kicad_sch")
		(attr smd)
		(fp_rect
			(start -0.925 -0.47)
			(end 0.925 0.47)
			(stroke
				(width 0.05)
				(type default)
			)
			(fill no)
			(layer "F.CrtYd")
		)
		(fp_line
			(start -0.494 -0.25)
			(end 0.504 -0.25)
			(stroke
				(width 0.15)
				(type solid)
			)
			(layer "F.Fab")
		)
		(fp_line
			(start -0.494 0.248)
			(end -0.494 -0.25)
			(stroke
				(width 0.15)
				(type solid)
			)
			(layer "F.Fab")
		)
		(fp_line
			(start 0.504 -0.25)
			(end 0.504 0.248)
			(stroke
				(width 0.15)
				(type solid)
			)
			(layer "F.Fab")
		)
		(fp_line
			(start 0.504 0.248)
			(end -0.494 0.248)
			(stroke
				(width 0.15)
				(type solid)
			)
			(layer "F.Fab")
		)
		(fp_text user "License: Apache-2.0"
			(at -0.939 5.799 0)
			(layer "F.Fab")
			(effects
				(font
					(size 0.7 0.7)
					(thickness 0.15)
				)
				(justify left bottom)
			)
		)
		(fp_text user "Author: Antmicro"
			(at -0.939 3.399 0)
			(layer "F.Fab")
			(effects
				(font
					(size 0.7 0.7)
					(thickness 0.15)
				)
				(justify left bottom)
			)
		)
		(fp_text user "${REFERENCE}"
			(at 0 0 0)
			(layer "F.Fab")
			(effects
				(font
					(size 0.7 0.7)
					(thickness 0.15)
				)
				(justify left bottom)
			)
		)
		(pad "1" smd roundrect
			(at -0.48 0)
			(size 0.59 0.64)
			(layers "F.Cu" "F.Mask" "F.Paste")
			(roundrect_rratio 0.25)
			(net 66 "GND")
			(pintype "passive")
		)
		(pad "2" smd roundrect
			(at 0.48 0)
			(size 0.59 0.64)
			(layers "F.Cu" "F.Mask" "F.Paste")
			(roundrect_rratio 0.25)
			(net 117 "/USB-PD/VDDD_3V3")
			(pintype "passive")
		)
	)
	(footprint "antmicro-footprints:R_0402_1005Metric"
		(layer "F.Cu")
		(at 146 64 180)
		(descr "Resistor SMD 0402")
		(tags "resistor SMD 0402")
		(property "Reference" "R58"
			(at -1.2 -0.7 0)
			(layer "F.SilkS")
			(effects
				(font
					(size 0.7 0.7)
					(thickness 0.15)
				)
				(justify right top)
			)
		)
		(property "Value" "R_50R_0402"
			(at -1.011843 1.772046 0)
			(layer "F.Fab")
			(effects
				(font
					(size 0.7 0.7)
					(thickness 0.15)
				)
				(justify right top)
			)
		)
		(property "Datasheet" "https://www.bourns.com/docs/product-datasheets/cr.pdf"
			(at 0 0 0)
			(layer "F.Fab")
			(hide yes)
			(effects
				(font
					(size 1.27 1.27)
					(thickness 0.15)
				)
			)
		)
		(property "Description" "SMD Chip Resistor"
			(at 0 0 0)
			(layer "F.Fab")
			(hide yes)
			(effects
				(font
					(size 1.27 1.27)
					(thickness 0.15)
				)
			)
		)
		(property "MPN" "CR0402-FX-50R0GLF"
			(at 0 0 180)
			(unlocked yes)
			(layer "F.Fab")
			(hide yes)
			(effects
				(font
					(size 1 1)
					(thickness 0.15)
				)
			)
		)
		(property "Manufacturer" "Bourns"
			(at 0 0 180)
			(unlocked yes)
			(layer "F.Fab")
			(hide yes)
			(effects
				(font
					(size 1 1)
					(thickness 0.15)
				)
			)
		)
		(property "License" "Apache-2.0"
			(at 0 0 180)
			(unlocked yes)
			(layer "F.Fab")
			(hide yes)
			(effects
				(font
					(size 1 1)
					(thickness 0.15)
				)
			)
		)
		(property "Author" "Antmicro"
			(at 0 0 180)
			(unlocked yes)
			(layer "F.Fab")
			(hide yes)
			(effects
				(font
					(size 1 1)
					(thickness 0.15)
				)
			)
		)
		(property "Val" "50R"
			(at 0 0 180)
			(unlocked yes)
			(layer "F.Fab")
			(hide yes)
			(effects
				(font
					(size 1 1)
					(thickness 0.15)
				)
			)
		)
		(property "Tolerance" "1%"
			(at 0 0 180)
			(unlocked yes)
			(layer "F.Fab")
			(hide yes)
			(effects
				(font
					(size 1 1)
					(thickness 0.15)
				)
			)
		)
		(sheetname "/PCIe-clock-generator/")
		(sheetfile "pcie-clock-generator.kicad_sch")
		(attr smd exclude_from_bom dnp)
		(fp_poly
			(pts
				(xy -0.925 -0.47) (xy 0.925 -0.47) (xy 0.925 0.47) (xy -0.925 0.47)
			)
			(stroke
				(width 0.05)
				(type default)
			)
			(fill no)
			(layer "F.CrtYd")
		)
		(fp_poly
			(pts
				(xy -0.5 -0.25) (xy 0.5 -0.25) (xy 0.5 0.25) (xy -0.5 0.25)
			)
			(stroke
				(width 0.15)
				(type solid)
			)
			(fill no)
			(layer "F.Fab")
		)
		(fp_text user "License: Apache-2.0"
			(at -0.949999 5.169 0)
			(layer "F.Fab")
			(effects
				(font
					(size 0.7 0.7)
					(thickness 0.15)
				)
				(justify right top)
			)
		)
		(fp_text user "${REFERENCE}"
			(at -0.95 3.168 0)
			(layer "F.Fab")
			(effects
				(font
					(size 0.7 0.7)
					(thickness 0.15)
				)
				(justify right top)
			)
		)
		(fp_text user "Author: Antmicro"
			(at -0.95 4.169 0)
			(layer "F.Fab")
			(effects
				(font
					(size 0.7 0.7)
					(thickness 0.15)
				)
				(justify right top)
			)
		)
		(pad "1" smd roundrect
			(at -0.48 0 180)
			(size 0.59 0.64)
			(layers "F.Cu" "F.Mask" "F.Paste")
			(roundrect_rratio 0.25)
			(net 66 "GND")
			(pintype "passive")
		)
		(pad "2" smd roundrect
			(at 0.48 0 180)
			(size 0.59 0.64)
			(layers "F.Cu" "F.Mask" "F.Paste")
			(roundrect_rratio 0.25)
			(net 178 "/PCIe-clock-generator/PCIe_{REF1}_R.CK+")
			(pintype "passive")
		)
	)
	(footprint "antmicro-footprints:R_0402_1005Metric"
		(layer "F.Cu")
		(at 148.152 93.999999)
		(descr "Resistor SMD 0402")
		(tags "resistor SMD 0402")
		(property "Reference" "R40"
			(at 1.248 0.400001 180)
			(layer "F.SilkS")
			(effects
				(font
					(size 0.7 0.7)
					(thickness 0.15)
				)
				(justify left bottom)
			)
		)
		(property "Value" "R_140k_0.1%_0402"
			(at -1.011843 1.772046 0)
			(layer "F.Fab")
			(effects
				(font
					(size 0.7 0.7)
					(thickness 0.15)
				)
				(justify left bottom)
			)
		)
		(property "Datasheet" "https://www.vishay.com/docs/28758/tnpw_e3.pdf"
			(at 0 0 0)
			(layer "F.Fab")
			(hide yes)
			(effects
				(font
					(size 1.27 1.27)
					(thickness 0.15)
				)
			)
		)
		(property "Description" "SMD Chip Resistor, Ceramic, 140 kohm, ± 0.1%, 62.5 mW, 0402 [1005 Metric], Thin Film, Precision resistors"
			(at 0 0 0)
			(layer "F.Fab")
			(hide yes)
			(effects
				(font
					(size 1.27 1.27)
					(thickness 0.15)
				)
			)
		)
		(property "MPN" "RT0402BRD07140KL"
			(at 0 0 0)
			(unlocked yes)
			(layer "F.Fab")
			(hide yes)
			(effects
				(font
					(size 1 1)
					(thickness 0.15)
				)
			)
		)
		(property "Val" "140k"
			(at 0 0 0)
			(unlocked yes)
			(layer "F.Fab")
			(hide yes)
			(effects
				(font
					(size 1 1)
					(thickness 0.15)
				)
			)
		)
		(property "Manufacturer" "YAGEO"
			(at 0 0 0)
			(unlocked yes)
			(layer "F.Fab")
			(hide yes)
			(effects
				(font
					(size 1 1)
					(thickness 0.15)
				)
			)
		)
		(property "Tolerance" "0.1%"
			(at 0 0 0)
			(unlocked yes)
			(layer "F.Fab")
			(hide yes)
			(effects
				(font
					(size 1 1)
					(thickness 0.15)
				)
			)
		)
		(property "License" "Apache-2.0"
			(at 0 0 0)
			(unlocked yes)
			(layer "F.Fab")
			(hide yes)
			(effects
				(font
					(size 1 1)
					(thickness 0.15)
				)
			)
		)
		(property "Author" "Antmicro"
			(at 0 0 0)
			(unlocked yes)
			(layer "F.Fab")
			(hide yes)
			(effects
				(font
					(size 1 1)
					(thickness 0.15)
				)
			)
		)
		(sheetname "/USB-PD/")
		(sheetfile "usb-pd.kicad_sch")
		(attr smd)
		(fp_rect
			(start -0.925 -0.47)
			(end 0.925 0.47)
			(stroke
				(width 0.05)
				(type default)
			)
			(fill no)
			(layer "F.CrtYd")
		)
		(fp_rect
			(start -0.5 -0.25)
			(end 0.5 0.25)
			(stroke
				(width 0.15)
				(type solid)
			)
			(fill no)
			(layer "F.Fab")
		)
		(fp_text user "License: Apache-2.0"
			(at -0.949999 5.169 0)
			(layer "F.Fab")
			(effects
				(font
					(size 0.7 0.7)
					(thickness 0.15)
				)
				(justify left bottom)
			)
		)
		(fp_text user "${REFERENCE}"
			(at 0 0 0)
			(layer "F.Fab")
			(effects
				(font
					(size 0.7 0.7)
					(thickness 0.15)
				)
				(justify left bottom)
			)
		)
		(fp_text user "Author: Antmicro"
			(at -0.95 4.169 0)
			(layer "F.Fab")
			(effects
				(font
					(size 0.7 0.7)
					(thickness 0.15)
				)
				(justify left bottom)
			)
		)
		(pad "1" smd roundrect
			(at -0.48 0)
			(size 0.59 0.64)
			(layers "F.Cu" "F.Mask" "F.Paste")
			(roundrect_rratio 0.25)
			(net 159 "/USB-PD/12V_FB")
			(pintype "passive")
		)
		(pad "2" smd roundrect
			(at 0.48 0)
			(size 0.59 0.64)
			(layers "F.Cu" "F.Mask" "F.Paste")
			(roundrect_rratio 0.25)
			(net 187 "/USB-PD/12V_CONV")
			(pintype "passive")
		)
	)
	(footprint "antmicro-footprints:LED_0603_1608Metric_G"
		(layer "F.Cu")
		(at 151.5 162.25)
		(descr "LED SMD 0603 Green")
		(tags "LED SMD 0603 Green")
		(property "Reference" "D1"
			(at -0.75 1.58 0)
			(layer "F.SilkS")
			(effects
				(font
					(size 0.7 0.7)
					(thickness 0.15)
				)
				(justify left bottom)
			)
		)
		(property "Value" "LED_G_0603_LTST-C190GKT"
			(at -0.001 1.599 0)
			(layer "F.Fab")
			(effects
				(font
					(size 0.7 0.7)
					(thickness 0.15)
				)
				(justify left bottom)
			)
		)
		(property "Datasheet" "https://media.digikey.com/pdf/Data%20Sheets/Lite-On%20PDFs/LTST-C190GKT.pdf"
			(at 0 0 0)
			(layer "F.Fab")
			(hide yes)
			(effects
				(font
					(size 1.27 1.27)
					(thickness 0.15)
				)
			)
		)
		(property "Description" "LED, Green, SMD, 0603, 20 mA, 2.1 V, 569 nm"
			(at 0 0 0)
			(layer "F.Fab")
			(hide yes)
			(effects
				(font
					(size 1.27 1.27)
					(thickness 0.15)
				)
			)
		)
		(property "MPN" "LTST-C190GKT"
			(at 0 0 0)
			(unlocked yes)
			(layer "F.Fab")
			(hide yes)
			(effects
				(font
					(size 1 1)
					(thickness 0.15)
				)
			)
		)
		(property "Manufacturer" "Lite-On"
			(at 0 0 0)
			(unlocked yes)
			(layer "F.Fab")
			(hide yes)
			(effects
				(font
					(size 1 1)
					(thickness 0.15)
				)
			)
		)
		(property "Color" "Green"
			(at 0 0 0)
			(unlocked yes)
			(layer "F.Fab")
			(hide yes)
			(effects
				(font
					(size 1 1)
					(thickness 0.15)
				)
			)
		)
		(property "Author" "Antmicro"
			(at 0 0 0)
			(unlocked yes)
			(layer "F.Fab")
			(hide yes)
			(effects
				(font
					(size 1 1)
					(thickness 0.15)
				)
			)
		)
		(property "License" "Apache-2.0"
			(at 0 0 0)
			(unlocked yes)
			(layer "F.Fab")
			(hide yes)
			(effects
				(font
					(size 1 1)
					(thickness 0.15)
				)
			)
		)
		(sheetname "/Power/")
		(sheetfile "power.kicad_sch")
		(attr smd)
		(fp_line
			(start -1.18 -0.319)
			(end -1.18 0.321)
			(stroke
				(width 0.15)
				(type solid)
			)
			(layer "F.SilkS")
		)
		(fp_line
			(start -0.094672 0.001008)
			(end -0.24 0.001008)
			(stroke
				(width 0.1)
				(type solid)
			)
			(layer "F.SilkS")
		)
		(fp_line
			(start -0.094672 0.001008)
			(end 0.105328 -0.198992)
			(stroke
				(width 0.1)
				(type solid)
			)
			(layer "F.SilkS")
		)
		(fp_line
			(start -0.094672 0.201008)
			(end -0.094672 -0.198992)
			(stroke
				(width 0.1)
				(type solid)
			)
			(layer "F.SilkS")
		)
		(fp_line
			(start 0.105328 0.001008)
			(end 0.24 0.001)
			(stroke
				(width 0.1)
				(type solid)
			)
			(layer "F.SilkS")
		)
		(fp_line
			(start 0.105328 0.201008)
			(end -0.094672 0.001008)
			(stroke
				(width 0.1)
				(type solid)
			)
			(layer "F.SilkS")
		)
		(fp_line
			(start 0.105328 0.201008)
			(end 0.105328 -0.198992)
			(stroke
				(width 0.1)
				(type solid)
			)
			(layer "F.SilkS")
		)
		(fp_line
			(start 0.22 -0.35)
			(end -0.22 -0.35)
			(stroke
				(width 0.15)
				(type solid)
			)
			(layer "F.SilkS")
		)
		(fp_line
			(start 0.22 0.35)
			(end -0.22 0.35)
			(stroke
				(width 0.15)
				(type solid)
			)
			(layer "F.SilkS")
		)
		(fp_rect
			(start 1.25 0.65)
			(end -1.25 -0.65)
			(stroke
				(width 0.05)
				(type solid)
			)
			(fill no)
			(layer "F.CrtYd")
		)
		(fp_line
			(start -0.199 -0.202)
			(end -0.199 0.1)
			(stroke
				(width 0.15)
				(type solid)
			)
			(layer "F.Fab")
		)
		(fp_line
			(start -0.199 0)
			(end -0.597 0)
			(stroke
				(width 0.15)
				(type solid)
			)
			(layer "F.Fab")
		)
		(fp_line
			(start -0.199 0.2)
			(end -0.199 0.1)
			(stroke
				(width 0.15)
				(type solid)
			)
			(layer "F.Fab")
		)
		(fp_line
			(start -0.101 0)
			(end 0.201 0.2)
			(stroke
				(width 0.15)
				(type solid)
			)
			(layer "F.Fab")
		)
		(fp_line
			(start 0.201 -0.202)
			(end -0.101 0)
			(stroke
				(width 0.15)
				(type solid)
			)
			(layer "F.Fab")
		)
		(fp_line
			(start 0.201 0)
			(end 0.201 -0.202)
			(stroke
				(width 0.15)
				(type solid)
			)
			(layer "F.Fab")
		)
		(fp_line
			(start 0.201 0.2)
			(end 0.201 0)
			(stroke
				(width 0.15)
				(type solid)
			)
			(layer "F.Fab")
		)
		(fp_line
			(start 0.599 0)
			(end 0.201 0)
			(stroke
				(width 0.15)
				(type solid)
			)
			(layer "F.Fab")
		)
		(fp_rect
			(start 0.848 0.4)
			(end -0.85 -0.402)
			(stroke
				(width 0.15)
				(type solid)
			)
			(fill no)
			(layer "F.Fab")
		)
		(fp_text user "${REFERENCE}"
			(at 0 0 0)
			(layer "F.Fab")
			(effects
				(font
					(size 0.7 0.7)
					(thickness 0.15)
				)
				(justify left bottom)
			)
		)
		(fp_text user "Author: Antmicro"
			(at -1.4224 4.799 0)
			(layer "F.Fab")
			(effects
				(font
					(size 0.7 0.7)
					(thickness 0.15)
				)
				(justify left bottom)
			)
		)
		(fp_text user "License: Apache-2.0"
			(at -1.4224 3.599 0)
			(layer "F.Fab")
			(effects
				(font
					(size 0.7 0.7)
					(thickness 0.15)
				)
				(justify left bottom)
			)
		)
		(pad "1" smd roundrect
			(at -0.7 0 180)
			(size 0.8 1)
			(layers "F.Cu" "F.Mask" "F.Paste")
			(roundrect_rratio 0.2)
			(net 89 "Net-(D1-C)")
			(pinfunction "C")
			(pintype "passive")
		)
		(pad "2" smd roundrect
			(at 0.7 0 180)
			(size 0.8 1)
			(layers "F.Cu" "F.Mask" "F.Paste")
			(roundrect_rratio 0.2)
			(net 87 "+12V")
			(pinfunction "A")
			(pintype "passive")
		)
	)
	(footprint "antmicro-footprints:C_0402_1005Metric"
		(layer "F.Cu")
		(at 139.3 42.9 -90)
		(descr "Capacitor SMD 0402")
		(tags "capacitor SMD 0402")
		(property "Reference" "C9"
			(at 0.9 0.5 90)
			(layer "F.SilkS")
			(effects
				(font
					(size 0.7 0.7)
					(thickness 0.15)
				)
				(justify right top)
			)
		)
		(property "Value" "C_4u7_25V_0402"
			(at -1.022927 2.155213 90)
			(layer "F.Fab")
			(effects
				(font
					(size 0.7 0.7)
					(thickness 0.15)
				)
				(justify right top)
			)
		)
		(property "Datasheet" "https://www.murata.com/products/productdetail?partno=GRM155C61E475ME15%23"
			(at 0 0 90)
			(layer "F.Fab")
			(hide yes)
			(effects
				(font
					(size 1.27 1.27)
					(thickness 0.15)
				)
			)
		)
		(property "Description" "SMD Multilayer Ceramic Capacitor"
			(at 0 0 90)
			(layer "F.Fab")
			(hide yes)
			(effects
				(font
					(size 1.27 1.27)
					(thickness 0.15)
				)
			)
		)
		(property "MPN" "GRM155C61E475ME15J"
			(at 0 0 270)
			(unlocked yes)
			(layer "F.Fab")
			(hide yes)
			(effects
				(font
					(size 1 1)
					(thickness 0.15)
				)
			)
		)
		(property "Manufacturer" "Murata"
			(at 0 0 270)
			(unlocked yes)
			(layer "F.Fab")
			(hide yes)
			(effects
				(font
					(size 1 1)
					(thickness 0.15)
				)
			)
		)
		(property "License" "Apache-2.0"
			(at 0 0 270)
			(unlocked yes)
			(layer "F.Fab")
			(hide yes)
			(effects
				(font
					(size 1 1)
					(thickness 0.15)
				)
			)
		)
		(property "Author" "Antmicro"
			(at 0 0 270)
			(unlocked yes)
			(layer "F.Fab")
			(hide yes)
			(effects
				(font
					(size 1 1)
					(thickness 0.15)
				)
			)
		)
		(property "Val" "4u7"
			(at 0 0 270)
			(unlocked yes)
			(layer "F.Fab")
			(hide yes)
			(effects
				(font
					(size 1 1)
					(thickness 0.15)
				)
			)
		)
		(property "Voltage" "25V"
			(at 0 0 270)
			(unlocked yes)
			(layer "F.Fab")
			(hide yes)
			(effects
				(font
					(size 1 1)
					(thickness 0.15)
				)
			)
		)
		(property "Dielectric" "X5S"
			(at 0 0 270)
			(unlocked yes)
			(layer "F.Fab")
			(hide yes)
			(effects
				(font
					(size 1 1)
					(thickness 0.15)
				)
			)
		)
		(sheetname "/USB-PD/")
		(sheetfile "usb-pd.kicad_sch")
		(attr smd)
		(fp_rect
			(start -0.925 -0.47)
			(end 0.925 0.47)
			(stroke
				(width 0.05)
				(type default)
			)
			(fill no)
			(layer "F.CrtYd")
		)
		(fp_line
			(start -0.494 0.248)
			(end -0.494 -0.25)
			(stroke
				(width 0.15)
				(type solid)
			)
			(layer "F.Fab")
		)
		(fp_line
			(start 0.504 0.248)
			(end -0.494 0.248)
			(stroke
				(width 0.15)
				(type solid)
			)
			(layer "F.Fab")
		)
		(fp_line
			(start -0.494 -0.25)
			(end 0.504 -0.25)
			(stroke
				(width 0.15)
				(type solid)
			)
			(layer "F.Fab")
		)
		(fp_line
			(start 0.504 -0.25)
			(end 0.504 0.248)
			(stroke
				(width 0.15)
				(type solid)
			)
			(layer "F.Fab")
		)
		(fp_text user "License: Apache-2.0"
			(at -0.939 5.799 90)
			(layer "F.Fab")
			(effects
				(font
					(size 0.7 0.7)
					(thickness 0.15)
				)
				(justify right top)
			)
		)
		(fp_text user "${REFERENCE}"
			(at 0 0 90)
			(layer "F.Fab")
			(effects
				(font
					(size 0.7 0.7)
					(thickness 0.15)
				)
				(justify right top)
			)
		)
		(fp_text user "Author: Antmicro"
			(at -0.939 3.399 90)
			(layer "F.Fab")
			(effects
				(font
					(size 0.7 0.7)
					(thickness 0.15)
				)
				(justify right top)
			)
		)
		(pad "1" smd roundrect
			(at -0.48 0 270)
			(size 0.59 0.64)
			(layers "F.Cu" "F.Mask" "F.Paste")
			(roundrect_rratio 0.25)
			(net 66 "GND")
			(pintype "passive")
		)
		(pad "2" smd roundrect
			(at 0.48 0 270)
			(size 0.59 0.64)
			(layers "F.Cu" "F.Mask" "F.Paste")
			(roundrect_rratio 0.25)
			(net 113 "VBUS")
			(pintype "passive")
		)
	)
	(footprint "antmicro-footprints:R_0402_1005Metric"
		(layer "F.Cu")
		(at 148.151999 95)
		(descr "Resistor SMD 0402")
		(tags "resistor SMD 0402")
		(property "Reference" "R39"
			(at 1.248001 0.4 180)
			(layer "F.SilkS")
			(effects
				(font
					(size 0.7 0.7)
					(thickness 0.15)
				)
				(justify left bottom)
			)
		)
		(property "Value" "R_10k_0.1%_0402"
			(at -1.011843 1.772046 0)
			(layer "F.Fab")
			(effects
				(font
					(size 0.7 0.7)
					(thickness 0.15)
				)
				(justify left bottom)
			)
		)
		(property "Datasheet" "https://www.mouser.com/datasheet/2/54/CRT-1649066.pdf"
			(at 0 0 0)
			(layer "F.Fab")
			(hide yes)
			(effects
				(font
					(size 1.27 1.27)
					(thickness 0.15)
				)
			)
		)
		(property "Description" "SMD Chip Resistor, 10 kohm, ± 0.1%, 62.5 mW, 0402 [1005 Metric], Thin Film, Precision Resistors"
			(at 0 0 0)
			(layer "F.Fab")
			(hide yes)
			(effects
				(font
					(size 1.27 1.27)
					(thickness 0.15)
				)
			)
		)
		(property "MPN" "CRT0402-BY-1002GLF "
			(at 0 0 0)
			(unlocked yes)
			(layer "F.Fab")
			(hide yes)
			(effects
				(font
					(size 1 1)
					(thickness 0.15)
				)
			)
		)
		(property "Val" "10k"
			(at 0 0 0)
			(unlocked yes)
			(layer "F.Fab")
			(hide yes)
			(effects
				(font
					(size 1 1)
					(thickness 0.15)
				)
			)
		)
		(property "Manufacturer" "Bourns"
			(at 0 0 0)
			(unlocked yes)
			(layer "F.Fab")
			(hide yes)
			(effects
				(font
					(size 1 1)
					(thickness 0.15)
				)
			)
		)
		(property "Tolerance" "0.1%"
			(at 0 0 0)
			(unlocked yes)
			(layer "F.Fab")
			(hide yes)
			(effects
				(font
					(size 1 1)
					(thickness 0.15)
				)
			)
		)
		(property "License" "Apache-2.0"
			(at 0 0 0)
			(unlocked yes)
			(layer "F.Fab")
			(hide yes)
			(effects
				(font
					(size 1 1)
					(thickness 0.15)
				)
			)
		)
		(property "Author" "Antmicro"
			(at 0 0 0)
			(unlocked yes)
			(layer "F.Fab")
			(hide yes)
			(effects
				(font
					(size 1 1)
					(thickness 0.15)
				)
			)
		)
		(sheetname "/USB-PD/")
		(sheetfile "usb-pd.kicad_sch")
		(attr smd)
		(fp_rect
			(start -0.925 -0.47)
			(end 0.925 0.47)
			(stroke
				(width 0.05)
				(type default)
			)
			(fill no)
			(layer "F.CrtYd")
		)
		(fp_rect
			(start -0.5 -0.25)
			(end 0.5 0.25)
			(stroke
				(width 0.15)
				(type solid)
			)
			(fill no)
			(layer "F.Fab")
		)
		(fp_text user "License: Apache-2.0"
			(at -0.949999 5.169 0)
			(layer "F.Fab")
			(effects
				(font
					(size 0.7 0.7)
					(thickness 0.15)
				)
				(justify left bottom)
			)
		)
		(fp_text user "Author: Antmicro"
			(at -0.95 4.169 0)
			(layer "F.Fab")
			(effects
				(font
					(size 0.7 0.7)
					(thickness 0.15)
				)
				(justify left bottom)
			)
		)
		(fp_text user "${REFERENCE}"
			(at 0 0 0)
			(layer "F.Fab")
			(effects
				(font
					(size 0.7 0.7)
					(thickness 0.15)
				)
				(justify left bottom)
			)
		)
		(pad "1" smd roundrect
			(at -0.48 0)
			(size 0.59 0.64)
			(layers "F.Cu" "F.Mask" "F.Paste")
			(roundrect_rratio 0.25)
			(net 66 "GND")
			(pintype "passive")
		)
		(pad "2" smd roundrect
			(at 0.48 0)
			(size 0.59 0.64)
			(layers "F.Cu" "F.Mask" "F.Paste")
			(roundrect_rratio 0.25)
			(net 159 "/USB-PD/12V_FB")
			(pintype "passive")
		)
	)
	(footprint "antmicro-footprints:SIC47XED-T1-GE3"
		(layer "F.Cu")
		(at 143.5 91.749999 -90)
		(property "Reference" "U9"
			(at -4.149999 -2.7 180)
			(layer "F.SilkS")
			(effects
				(font
					(size 0.7 0.7)
					(thickness 0.15)
				)
				(justify right top)
			)
		)
		(property "Value" "SIC477ED-T1-GE3"
			(at 0 4.1 90)
			(layer "F.Fab")
			(effects
				(font
					(size 0.7 0.7)
					(thickness 0.15)
				)
				(justify right top)
			)
		)
		(property "Datasheet" "https://www.vishay.com/docs/77113/sic47x.pdf"
			(at 0 0 90)
			(layer "F.Fab")
			(hide yes)
			(effects
				(font
					(size 1.27 1.27)
					(thickness 0.15)
				)
			)
		)
		(property "Description" "DC/DC Synchronous Regulator, Adjustable, 4.5V to 55VIn, 0.8V to 50.6V/6AOut, 2MHz, PowerPAK MLP55-27"
			(at 0 0 90)
			(layer "F.Fab")
			(hide yes)
			(effects
				(font
					(size 1.27 1.27)
					(thickness 0.15)
				)
			)
		)
		(property "Manufacturer" "Vishay"
			(at 0 0 270)
			(unlocked yes)
			(layer "F.Fab")
			(hide yes)
			(effects
				(font
					(size 1 1)
					(thickness 0.15)
				)
			)
		)
		(property "MPN" "SIC477ED-T1-GE3"
			(at 0 0 270)
			(unlocked yes)
			(layer "F.Fab")
			(hide yes)
			(effects
				(font
					(size 1 1)
					(thickness 0.15)
				)
			)
		)
		(property "Author" "Antmicro"
			(at 0 0 270)
			(unlocked yes)
			(layer "F.Fab")
			(hide yes)
			(effects
				(font
					(size 1 1)
					(thickness 0.15)
				)
			)
		)
		(property "License" "Apache-2.0"
			(at 0 0 270)
			(unlocked yes)
			(layer "F.Fab")
			(hide yes)
			(effects
				(font
					(size 1 1)
					(thickness 0.15)
				)
			)
		)
		(sheetname "/USB-PD/")
		(sheetfile "usb-pd.kicad_sch")
		(attr smd)
		(fp_line
			(start -2.5 2.499)
			(end -2.5 2.148)
			(stroke
				(width 0.15)
				(type solid)
			)
			(layer "F.SilkS")
		)
		(fp_line
			(start -2.101 2.499)
			(end -2.5 2.499)
			(stroke
				(width 0.15)
				(type solid)
			)
			(layer "F.SilkS")
		)
		(fp_line
			(start 2.499 2.499)
			(end 2.1 2.499)
			(stroke
				(width 0.15)
				(type solid)
			)
			(layer "F.SilkS")
		)
		(fp_line
			(start 2.499 2.297)
			(end 2.499 2.499)
			(stroke
				(width 0.15)
				(type solid)
			)
			(layer "F.SilkS")
		)
		(fp_line
			(start -2.5 -2.15)
			(end -2.5 -2.5)
			(stroke
				(width 0.15)
				(type solid)
			)
			(layer "F.SilkS")
		)
		(fp_line
			(start -2.5 -2.5)
			(end -2.15 -2.5)
			(stroke
				(width 0.15)
				(type solid)
			)
			(layer "F.SilkS")
		)
		(fp_line
			(start 2.148 -2.5)
			(end 2.499 -2.5)
			(stroke
				(width 0.15)
				(type solid)
			)
			(layer "F.SilkS")
		)
		(fp_line
			(start 2.499 -2.5)
			(end 2.499 -2.15)
			(stroke
				(width 0.15)
				(type solid)
			)
			(layer "F.SilkS")
		)
		(fp_circle
			(center -2.9 -2.1)
			(end -2.849 -2.1)
			(stroke
				(width 0.15)
				(type solid)
			)
			(fill yes)
			(layer "F.SilkS")
		)
		(fp_poly
			(pts
				(xy -0.803 2.1) (xy -1.601 2.1) (xy -1.601 -0.203) (xy -0.803 -0.203)
			)
			(stroke
				(width 0.1)
				(type solid)
			)
			(fill yes)
			(layer "F.Paste")
		)
		(fp_poly
			(pts
				(xy 1.648 2.048) (xy -0.25 2.048) (xy -0.25 1.398) (xy 1.648 1.398)
			)
			(stroke
				(width 0.1)
				(type solid)
			)
			(fill yes)
			(layer "F.Paste")
		)
		(fp_poly
			(pts
				(xy 1.1 0.597) (xy -0.25 0.597) (xy -0.25 -0.25) (xy 1.1 -0.25)
			)
			(stroke
				(width 0.1)
				(type solid)
			)
			(fill yes)
			(layer "F.Paste")
		)
		(fp_poly
			(pts
				(xy -0.453 -0.75) (xy -1.601 -0.75) (xy -1.601 -1.651) (xy -0.453 -1.651)
			)
			(stroke
				(width 0.1)
				(type solid)
			)
			(fill yes)
			(layer "F.Paste")
		)
		(fp_poly
			(pts
				(xy 1.6 -0.75) (xy 0.45 -0.75) (xy 0.45 -1.651) (xy 1.6 -1.651)
			)
			(stroke
				(width 0.1)
				(type solid)
			)
			(fill yes)
			(layer "F.Paste")
		)
		(fp_line
			(start -1.9 3.2)
			(end 1.65 3.2)
			(stroke
				(width 0.05)
				(type solid)
			)
			(layer "F.CrtYd")
		)
		(fp_line
			(start 1.65 3.2)
			(end 1.65 2.75)
			(stroke
				(width 0.05)
				(type solid)
			)
			(layer "F.CrtYd")
		)
		(fp_line
			(start -2.75 2.75)
			(end -1.9 2.75)
			(stroke
				(width 0.05)
				(type solid)
			)
			(layer "F.CrtYd")
		)
		(fp_line
			(start -1.9 2.75)
			(end -1.9 3.2)
			(stroke
				(width 0.05)
				(type solid)
			)
			(layer "F.CrtYd")
		)
		(fp_line
			(start 1.65 2.75)
			(end 2.75 2.75)
			(stroke
				(width 0.05)
				(type solid)
			)
			(layer "F.CrtYd")
		)
		(fp_line
			(start 2.75 2.75)
			(end 2.75 2.3)
			(stroke
				(width 0.05)
				(type solid)
			)
			(layer "F.CrtYd")
		)
		(fp_line
			(start 2.75 2.3)
			(end 3.2 2.3)
			(stroke
				(width 0.05)
				(type solid)
			)
			(layer "F.CrtYd")
		)
		(fp_line
			(start 3.2 2.3)
			(end 3.2 -2.15)
			(stroke
				(width 0.05)
				(type solid)
			)
			(layer "F.CrtYd")
		)
		(fp_line
			(start -3.2 2.15)
			(end -2.75 2.15)
			(stroke
				(width 0.05)
				(type solid)
			)
			(layer "F.CrtYd")
		)
		(fp_line
			(start -2.75 2.15)
			(end -2.75 2.75)
			(stroke
				(width 0.05)
				(type solid)
			)
			(layer "F.CrtYd")
		)
		(fp_line
			(start -3.2 -2.1)
			(end -3.2 2.15)
			(stroke
				(width 0.05)
				(type solid)
			)
			(layer "F.CrtYd")
		)
		(fp_line
			(start -2.75 -2.1)
			(end -3.2 -2.1)
			(stroke
				(width 0.05)
				(type solid)
			)
			(layer "F.CrtYd")
		)
		(fp_line
			(start 2.75 -2.15)
			(end 2.75 -2.75)
			(stroke
				(width 0.05)
				(type solid)
			)
			(layer "F.CrtYd")
		)
		(fp_line
			(start 3.2 -2.15)
			(end 2.75 -2.15)
			(stroke
				(width 0.05)
				(type solid)
			)
			(layer "F.CrtYd")
		)
		(fp_line
			(start -2.75 -2.75)
			(end -2.75 -2.1)
			(stroke
				(width 0.05)
				(type solid)
			)
			(layer "F.CrtYd")
		)
		(fp_line
			(start -2.15 -2.75)
			(end -2.75 -2.75)
			(stroke
				(width 0.05)
				(type solid)
			)
			(layer "F.CrtYd")
		)
		(fp_line
			(start 2.15 -2.75)
			(end 2.15 -3.2)
			(stroke
				(width 0.05)
				(type solid)
			)
			(layer "F.CrtYd")
		)
		(fp_line
			(start 2.75 -2.75)
			(end 2.15 -2.75)
			(stroke
				(width 0.05)
				(type solid)
			)
			(layer "F.CrtYd")
		)
		(fp_line
			(start -2.15 -3.2)
			(end -2.15 -2.75)
			(stroke
				(width 0.05)
				(type solid)
			)
			(layer "F.CrtYd")
		)
		(fp_line
			(start 2.15 -3.2)
			(end -2.15 -3.2)
			(stroke
				(width 0.05)
				(type solid)
			)
			(layer "F.CrtYd")
		)
		(fp_line
			(start -2.5 -2.302)
			(end -2.302 -2.5)
			(stroke
				(width 0.15)
				(type solid)
			)
			(layer "F.Fab")
		)
		(fp_rect
			(start 2.499 2.499)
			(end -2.5 -2.5)
			(stroke
				(width 0.15)
				(type solid)
			)
			(fill no)
			(layer "F.Fab")
		)
		(fp_text user "${REFERENCE}"
			(at 0 0 90)
			(layer "F.Fab")
			(effects
				(font
					(size 0.7 0.7)
					(thickness 0.15)
				)
				(justify right top)
			)
		)
		(fp_text user "Author: Antmicro"
			(at -4.851 8.338999 90)
			(layer "F.Fab")
			(effects
				(font
					(size 0.7 0.7)
					(thickness 0.15)
				)
				(justify right top)
			)
		)
		(fp_text user "License: Apache-2.0"
			(at -4.851 5.94 90)
			(layer "F.Fab")
			(effects
				(font
					(size 0.7 0.7)
					(thickness 0.15)
				)
				(justify right top)
			)
		)
		(pad "1" smd rect
			(at -2.525 -1.7 270)
			(size 0.95 0.35)
			(layers "F.Cu" "F.Mask" "F.Paste")
			(net 115 "/USB-PD/VCC")
			(pinfunction "V_{CIN}")
			(pintype "input")
		)
		(pad "2" smd rect
			(at -2.525 -1.051 270)
			(size 0.95 0.35)
			(layers "F.Cu" "F.Mask" "F.Paste")
			(net 158 "/USB-PD/12V_PG")
			(pinfunction "P_{GOOD}")
			(pintype "output")
		)
		(pad "3" smd rect
			(at -2.525 -0.403 270)
			(size 0.95 0.35)
			(layers "F.Cu" "F.Mask" "F.Paste")
			(net 156 "/USB-PD/12V_EN")
			(pinfunction "EN")
			(pintype "input")
		)
		(pad "4" smd rect
			(at -2.525 0.247 270)
			(size 0.95 0.35)
			(layers "F.Cu" "F.Mask" "F.Paste")
			(net 122 "/USB-PD/12V_BOOT")
			(pinfunction "BOOT")
			(pintype "input")
		)
		(pad "5" smd rect
			(at -2.525 1.249 270)
			(size 0.95 0.35)
			(layers "F.Cu" "F.Mask" "F.Paste")
			(net 120 "Net-(C27-Pad2)")
			(pinfunction "PHASE")
			(pintype "bidirectional")
		)
		(pad "6" smd rect
			(at -2.525 1.749 270)
			(size 0.95 0.35)
			(layers "F.Cu" "F.Mask" "F.Paste")
			(net 120 "Net-(C27-Pad2)")
			(pinfunction "PHASE")
			(pintype "passive")
		)
		(pad "7" smd rect
			(at -1.52 2.523 270)
			(size 0.35 0.95)
			(layers "F.Cu" "F.Mask" "F.Paste")
			(net 115 "/USB-PD/VCC")
			(pinfunction "V_{IN}")
			(pintype "input")
		)
		(pad "7" smd rect
			(at -1.2 0.997 270)
			(size 1.1 2.7)
			(layers "F.Cu" "F.Mask")
			(net 115 "/USB-PD/VCC")
			(pinfunction "V_{IN}")
			(pintype "input")
		)
		(pad "8" smd rect
			(at -0.87 2.523 270)
			(size 0.35 0.95)
			(layers "F.Cu" "F.Mask" "F.Paste")
			(net 115 "/USB-PD/VCC")
			(pinfunction "V_{IN}")
			(pintype "passive")
		)
		(pad "9" smd rect
			(at 0.26 2.523 270)
			(size 0.35 0.95)
			(layers "F.Cu" "F.Mask" "F.Paste")
			(net 66 "GND")
			(pinfunction "PGND")
			(pintype "power_in")
		)
		(pad "9" smd rect
			(at 0.409 0.997 270)
			(size 1.52 2.7)
			(layers "F.Cu" "F.Mask")
			(net 66 "GND")
			(pinfunction "PGND")
			(pintype "power_in")
		)
		(pad "9" smd rect
			(at 0.699 1.485 270)
			(size 2.1 1.73)
			(layers "F.Cu" "F.Mask")
			(net 66 "GND")
			(pinfunction "PGND")
			(pintype "power_in")
		)
		(pad "10" smd rect
			(at 0.757 2.523 270)
			(size 0.35 0.95)
			(layers "F.Cu" "F.Mask" "F.Paste")
			(net 66 "GND")
			(pinfunction "PGND")
			(pintype "passive")
		)
		(pad "11" smd rect
			(at 1.259 2.523 270)
			(size 0.35 0.95)
			(layers "F.Cu" "F.Mask" "F.Paste")
			(net 66 "GND")
			(pinfunction "PGND")
			(pintype "passive")
		)
		(pad "12" smd rect
			(at 2.523 1.898 270)
			(size 0.95 0.35)
			(layers "F.Cu" "F.Mask" "F.Paste")
			(net 143 "/USB-PD/12V_SW")
			(pinfunction "SW")
			(pintype "bidirectional")
		)
		(pad "13" smd rect
			(at 2.523 1.398 270)
			(size 0.95 0.35)
			(layers "F.Cu" "F.Mask" "F.Paste")
			(net 143 "/USB-PD/12V_SW")
			(pinfunction "SW")
			(pintype "passive")
		)
		(pad "14" smd rect
			(at 2.2 1.398 270)
			(size 0.3 1.35)
			(layers "F.Cu" "F.Mask" "F.Paste")
			(net 143 "/USB-PD/12V_SW")
			(pinfunction "SW")
			(pintype "passive")
		)
		(pad "14" smd rect
			(at 2.523 0.9 270)
			(size 0.95 0.35)
			(layers "F.Cu" "F.Mask" "F.Paste")
			(net 143 "/USB-PD/12V_SW")
			(pinfunction "SW")
			(pintype "passive")
		)
		(pad "15" smd rect
			(at 2.523 0.247 270)
			(size 0.95 0.35)
			(layers "F.Cu" "F.Mask" "F.Paste")
			(net 150 "unconnected-(U9-GL-Pad15)")
			(pinfunction "GL")
			(pintype "input+no_connect")
		)
		(pad "16" smd rect
			(at 2.523 -0.25 270)
			(size 0.95 0.35)
			(layers "F.Cu" "F.Mask" "F.Paste")
			(net 123 "/USB-PD/12V_VDRV")
			(pinfunction "V_{DRV}")
			(pintype "passive")
		)
		(pad "17" smd rect
			(at 2.523 -0.75 270)
			(size 0.95 0.35)
			(layers "F.Cu" "F.Mask" "F.Paste")
			(net 66 "GND")
			(pinfunction "PGND")
			(pintype "passive")
		)
		(pad "18" smd rect
			(at 2.523 -1.25 270)
			(size 0.95 0.35)
			(layers "F.Cu" "F.Mask" "F.Paste")
			(net 149 "unconnected-(U9-NC-Pad18)")
			(pinfunction "NC")
			(pintype "passive+no_connect")
		)
		(pad "19" smd rect
			(at 2.523 -1.75 270)
			(size 0.95 0.35)
			(layers "F.Cu" "F.Mask" "F.Paste")
			(net 125 "/USB-PD/12V_SS")
			(pinfunction "SS")
			(pintype "passive")
		)
		(pad "20" smd rect
			(at 1.749 -2.525 270)
			(size 0.35 0.95)
			(layers "F.Cu" "F.Mask" "F.Paste")
			(net 187 "/USB-PD/12V_CONV")
			(pinfunction "V_{SNS}")
			(pintype "power_in")
		)
		(pad "21" smd rect
			(at 1.249 -2.525 270)
			(size 0.35 0.95)
			(layers "F.Cu" "F.Mask" "F.Paste")
			(net 160 "unconnected-(U9-NC-Pad21)")
			(pinfunction "NC")
			(pintype "passive+no_connect")
		)
		(pad "22" smd rect
			(at 0.747 -2.525 270)
			(size 0.35 0.95)
			(layers "F.Cu" "F.Mask" "F.Paste")
			(net 159 "/USB-PD/12V_FB")
			(pinfunction "V_{FB}")
			(pintype "input")
		)
		(pad "23" smd rect
			(at 0.247 -2.525 270)
			(size 0.35 0.95)
			(layers "F.Cu" "F.Mask" "F.Paste")
			(net 66 "GND")
			(pinfunction "AGND")
			(pintype "power_in")
		)
		(pad "24" smd rect
			(at -0.25 -2.525 270)
			(size 0.35 0.95)
			(layers "F.Cu" "F.Mask" "F.Paste")
			(net 157 "/USB-PD/12V_FSW")
			(pinfunction "f_{SW}")
			(pintype "passive")
		)
		(pad "25" smd rect
			(at -0.75 -2.525 270)
			(size 0.35 0.95)
			(layers "F.Cu" "F.Mask" "F.Paste")
			(net 155 "/USB-PD/12V_ILIM")
			(pinfunction "I_{LIMIT}")
			(pintype "passive")
		)
		(pad "26" smd rect
			(at -1.25 -2.525 270)
			(size 0.35 0.95)
			(layers "F.Cu" "F.Mask" "F.Paste")
			(net 121 "/USB-PD/12V_VDD")
			(pinfunction "V_{DD}")
			(pintype "power_out")
		)
		(pad "27" smd rect
			(at -1.75 -2.525 270)
			(size 0.35 0.95)
			(layers "F.Cu" "F.Mask" "F.Paste")
			(net 153 "/USB-PD/12V_MODE")
			(pinfunction "MODE")
			(pintype "bidirectional")
		)
		(pad "28" smd rect
			(at 0 -1.2 270)
			(size 3.4 1.1)
			(layers "F.Cu" "F.Mask")
			(net 66 "GND")
			(pinfunction "AGND")
			(pintype "passive")
		)
	)
	(footprint "antmicro-footprints:AMPHENOL_10146070-113Y0LF"
		(locked yes)
		(layer "F.Cu")
		(at 111.674 79.6 90)
		(property "Reference" "J2"
			(at 41.1 5.926 90)
			(layer "F.SilkS")
			(effects
				(font
					(size 0.7 0.7)
					(thickness 0.15)
				)
				(justify left bottom)
			)
		)
		(property "Value" "PCIe_x16_10146070-113Y0LF-vertical"
			(at -28.471 6.61 90)
			(layer "F.Fab")
			(effects
				(font
					(size 0.7 0.7)
					(thickness 0.15)
				)
				(justify left bottom)
			)
		)
		(property "Datasheet" "https://www.farnell.com/datasheets/3212936.pdf"
			(at 0 0 90)
			(layer "F.Fab")
			(hide yes)
			(effects
				(font
					(size 1.27 1.27)
					(thickness 0.15)
				)
			)
		)
		(property "Description" "164 Position Female Connector PCI Express™ Gold 0.039\" (1.00mm) Black"
			(at 0 0 90)
			(layer "F.Fab")
			(hide yes)
			(effects
				(font
					(size 1.27 1.27)
					(thickness 0.15)
				)
			)
		)
		(property "PARTREV" "E"
			(at 0 0 90)
			(unlocked yes)
			(layer "F.Fab")
			(hide yes)
			(effects
				(font
					(size 1 1)
					(thickness 0.15)
				)
			)
		)
		(property "STANDARD" "Manufacturer Recommendations"
			(at 0 0 90)
			(unlocked yes)
			(layer "F.Fab")
			(hide yes)
			(effects
				(font
					(size 1 1)
					(thickness 0.15)
				)
			)
		)
		(property "MAXIMUM_PACKAGE_HEIGHT" "11.25mm"
			(at 0 0 90)
			(unlocked yes)
			(layer "F.Fab")
			(hide yes)
			(effects
				(font
					(size 1 1)
					(thickness 0.15)
				)
			)
		)
		(property "Manufacturer" "Amphenol"
			(at 0 0 90)
			(unlocked yes)
			(layer "F.Fab")
			(hide yes)
			(effects
				(font
					(size 1 1)
					(thickness 0.15)
				)
			)
		)
		(property "Author" "Antmicro"
			(at 0 0 90)
			(unlocked yes)
			(layer "F.Fab")
			(hide yes)
			(effects
				(font
					(size 1 1)
					(thickness 0.15)
				)
			)
		)
		(property "License" "Apache-2.0"
			(at 0 0 90)
			(unlocked yes)
			(layer "F.Fab")
			(hide yes)
			(effects
				(font
					(size 1 1)
					(thickness 0.15)
				)
			)
		)
		(property "MPN" "10146070-113Y0LF"
			(at 0 0 90)
			(unlocked yes)
			(layer "F.Fab")
			(hide yes)
			(effects
				(font
					(size 1 1)
					(thickness 0.15)
				)
			)
		)
		(sheetname "/PCIe-connector/")
		(sheetfile "pcie-connector.kicad_sch")
		(attr smd)
		(fp_line
			(start 44.648 -4.202)
			(end 44.648 -3.321)
			(stroke
				(width 0.15)
				(type solid)
			)
			(layer "F.SilkS")
		)
		(fp_line
			(start 42.084 -4.202)
			(end 44.648 -4.202)
			(stroke
				(width 0.15)
				(type solid)
			)
			(layer "F.SilkS")
		)
		(fp_line
			(start -44.351 -4.202)
			(end -42.085 -4.202)
			(stroke
				(width 0.15)
				(type solid)
			)
			(layer "F.SilkS")
		)
		(fp_line
			(start -44.351 -3.321)
			(end -44.351 -4.202)
			(stroke
				(width 0.15)
				(type solid)
			)
			(layer "F.SilkS")
		)
		(fp_line
			(start 44.648 4.599)
			(end 44.648 2.318)
			(stroke
				(width 0.15)
				(type solid)
			)
			(layer "F.SilkS")
		)
		(fp_line
			(start 44.648 4.599)
			(end -44.351 4.599)
			(stroke
				(width 0.15)
				(type solid)
			)
			(layer "F.SilkS")
		)
		(fp_line
			(start -44.351 4.599)
			(end -44.351 2.318)
			(stroke
				(width 0.15)
				(type solid)
			)
			(layer "F.SilkS")
		)
		(fp_circle
			(center -42.08 -4.68)
			(end -42.031 -4.68)
			(stroke
				(width 0.15)
				(type solid)
			)
			(fill yes)
			(layer "F.SilkS")
		)
		(fp_poly
			(pts
				(xy 44.838 -2.661) (xy 45.658 -2.661) (xy 45.658 -0.841) (xy 44.838 -0.841)
			)
			(stroke
				(width 0.01)
				(type solid)
			)
			(fill yes)
			(layer "F.Paste")
		)
		(fp_poly
			(pts
				(xy 43.588 -2.661) (xy 44.408 -2.661) (xy 44.408 -1.091) (xy 43.588 -1.091)
			)
			(stroke
				(width 0.01)
				(type solid)
			)
			(fill yes)
			(layer "F.Paste")
		)
		(fp_poly
			(pts
				(xy -44.162 -2.661) (xy -43.342 -2.661) (xy -43.342 -0.841) (xy -44.162 -0.841)
			)
			(stroke
				(width 0.01)
				(type solid)
			)
			(fill yes)
			(layer "F.Paste")
		)
		(fp_poly
			(pts
				(xy -45.662 -2.661) (xy -44.842 -2.661) (xy -44.842 -0.841) (xy -45.662 -0.841)
			)
			(stroke
				(width 0.01)
				(type solid)
			)
			(fill yes)
			(layer "F.Paste")
		)
		(fp_poly
			(pts
				(xy 44.838 -0.16) (xy 45.658 -0.16) (xy 45.658 1.66) (xy 44.838 1.66)
			)
			(stroke
				(width 0.01)
				(type solid)
			)
			(fill yes)
			(layer "F.Paste")
		)
		(fp_poly
			(pts
				(xy -44.162 -0.16) (xy -43.342 -0.16) (xy -43.342 1.66) (xy -44.162 1.66)
			)
			(stroke
				(width 0.01)
				(type solid)
			)
			(fill yes)
			(layer "F.Paste")
		)
		(fp_poly
			(pts
				(xy -45.662 -0.16) (xy -44.842 -0.16) (xy -44.842 1.66) (xy -45.662 1.66)
			)
			(stroke
				(width 0.01)
				(type solid)
			)
			(fill yes)
			(layer "F.Paste")
		)
		(fp_poly
			(pts
				(xy 43.588 0.088) (xy 44.408 0.088) (xy 44.408 1.66) (xy 43.588 1.66)
			)
			(stroke
				(width 0.01)
				(type solid)
			)
			(fill yes)
			(layer "F.Paste")
		)
		(fp_rect
			(start -46.4 -5.2)
			(end 46.6 5.2)
			(stroke
				(width 0.05)
				(type solid)
			)
			(fill no)
			(layer "F.CrtYd")
		)
		(fp_line
			(start 44.648 -4.202)
			(end 44.648 4.599)
			(stroke
				(width 0.15)
				(type solid)
			)
			(layer "F.Fab")
		)
		(fp_line
			(start -43.15 -4.15)
			(end 44.648 -4.202)
			(stroke
				(width 0.15)
				(type solid)
			)
			(layer "F.Fab")
		)
		(fp_line
			(start -43.15 -4.15)
			(end -44.35 -3)
			(stroke
				(width 0.15)
				(type solid)
			)
			(layer "F.Fab")
		)
		(fp_line
			(start 44.648 4.599)
			(end -44.351 4.599)
			(stroke
				(width 0.15)
				(type solid)
			)
			(layer "F.Fab")
		)
		(fp_line
			(start -44.351 4.599)
			(end -44.35 -3)
			(stroke
				(width 0.15)
				(type solid)
			)
			(layer "F.Fab")
		)
		(fp_text user "Author: Antmicro"
			(at -46.501 8.61 90)
			(layer "F.Fab")
			(effects
				(font
					(size 0.7 0.7)
					(thickness 0.15)
				)
				(justify left bottom)
			)
		)
		(fp_text user "License: Apache-2.0"
			(at -46.501 9.81 90)
			(layer "F.Fab")
			(effects
				(font
					(size 0.7 0.7)
					(thickness 0.15)
				)
				(justify left bottom)
			)
		)
		(fp_text user "${REFERENCE}"
			(at 0.049 -0.6255 90)
			(layer "F.Fab")
			(effects
				(font
					(size 0.7 0.7)
					(thickness 0.15)
				)
				(justify left bottom)
			)
		)
		(pad "" np_thru_hole circle
			(at -29.851 -0.5 90)
			(size 1.25 1.25)
			(drill 1.25)
			(layers "*.Cu" "*.Mask")
		)
		(pad "" np_thru_hole circle
			(at 43.298 -0.5 90)
			(size 1.25 1.25)
			(drill 1.25)
			(layers "*.Cu" "*.Mask")
		)
		(pad "A1" smd rect
			(at -41.5 -4.1 90)
			(size 0.53 2)
			(layers "F.Cu" "F.Mask" "F.Paste")
			(net 55 "unconnected-(J2-PadA1)")
			(pinfunction "A1")
			(pintype "passive+no_connect")
		)
		(pad "A2" smd rect
			(at -40.5 -4.1 90)
			(size 0.53 2)
			(layers "F.Cu" "F.Mask" "F.Paste")
			(net 87 "+12V")
			(pinfunction "A2")
			(pintype "passive")
		)
		(pad "A3" smd rect
			(at -39.5 -4.1 90)
			(size 0.53 2)
			(layers "F.Cu" "F.Mask" "F.Paste")
			(net 87 "+12V")
			(pinfunction "A3")
			(pintype "passive")
		)
		(pad "A4" smd rect
			(at -38.5 -4.1 90)
			(size 0.53 2)
			(layers "F.Cu" "F.Mask" "F.Paste")
			(net 66 "GND")
			(pinfunction "A4")
			(pintype "passive")
		)
		(pad "A5" smd rect
			(at -37.5 -4.1 90)
			(size 0.53 2)
			(layers "F.Cu" "F.Mask" "F.Paste")
			(net 24 "unconnected-(J2-PadA5)")
			(pinfunction "A5")
			(pintype "passive+no_connect")
		)
		(pad "A6" smd rect
			(at -36.5 -4.1 90)
			(size 0.53 2)
			(layers "F.Cu" "F.Mask" "F.Paste")
			(net 19 "unconnected-(J2-PadA6)")
			(pinfunction "A6")
			(pintype "passive+no_connect")
		)
		(pad "A7" smd rect
			(at -35.5 -4.1 90)
			(size 0.53 2)
			(layers "F.Cu" "F.Mask" "F.Paste")
			(net 57 "unconnected-(J2-PadA7)")
			(pinfunction "A7")
			(pintype "passive+no_connect")
		)
		(pad "A8" smd rect
			(at -34.5 -4.1 90)
			(size 0.53 2)
			(layers "F.Cu" "F.Mask" "F.Paste")
			(net 21 "unconnected-(J2-PadA8)")
			(pinfunction "A8")
			(pintype "passive+no_connect")
		)
		(pad "A9" smd rect
			(at -33.5 -4.1 90)
			(size 0.53 2)
			(layers "F.Cu" "F.Mask" "F.Paste")
			(net 134 "+3V3")
			(pinfunction "A9")
			(pintype "passive")
		)
		(pad "A10" smd rect
			(at -32.5 -4.1 90)
			(size 0.53 2)
			(layers "F.Cu" "F.Mask" "F.Paste")
			(net 134 "+3V3")
			(pinfunction "A10")
			(pintype "passive")
		)
		(pad "A11" smd rect
			(at -31.5 -4.1 90)
			(size 0.53 2)
			(layers "F.Cu" "F.Mask" "F.Paste")
			(net 172 "/Power/~{PERST}")
			(pinfunction "A11")
			(pintype "passive")
		)
		(pad "A12" smd rect
			(at -28.5 -4.1 90)
			(size 0.53 2)
			(layers "F.Cu" "F.Mask" "F.Paste")
			(net 66 "GND")
			(pinfunction "A12")
			(pintype "passive")
		)
		(pad "A13" smd rect
			(at -27.5 -4.1 90)
			(size 0.53 2)
			(layers "F.Cu" "F.Mask" "F.Paste")
			(net 96 "/OCuLink/PCIe_{REF0}.CK+")
			(pinfunction "A13")
			(pintype "passive")
		)
		(pad "A14" smd rect
			(at -26.5 -4.1 90)
			(size 0.53 2)
			(layers "F.Cu" "F.Mask" "F.Paste")
			(net 97 "/OCuLink/PCIe_{REF0}.CK-")
			(pinfunction "A14")
			(pintype "passive")
		)
		(pad "A15" smd rect
			(at -25.5 -4.1 90)
			(size 0.53 2)
			(layers "F.Cu" "F.Mask" "F.Paste")
			(net 66 "GND")
			(pinfunction "A15")
			(pintype "passive")
		)
		(pad "A16" smd rect
			(at -24.5 -4.1 90)
			(size 0.53 2)
			(layers "F.Cu" "F.Mask" "F.Paste")
			(net 78 "/OCuLink/PCIe_{x4}.RX0+")
			(pinfunction "A16")
			(pintype "passive")
		)
		(pad "A17" smd rect
			(at -23.5 -4.1 90)
			(size 0.53 2)
			(layers "F.Cu" "F.Mask" "F.Paste")
			(net 73 "/OCuLink/PCIe_{x4}.RX0-")
			(pinfunction "A17")
			(pintype "passive")
		)
		(pad "A18" smd rect
			(at -22.5 -4.1 90)
			(size 0.53 2)
			(layers "F.Cu" "F.Mask" "F.Paste")
			(net 66 "GND")
			(pinfunction "A18")
			(pintype "passive")
		)
		(pad "A19" smd rect
			(at -21.5 -4.1 90)
			(size 0.53 2)
			(layers "F.Cu" "F.Mask" "F.Paste")
			(net 36 "unconnected-(J2-PadA19)")
			(pinfunction "A19")
			(pintype "passive+no_connect")
		)
		(pad "A20" smd rect
			(at -20.5 -4.1 90)
			(size 0.53 2)
			(layers "F.Cu" "F.Mask" "F.Paste")
			(net 66 "GND")
			(pinfunction "A20")
			(pintype "passive")
		)
		(pad "A21" smd rect
			(at -19.5 -4.1 90)
			(size 0.53 2)
			(layers "F.Cu" "F.Mask" "F.Paste")
			(net 75 "/OCuLink/PCIe_{x4}.RX1+")
			(pinfunction "A21")
			(pintype "passive")
		)
		(pad "A22" smd rect
			(at -18.5 -4.1 90)
			(size 0.53 2)
			(layers "F.Cu" "F.Mask" "F.Paste")
			(net 71 "/OCuLink/PCIe_{x4}.RX1-")
			(pinfunction "A22")
			(pintype "passive")
		)
		(pad "A23" smd rect
			(at -17.5 -4.1 90)
			(size 0.53 2)
			(layers "F.Cu" "F.Mask" "F.Paste")
			(net 66 "GND")
			(pinfunction "A23")
			(pintype "passive")
		)
		(pad "A24" smd rect
			(at -16.5 -4.1 90)
			(size 0.53 2)
			(layers "F.Cu" "F.Mask" "F.Paste")
			(net 66 "GND")
			(pinfunction "A24")
			(pintype "passive")
		)
		(pad "A25" smd rect
			(at -15.501 -4.1 90)
			(size 0.53 2)
			(layers "F.Cu" "F.Mask" "F.Paste")
			(net 81 "/OCuLink/PCIe_{x4}.RX2+")
			(pinfunction "A25")
			(pintype "passive")
		)
		(pad "A26" smd rect
			(at -14.501 -4.1 90)
			(size 0.53 2)
			(layers "F.Cu" "F.Mask" "F.Paste")
			(net 79 "/OCuLink/PCIe_{x4}.RX2-")
			(pinfunction "A26")
			(pintype "passive")
		)
		(pad "A27" smd rect
			(at -13.501 -4.1 90)
			(size 0.53 2)
			(layers "F.Cu" "F.Mask" "F.Paste")
			(net 66 "GND")
			(pinfunction "A27")
			(pintype "passive")
		)
		(pad "A28" smd rect
			(at -12.501 -4.1 90)
			(size 0.53 2)
			(layers "F.Cu" "F.Mask" "F.Paste")
			(net 66 "GND")
			(pinfunction "A28")
			(pintype "passive")
		)
		(pad "A29" smd rect
			(at -11.501 -4.1 90)
			(size 0.53 2)
			(layers "F.Cu" "F.Mask" "F.Paste")
			(net 68 "/OCuLink/PCIe_{x4}.RX3+")
			(pinfunction "A29")
			(pintype "passive")
		)
		(pad "A30" smd rect
			(at -10.501 -4.1 90)
			(size 0.53 2)
			(layers "F.Cu" "F.Mask" "F.Paste")
			(net 67 "/OCuLink/PCIe_{x4}.RX3-")
			(pinfunction "A30")
			(pintype "passive")
		)
		(pad "A31" smd rect
			(at -9.501 -4.1 90)
			(size 0.53 2)
			(layers "F.Cu" "F.Mask" "F.Paste")
			(net 66 "GND")
			(pinfunction "A31")
			(pintype "passive")
		)
		(pad "A32" smd rect
			(at -8.501 -4.1 90)
			(size 0.53 2)
			(layers "F.Cu" "F.Mask" "F.Paste")
			(net 27 "unconnected-(J2-PadA32)")
			(pinfunction "A32")
			(pintype "passive+no_connect")
		)
		(pad "A33" smd rect
			(at -7.502 -4.1 90)
			(size 0.53 2)
			(layers "F.Cu" "F.Mask" "F.Paste")
			(net 49 "unconnected-(J2-PadA33)")
			(pinfunction "A33")
			(pintype "passive+no_connect")
		)
		(pad "A34" smd rect
			(at -6.502 -4.1 90)
			(size 0.53 2)
			(layers "F.Cu" "F.Mask" "F.Paste")
			(net 66 "GND")
			(pinfunction "A34")
			(pintype "passive")
		)
		(pad "A35" smd rect
			(at -5.502 -4.1 90)
			(size 0.53 2)
			(layers "F.Cu" "F.Mask" "F.Paste")
			(net 62 "unconnected-(J2-PadA35)")
			(pinfunction "A35")
			(pintype "passive+no_connect")
		)
		(pad "A36" smd rect
			(at -4.502 -4.1 90)
			(size 0.53 2)
			(layers "F.Cu" "F.Mask" "F.Paste")
			(net 1 "unconnected-(J2-PadA36)")
			(pinfunction "A36")
			(pintype "passive+no_connect")
		)
		(pad "A37" smd rect
			(at -3.501 -4.1 90)
			(size 0.53 2)
			(layers "F.Cu" "F.Mask" "F.Paste")
			(net 66 "GND")
			(pinfunction "A37")
			(pintype "passive")
		)
		(pad "A38" smd rect
			(at -2.501 -4.1 90)
			(size 0.53 2)
			(layers "F.Cu" "F.Mask" "F.Paste")
			(net 66 "GND")
			(pinfunction "A38")
			(pintype "passive")
		)
		(pad "A39" smd rect
			(at -1.502 -4.1 90)
			(size 0.53 2)
			(layers "F.Cu" "F.Mask" "F.Paste")
			(net 14 "unconnected-(J2-PadA39)")
			(pinfunction "A39")
			(pintype "passive+no_connect")
		)
		(pad "A40" smd rect
			(at -0.501 -4.1 90)
			(size 0.53 2)
			(layers "F.Cu" "F.Mask" "F.Paste")
			(net 64 "unconnected-(J2-PadA40)")
			(pinfunction "A40")
			(pintype "passive+no_connect")
		)
		(pad "A41" smd rect
			(at 0.498 -4.1 90)
			(size 0.53 2)
			(layers "F.Cu" "F.Mask" "F.Paste")
			(net 66 "GND")
			(pinfunction "A41")
			(pintype "passive")
		)
		(pad "A42" smd rect
			(at 1.499 -4.1 90)
			(size 0.53 2)
			(layers "F.Cu" "F.Mask" "F.Paste")
			(net 66 "GND")
			(pinfunction "A42")
			(pintype "passive")
		)
		(pad "A43" smd rect
			(at 2.499 -4.1 90)
			(size 0.53 2)
			(layers "F.Cu" "F.Mask" "F.Paste")
			(net 39 "unconnected-(J2-PadA43)")
			(pinfunction "A43")
			(pintype "passive+no_connect")
		)
		(pad "A44" smd rect
			(at 3.499 -4.1 90)
			(size 0.53 2)
			(layers "F.Cu" "F.Mask" "F.Paste")
			(net 53 "unconnected-(J2-PadA44)")
			(pinfunction "A44")
			(pintype "passive+no_connect")
		)
		(pad "A45" smd rect
			(at 4.498 -4.1 90)
			(size 0.53 2)
			(layers "F.Cu" "F.Mask" "F.Paste")
			(net 66 "GND")
			(pinfunction "A45")
			(pintype "passive")
		)
		(pad "A46" smd rect
			(at 5.499 -4.1 90)
			(size 0.53 2)
			(layers "F.Cu" "F.Mask" "F.Paste")
			(net 66 "GND")
			(pinfunction "A46")
			(pintype "passive")
		)
		(pad "A47" smd rect
			(at 6.499 -4.1 90)
			(size 0.53 2)
			(layers "F.Cu" "F.Mask" "F.Paste")
			(net 16 "unconnected-(J2-PadA47)")
			(pinfunction "A47")
			(pintype "passive+no_connect")
		)
		(pad "A48" smd rect
			(at 7.499 -4.1 90)
			(size 0.53 2)
			(layers "F.Cu" "F.Mask" "F.Paste")
			(net 12 "unconnected-(J2-PadA48)")
			(pinfunction "A48")
			(pintype "passive+no_connect")
		)
		(pad "A49" smd rect
			(at 8.499 -4.1 90)
			(size 0.53 2)
			(layers "F.Cu" "F.Mask" "F.Paste")
			(net 66 "GND")
			(pinfunction "A49")
			(pintype "passive")
		)
		(pad "A50" smd rect
			(at 9.499 -4.1 90)
			(size 0.53 2)
			(layers "F.Cu" "F.Mask" "F.Paste")
			(net 2 "unconnected-(J2-PadA50)")
			(pinfunction "A50")
			(pintype "passive+no_connect")
		)
		(pad "A51" smd rect
			(at 10.499 -4.1 90)
			(size 0.53 2)
			(layers "F.Cu" "F.Mask" "F.Paste")
			(net 66 "GND")
			(pinfunction "A51")
			(pintype "passive")
		)
		(pad "A52" smd rect
			(at 11.499 -4.1 90)
			(size 0.53 2)
			(layers "F.Cu" "F.Mask" "F.Paste")
			(net 26 "unconnected-(J2-PadA52)")
			(pinfunction "A52")
			(pintype "passive+no_connect")
		)
		(pad "A53" smd rect
			(at 12.499 -4.1 90)
			(size 0.53 2)
			(layers "F.Cu" "F.Mask" "F.Paste")
			(net 29 "unconnected-(J2-PadA53)")
			(pinfunction "A53")
			(pintype "passive+no_connect")
		)
		(pad "A54" smd rect
			(at 13.499 -4.1 90)
			(size 0.53 2)
			(layers "F.Cu" "F.Mask" "F.Paste")
			(net 66 "GND")
			(pinfunction "A54")
			(pintype "passive")
		)
		(pad "A55" smd rect
			(at 14.499 -4.1 90)
			(size 0.53 2)
			(layers "F.Cu" "F.Mask" "F.Paste")
			(net 66 "GND")
			(pinfunction "A55")
			(pintype "passive")
		)
		(pad "A56" smd rect
			(at 15.499 -4.1 90)
			(size 0.53 2)
			(layers "F.Cu" "F.Mask" "F.Paste")
			(net 40 "unconnected-(J2-PadA56)")
			(pinfunction "A56")
			(pintype "passive+no_connect")
		)
		(pad "A57" smd rect
			(at 16.498 -4.1 90)
			(size 0.53 2)
			(layers "F.Cu" "F.Mask" "F.Paste")
			(net 37 "unconnected-(J2-PadA57)")
			(pinfunction "A57")
			(pintype "passive+no_connect")
		)
		(pad "A58" smd rect
			(at 17.498 -4.1 90)
			(size 0.53 2)
			(layers "F.Cu" "F.Mask" "F.Paste")
			(net 66 "GND")
			(pinfunction "A58")
			(pintype "passive")
		)
		(pad "A59" smd rect
			(at 18.498 -4.1 90)
			(size 0.53 2)
			(layers "F.Cu" "F.Mask" "F.Paste")
			(net 66 "GND")
			(pinfunction "A59")
			(pintype "passive")
		)
		(pad "A60" smd rect
			(at 19.498 -4.1 90)
			(size 0.53 2)
			(layers "F.Cu" "F.Mask" "F.Paste")
			(net 18 "unconnected-(J2-PadA60)")
			(pinfunction "A60")
			(pintype "passive+no_connect")
		)
		(pad "A61" smd rect
			(at 20.498 -4.1 90)
			(size 0.53 2)
			(layers "F.Cu" "F.Mask" "F.Paste")
			(net 30 "unconnected-(J2-PadA61)")
			(pinfunction "A61")
			(pintype "passive+no_connect")
		)
		(pad "A62" smd rect
			(at 21.498 -4.1 90)
			(size 0.53 2)
			(layers "F.Cu" "F.Mask" "F.Paste")
			(net 66 "GND")
			(pinfunction "A62")
			(pintype "passive")
		)
		(pad "A63" smd rect
			(at 22.498 -4.1 90)
			(size 0.53 2)
			(layers "F.Cu" "F.Mask" "F.Paste")
			(net 66 "GND")
			(pinfunction "A63")
			(pintype "passive")
		)
		(pad "A64" smd rect
			(at 23.498 -4.1 90)
			(size 0.53 2)
			(layers "F.Cu" "F.Mask" "F.Paste")
			(net 3 "unconnected-(J2-PadA64)")
			(pinfunction "A64")
			(pintype "passive+no_connect")
		)
		(pad "A65" smd rect
			(at 24.498 -4.1 90)
			(size 0.53 2)
			(layers "F.Cu" "F.Mask" "F.Paste")
			(net 6 "unconnected-(J2-PadA65)")
			(pinfunction "A65")
			(pintype "passive+no_connect")
		)
		(pad "A66" smd rect
			(at 25.498 -4.1 90)
			(size 0.53 2)
			(layers "F.Cu" "F.Mask" "F.Paste")
			(net 66 "GND")
			(pinfunction "A66")
			(pintype "passive")
		)
		(pad "A67" smd rect
			(at 26.498 -4.1 90)
			(size 0.53 2)
			(layers "F.Cu" "F.Mask" "F.Paste")
			(net 66 "GND")
			(pinfunction "A67")
			(pintype "passive")
		)
		(pad "A68" smd rect
			(at 27.499 -4.1 90)
			(size 0.53 2)
			(layers "F.Cu" "F.Mask" "F.Paste")
			(net 23 "unconnected-(J2-PadA68)")
			(pinfunction "A68")
			(pintype "passive+no_connect")
		)
		(pad "A69" smd rect
			(at 28.499 -4.1 90)
			(size 0.53 2)
			(layers "F.Cu" "F.Mask" "F.Paste")
			(net 20 "unconnected-(J2-PadA69)")
			(pinfunction "A69")
			(pintype "passive+no_connect")
		)
		(pad "A70" smd rect
			(at 29.499 -4.1 90)
			(size 0.53 2)
			(layers "F.Cu" "F.Mask" "F.Paste")
			(net 66 "GND")
			(pinfunction "A70")
			(pintype "passive")
		)
		(pad "A71" smd rect
			(at 30.499 -4.1 90)
			(size 0.53 2)
			(layers "F.Cu" "F.Mask" "F.Paste")
			(net 66 "GND")
			(pinfunction "A71")
			(pintype "passive")
		)
		(pad "A72" smd rect
			(at 31.499 -4.1 90)
			(size 0.53 2)
			(layers "F.Cu" "F.Mask" "F.Paste")
			(net 8 "unconnected-(J2-PadA72)")
			(pinfunction "A72")
			(pintype "passive+no_connect")
		)
		(pad "A73" smd rect
			(at 32.499 -4.1 90)
			(size 0.53 2)
			(layers "F.Cu" "F.Mask" "F.Paste")
			(net 59 "unconnected-(J2-PadA73)")
			(pinfunction "A73")
			(pintype "passive+no_connect")
		)
		(pad "A74" smd rect
			(at 33.499 -4.1 90)
			(size 0.53 2)
			(layers "F.Cu" "F.Mask" "F.Paste")
			(net 66 "GND")
			(pinfunction "A74")
			(pintype "passive")
		)
		(pad "A75" smd rect
			(at 34.499 -4.1 90)
			(size 0.53 2)
			(layers "F.Cu" "F.Mask" "F.Paste")
			(net 66 "GND")
			(pinfunction "A75")
			(pintype "passive")
		)
		(pad "A76" smd rect
			(at 35.499 -4.1 90)
			(size 0.53 2)
			(layers "F.Cu" "F.Mask" "F.Paste")
			(net 13 "unconnected-(J2-PadA76)")
			(pinfunction "A76")
			(pintype "passive+no_connect")
		)
		(pad "A77" smd rect
			(at 36.499 -4.1 90)
			(size 0.53 2)
			(layers "F.Cu" "F.Mask" "F.Paste")
			(net 45 "unconnected-(J2-PadA77)")
			(pinfunction "A77")
			(pintype "passive+no_connect")
		)
		(pad "A78" smd rect
			(at 37.499 -4.1 90)
			(size 0.53 2)
			(layers "F.Cu" "F.Mask" "F.Paste")
			(net 66 "GND")
			(pinfunction "A78")
			(pintype "passive")
		)
		(pad "A79" smd rect
			(at 38.499 -4.1 90)
			(size 0.53 2)
			(layers "F.Cu" "F.Mask" "F.Paste")
			(net 66 "GND")
			(pinfunction "A79")
			(pintype "passive")
		)
		(pad "A80" smd rect
			(at 39.499 -4.1 90)
			(size 0.53 2)
			(layers "F.Cu" "F.Mask" "F.Paste")
			(net 32 "unconnected-(J2-PadA80)")
			(pinfunction "A80")
			(pintype "passive+no_connect")
		)
		(pad "A81" smd rect
			(at 40.499 -4.1 90)
			(size 0.53 2)
			(layers "F.Cu" "F.Mask" "F.Paste")
			(net 47 "unconnected-(J2-PadA81)")
			(pinfunction "A81")
			(pintype "passive+no_connect")
		)
		(pad "A82" smd rect
			(at 41.499 -4.1 90)
			(size 0.53 2)
			(layers "F.Cu" "F.Mask" "F.Paste")
			(net 66 "GND")
			(pinfunction "A82")
			(pintype "passive")
		)
		(pad "B1" smd rect
			(at -41.5 3.1 90)
			(size 0.53 2)
			(layers "F.Cu" "F.Mask" "F.Paste")
			(net 87 "+12V")
			(pinfunction "B1")
			(pintype "passive")
		)
		(pad "B2" smd rect
			(at -40.5 3.1 90)
			(size 0.53 2)
			(layers "F.Cu" "F.Mask" "F.Paste")
			(net 87 "+12V")
			(pinfunction "B2")
			(pintype "passive")
		)
		(pad "B3" smd rect
			(at -39.5 3.1 90)
			(size 0.53 2)
			(layers "F.Cu" "F.Mask" "F.Paste")
			(net 87 "+12V")
			(pinfunction "B3")
			(pintype "passive")
		)
		(pad "B4" smd rect
			(at -38.5 3.1 90)
			(size 0.53 2)
			(layers "F.Cu" "F.Mask" "F.Paste")
			(net 66 "GND")
			(pinfunction "B4")
			(pintype "passive")
		)
		(pad "B5" smd rect
			(at -37.5 3.1 90)
			(size 0.53 2)
			(layers "F.Cu" "F.Mask" "F.Paste")
			(net 102 "/OCuLink/I2C0.SCL")
			(pinfunction "B5")
			(pintype "passive")
		)
		(pad "B6" smd rect
			(at -36.5 3.1 90)
			(size 0.53 2)
			(layers "F.Cu" "F.Mask" "F.Paste")
			(net 103 "/OCuLink/I2C0.SDA")
			(pinfunction "B6")
			(pintype "passive")
		)
		(pad "B7" smd rect
			(at -35.5 3.1 90)
			(size 0.53 2)
			(layers "F.Cu" "F.Mask" "F.Paste")
			(net 66 "GND")
			(pinfunction "B7")
			(pintype "passive")
		)
		(pad "B8" smd rect
			(at -34.5 3.1 90)
			(size 0.53 2)
			(layers "F.Cu" "F.Mask" "F.Paste")
			(net 134 "+3V3")
			(pinfunction "B8")
			(pintype "passive")
		)
		(pad "B9" smd rect
			(at -33.5 3.1 90)
			(size 0.53 2)
			(layers "F.Cu" "F.Mask" "F.Paste")
			(net 50 "unconnected-(J2-PadB9)")
			(pinfunction "B9")
			(pintype "passive+no_connect")
		)
		(pad "B10" smd rect
			(at -32.5 3.1 90)
			(size 0.53 2)
			(layers "F.Cu" "F.Mask" "F.Paste")
			(net 83 "/PCIe-connector/3V3_PCIe_AUX")
			(pinfunction "B10")
			(pintype "passive")
		)
		(pad "B11" smd rect
			(at -31.5 3.1 90)
			(size 0.53 2)
			(layers "F.Cu" "F.Mask" "F.Paste")
			(net 93 "/OCuLink/~{WAKE}")
			(pinfunction "B11")
			(pintype "passive")
		)
		(pad "B12" smd rect
			(at -28.5 3.1 90)
			(size 0.53 2)
			(layers "F.Cu" "F.Mask" "F.Paste")
			(net 38 "unconnected-(J2-PadB12)")
			(pinfunction "B12")
			(pintype "passive+no_connect")
		)
		(pad "B13" smd rect
			(at -27.5 3.1 90)
			(size 0.53 2)
			(layers "F.Cu" "F.Mask" "F.Paste")
			(net 66 "GND")
			(pinfunction "B13")
			(pintype "passive")
		)
		(pad "B14" smd rect
			(at -26.5 3.1 90)
			(size 0.53 2)
			(layers "F.Cu" "F.Mask" "F.Paste")
			(net 72 "/OCuLink/PCIe_{x4}.TX0+")
			(pinfunction "B14")
			(pintype "passive")
		)
		(pad "B15" smd rect
			(at -25.5 3.1 90)
			(size 0.53 2)
			(layers "F.Cu" "F.Mask" "F.Paste")
			(net 74 "/OCuLink/PCIe_{x4}.TX0-")
			(pinfunction "B15")
			(pintype "passive")
		)
		(pad "B16" smd rect
			(at -24.5 3.1 90)
			(size 0.53 2)
			(layers "F.Cu" "F.Mask" "F.Paste")
			(net 66 "GND")
			(pinfunction "B16")
			(pintype "passive")
		)
		(pad "B17" smd rect
			(at -23.5 3.1 90)
			(size 0.53 2)
			(layers "F.Cu" "F.Mask" "F.Paste")
			(net 7 "unconnected-(J2-PadB17)")
			(pinfunction "B17")
			(pintype "passive+no_connect")
		)
		(pad "B18" smd rect
			(at -22.5 3.1 90)
			(size 0.53 2)
			(layers "F.Cu" "F.Mask" "F.Paste")
			(net 66 "GND")
			(pinfunction "B18")
			(pintype "passive")
		)
		(pad "B19" smd rect
			(at -21.5 3.1 90)
			(size 0.53 2)
			(layers "F.Cu" "F.Mask" "F.Paste")
			(net 77 "/OCuLink/PCIe_{x4}.TX1+")
			(pinfunction "B19")
			(pintype "passive")
		)
		(pad "B20" smd rect
			(at -20.5 3.1 90)
			(size 0.53 2)
			(layers "F.Cu" "F.Mask" "F.Paste")
			(net 69 "/OCuLink/PCIe_{x4}.TX1-")
			(pinfunction "B20")
			(pintype "passive")
		)
		(pad "B21" smd rect
			(at -19.5 3.1 90)
			(size 0.53 2)
			(layers "F.Cu" "F.Mask" "F.Paste")
			(net 66 "GND")
			(pinfunction "B21")
			(pintype "passive")
		)
		(pad "B22" smd rect
			(at -18.5 3.1 90)
			(size 0.53 2)
			(layers "F.Cu" "F.Mask" "F.Paste")
			(net 66 "GND")
			(pinfunction "B22")
			(pintype "passive")
		)
		(pad "B23" smd rect
			(at -17.5 3.1 90)
			(size 0.53 2)
			(layers "F.Cu" "F.Mask" "F.Paste")
			(net 70 "/OCuLink/PCIe_{x4}.TX2+")
			(pinfunction "B23")
			(pintype "passive")
		)
		(pad "B24" smd rect
			(at -16.5 3.1 90)
			(size 0.53 2)
			(layers "F.Cu" "F.Mask" "F.Paste")
			(net 76 "/OCuLink/PCIe_{x4}.TX2-")
			(pinfunction "B24")
			(pintype "passive")
		)
		(pad "B25" smd rect
			(at -15.501 3.1 90)
			(size 0.53 2)
			(layers "F.Cu" "F.Mask" "F.Paste")
			(net 66 "GND")
			(pinfunction "B25")
			(pintype "passive")
		)
		(pad "B26" smd rect
			(at -14.501 3.1 90)
			(size 0.53 2)
			(layers "F.Cu" "F.Mask" "F.Paste")
			(net 66 "GND")
			(pinfunction "B26")
			(pintype "passive")
		)
		(pad "B27" smd rect
			(at -13.501 3.1 90)
			(size 0.53 2)
			(layers "F.Cu" "F.Mask" "F.Paste")
			(net 82 "/OCuLink/PCIe_{x4}.TX3+")
			(pinfunction "B27")
			(pintype "passive")
		)
		(pad "B28" smd rect
			(at -12.501 3.1 90)
			(size 0.53 2)
			(layers "F.Cu" "F.Mask" "F.Paste")
			(net 80 "/OCuLink/PCIe_{x4}.TX3-")
			(pinfunction "B28")
			(pintype "passive")
		)
		(pad "B29" smd rect
			(at -11.501 3.1 90)
			(size 0.53 2)
			(layers "F.Cu" "F.Mask" "F.Paste")
			(net 66 "GND")
			(pinfunction "B29")
			(pintype "passive")
		)
		(pad "B30" smd rect
			(at -10.501 3.1 90)
			(size 0.53 2)
			(layers "F.Cu" "F.Mask" "F.Paste")
			(net 54 "unconnected-(J2-PadB30)")
			(pinfunction "B30")
			(pintype "passive+no_connect")
		)
		(pad "B31" smd rect
			(at -9.501 3.1 90)
			(size 0.53 2)
			(layers "F.Cu" "F.Mask" "F.Paste")
			(net 10 "unconnected-(J2-PadB31)")
			(pinfunction "B31")
			(pintype "passive+no_connect")
		)
		(pad "B32" smd rect
			(at -8.501 3.1 90)
			(size 0.53 2)
			(layers "F.Cu" "F.Mask" "F.Paste")
			(net 66 "GND")
			(pinfunction "B32")
			(pintype "passive")
		)
		(pad "B33" smd rect
			(at -7.502 3.1 90)
			(size 0.53 2)
			(layers "F.Cu" "F.Mask" "F.Paste")
			(net 5 "unconnected-(J2-PadB33)")
			(pinfunction "B33")
			(pintype "passive+no_connect")
		)
		(pad "B34" smd rect
			(at -6.502 3.1 90)
			(size 0.53 2)
			(layers "F.Cu" "F.Mask" "F.Paste")
			(net 41 "unconnected-(J2-PadB34)")
			(pinfunction "B34")
			(pintype "passive+no_connect")
		)
		(pad "B35" smd rect
			(at -5.502 3.1 90)
			(size 0.53 2)
			(layers "F.Cu" "F.Mask" "F.Paste")
			(net 66 "GND")
			(pinfunction "B35")
			(pintype "passive")
		)
		(pad "B36" smd rect
			(at -4.502 3.1 90)
			(size 0.53 2)
			(layers "F.Cu" "F.Mask" "F.Paste")
			(net 66 "GND")
			(pinfunction "B36")
			(pintype "passive")
		)
		(pad "B37" smd rect
			(at -3.501 3.1 90)
			(size 0.53 2)
			(layers "F.Cu" "F.Mask" "F.Paste")
			(net 44 "unconnected-(J2-PadB37)")
			(pinfunction "B37")
			(pintype "passive+no_connect")
		)
		(pad "B38" smd rect
			(at -2.501 3.1 90)
			(size 0.53 2)
			(layers "F.Cu" "F.Mask" "F.Paste")
			(net 11 "unconnected-(J2-PadB38)")
			(pinfunction "B38")
			(pintype "passive+no_connect")
		)
		(pad "B39" smd rect
			(at -1.502 3.1 90)
			(size 0.53 2)
			(layers "F.Cu" "F.Mask" "F.Paste")
			(net 66 "GND")
			(pinfunction "B39")
			(pintype "passive")
		)
		(pad "B40" smd rect
			(at -0.501 3.1 90)
			(size 0.53 2)
			(layers "F.Cu" "F.Mask" "F.Paste")
			(net 66 "GND")
			(pinfunction "B40")
			(pintype "passive")
		)
		(pad "B41" smd rect
			(at 0.498 3.1 90)
			(size 0.53 2)
			(layers "F.Cu" "F.Mask" "F.Paste")
			(net 46 "unconnected-(J2-PadB41)")
			(pinfunction "B41")
			(pintype "passive+no_connect")
		)
		(pad "B42" smd rect
			(at 1.499 3.1 90)
			(size 0.53 2)
			(layers "F.Cu" "F.Mask" "F.Paste")
			(net 58 "unconnected-(J2-PadB42)")
			(pinfunction "B42")
			(pintype "passive+no_connect")
		)
		(pad "B43" smd rect
			(at 2.499 3.1 90)
			(size 0.53 2)
			(layers "F.Cu" "F.Mask" "F.Paste")
			(net 66 "GND")
			(pinfunction "B43")
			(pintype "passive")
		)
		(pad "B44" smd rect
			(at 3.499 3.1 90)
			(size 0.53 2)
			(layers "F.Cu" "F.Mask" "F.Paste")
			(net 66 "GND")
			(pinfunction "B44")
			(pintype "passive")
		)
		(pad "B45" smd rect
			(at 4.498 3.1 90)
			(size 0.53 2)
			(layers "F.Cu" "F.Mask" "F.Paste")
			(net 65 "unconnected-(J2-PadB45)")
			(pinfunction "B45")
			(pintype "passive+no_connect")
		)
		(pad "B46" smd rect
			(at 5.499 3.1 90)
			(size 0.53 2)
			(layers "F.Cu" "F.Mask" "F.Paste")
			(net 15 "unconnected-(J2-PadB46)")
			(pinfunction "B46")
			(pintype "passive+no_connect")
		)
		(pad "B47" smd rect
			(at 6.499 3.1 90)
			(size 0.53 2)
			(layers "F.Cu" "F.Mask" "F.Paste")
			(net 66 "GND")
			(pinfunction "B47")
			(pintype "passive")
		)
		(pad "B48" smd rect
			(at 7.499 3.1 90)
			(size 0.53 2)
			(layers "F.Cu" "F.Mask" "F.Paste")
			(net 43 "unconnected-(J2-PadB48)")
			(pinfunction "B48")
			(pintype "passive+no_connect")
		)
		(pad "B49" smd rect
			(at 8.499 3.1 90)
			(size 0.53 2)
			(layers "F.Cu" "F.Mask" "F.Paste")
			(net 66 "GND")
			(pinfunction "B49")
			(pintype "passive")
		)
		(pad "B50" smd rect
			(at 9.499 3.1 90)
			(size 0.53 2)
			(layers "F.Cu" "F.Mask" "F.Paste")
			(net 35 "unconnected-(J2-PadB50)")
			(pinfunction "B50")
			(pintype "passive+no_connect")
		)
		(pad "B51" smd rect
			(at 10.499 3.1 90)
			(size 0.53 2)
			(layers "F.Cu" "F.Mask" "F.Paste")
			(net 31 "unconnected-(J2-PadB51)")
			(pinfunction "B51")
			(pintype "passive+no_connect")
		)
		(pad "B52" smd rect
			(at 11.499 3.1 90)
			(size 0.53 2)
			(layers "F.Cu" "F.Mask" "F.Paste")
			(net 66 "GND")
			(pinfunction "B52")
			(pintype "passive")
		)
		(pad "B53" smd rect
			(at 12.499 3.1 90)
			(size 0.53 2)
			(layers "F.Cu" "F.Mask" "F.Paste")
			(net 66 "GND")
			(pinfunction "B53")
			(pintype "passive")
		)
		(pad "B54" smd rect
			(at 13.499 3.1 90)
			(size 0.53 2)
			(layers "F.Cu" "F.Mask" "F.Paste")
			(net 33 "unconnected-(J2-PadB54)")
			(pinfunction "B54")
			(pintype "passive+no_connect")
		)
		(pad "B55" smd rect
			(at 14.499 3.1 90)
			(size 0.53 2)
			(layers "F.Cu" "F.Mask" "F.Paste")
			(net 9 "unconnected-(J2-PadB55)")
			(pinfunction "B55")
			(pintype "passive+no_connect")
		)
		(pad "B56" smd rect
			(at 15.499 3.1 90)
			(size 0.53 2)
			(layers "F.Cu" "F.Mask" "F.Paste")
			(net 66 "GND")
			(pinfunction "B56")
			(pintype "passive")
		)
		(pad "B57" smd rect
			(at 16.498 3.1 90)
			(size 0.53 2)
			(layers "F.Cu" "F.Mask" "F.Paste")
			(net 66 "GND")
			(pinfunction "B57")
			(pintype "passive")
		)
		(pad "B58" smd rect
			(at 17.498 3.1 90)
			(size 0.53 2)
			(layers "F.Cu" "F.Mask" "F.Paste")
			(net 56 "unconnected-(J2-PadB58)")
			(pinfunction "B58")
			(pintype "passive+no_connect")
		)
		(pad "B59" smd rect
			(at 18.498 3.1 90)
			(size 0.53 2)
			(layers "F.Cu" "F.Mask" "F.Paste")
			(net 63 "unconnected-(J2-PadB59)")
			(pinfunction "B59")
			(pintype "passive+no_connect")
		)
		(pad "B60" smd rect
			(at 19.498 3.1 90)
			(size 0.53 2)
			(layers "F.Cu" "F.Mask" "F.Paste")
			(net 66 "GND")
			(pinfunction "B60")
			(pintype "passive")
		)
		(pad "B61" smd rect
			(at 20.498 3.1 90)
			(size 0.53 2)
			(layers "F.Cu" "F.Mask" "F.Paste")
			(net 66 "GND")
			(pinfunction "B61")
			(pintype "passive")
		)
		(pad "B62" smd rect
			(at 21.498 3.1 90)
			(size 0.53 2)
			(layers "F.Cu" "F.Mask" "F.Paste")
			(net 17 "unconnected-(J2-PadB62)")
			(pinfunction "B62")
			(pintype "passive+no_connect")
		)
		(pad "B63" smd rect
			(at 22.498 3.1 90)
			(size 0.53 2)
			(layers "F.Cu" "F.Mask" "F.Paste")
			(net 51 "unconnected-(J2-PadB63)")
			(pinfunction "B63")
			(pintype "passive+no_connect")
		)
		(pad "B64" smd rect
			(at 23.498 3.1 90)
			(size 0.53 2)
			(layers "F.Cu" "F.Mask" "F.Paste")
			(net 66 "GND")
			(pinfunction "B64")
			(pintype "passive")
		)
		(pad "B65" smd rect
			(at 24.498 3.1 90)
			(size 0.53 2)
			(layers "F.Cu" "F.Mask" "F.Paste")
			(net 66 "GND")
			(pinfunction "B65")
			(pintype "passive")
		)
		(pad "B66" smd rect
			(at 25.498 3.1 90)
			(size 0.53 2)
			(layers "F.Cu" "F.Mask" "F.Paste")
			(net 34 "unconnected-(J2-PadB66)")
			(pinfunction "B66")
			(pintype "passive+no_connect")
		)
		(pad "B67" smd rect
			(at 26.498 3.1 90)
			(size 0.53 2)
			(layers "F.Cu" "F.Mask" "F.Paste")
			(net 52 "unconnected-(J2-PadB67)")
			(pinfunction "B67")
			(pintype "passive+no_connect")
		)
		(pad "B68" smd rect
			(at 27.499 3.1 90)
			(size 0.53 2)
			(layers "F.Cu" "F.Mask" "F.Paste")
			(net 66 "GND")
			(pinfunction "B68")
			(pintype "passive")
		)
		(pad "B69" smd rect
			(at 28.499 3.1 90)
			(size 0.53 2)
			(layers "F.Cu" "F.Mask" "F.Paste")
			(net 66 "GND")
			(pinfunction "B69")
			(pintype "passive")
		)
		(pad "B70" smd rect
			(at 29.499 3.1 90)
			(size 0.53 2)
			(layers "F.Cu" "F.Mask" "F.Paste")
			(net 4 "unconnected-(J2-PadB70)")
			(pinfunction "B70")
			(pintype "passive+no_connect")
		)
		(pad "B71" smd rect
			(at 30.499 3.1 90)
			(size 0.53 2)
			(layers "F.Cu" "F.Mask" "F.Paste")
			(net 42 "unconnected-(J2-PadB71)")
			(pinfunction "B71")
			(pintype "passive+no_connect")
		)
		(pad "B72" smd rect
			(at 31.499 3.1 90)
			(size 0.53 2)
			(layers "F.Cu" "F.Mask" "F.Paste")
			(net 66 "GND")
			(pinfunction "B72")
			(pintype "passive")
		)
		(pad "B73" smd rect
			(at 32.499 3.1 90)
			(size 0.53 2)
			(layers "F.Cu" "F.Mask" "F.Paste")
			(net 66 "GND")
			(pinfunction "B73")
			(pintype "passive")
		)
		(pad "B74" smd rect
			(at 33.499 3.1 90)
			(size 0.53 2)
			(layers "F.Cu" "F.Mask" "F.Paste")
			(net 22 "unconnected-(J2-PadB74)")
			(pinfunction "B74")
			(pintype "passive+no_connect")
		)
		(pad "B75" smd rect
			(at 34.499 3.1 90)
			(size 0.53 2)
			(layers "F.Cu" "F.Mask" "F.Paste")
			(net 60 "unconnected-(J2-PadB75)")
			(pinfunction "B75")
			(pintype "passive+no_connect")
		)
		(pad "B76" smd rect
			(at 35.499 3.1 90)
			(size 0.53 2)
			(layers "F.Cu" "F.Mask" "F.Paste")
			(net 66 "GND")
			(pinfunction "B76")
			(pintype "passive")
		)
		(pad "B77" smd rect
			(at 36.499 3.1 90)
			(size 0.53 2)
			(layers "F.Cu" "F.Mask" "F.Paste")
			(net 66 "GND")
			(pinfunction "B77")
			(pintype "passive")
		)
		(pad "B78" smd rect
			(at 37.499 3.1 90)
			(size 0.53 2)
			(layers "F.Cu" "F.Mask" "F.Paste")
			(net 48 "unconnected-(J2-PadB78)")
			(pinfunction "B78")
			(pintype "passive+no_connect")
		)
		(pad "B79" smd rect
			(at 38.499 3.1 90)
			(size 0.53 2)
			(layers "F.Cu" "F.Mask" "F.Paste")
			(net 61 "unconnected-(J2-PadB79)")
			(pinfunction "B79")
			(pintype "passive+no_connect")
		)
		(pad "B80" smd rect
			(at 39.499 3.1 90)
			(size 0.53 2)
			(layers "F.Cu" "F.Mask" "F.Paste")
			(net 66 "GND")
			(pinfunction "B80")
			(pintype "passive")
		)
		(pad "B81" smd rect
			(at 40.499 3.1 90)
			(size 0.53 2)
			(layers "F.Cu" "F.Mask" "F.Paste")
			(net 25 "unconnected-(J2-PadB81)")
			(pinfunction "B81")
			(pintype "passive+no_connect")
		)
		(pad "B82" smd rect
			(at 41.499 3.1 90)
			(size 0.53 2)
			(layers "F.Cu" "F.Mask" "F.Paste")
			(net 28 "unconnected-(J2-PadB82)")
			(pinfunction "B82")
			(pintype "passive+no_connect")
		)
		(pad "S1" smd rect
			(at -44.5 -0.5 90)
			(size 3 5)
			(layers "F.Cu" "F.Mask")
			(net 66 "GND")
			(pinfunction "S1")
			(pintype "passive")
		)
		(pad "S2" smd rect
			(at 44.6 -0.5005 90)
			(size 3 5)
			(layers "F.Cu" "F.Mask")
			(net 66 "GND")
			(pinfunction "S2")
			(pintype "passive")
		)
	)
	(footprint "antmicro-footprints:R_0402_1005Metric"
		(layer "F.Cu")
		(at 136.75 68.05 90)
		(descr "Resistor SMD 0402")
		(tags "resistor SMD 0402")
		(property "Reference" "R48"
			(at 1.299999 -5.499499 90)
			(layer "F.SilkS")
			(effects
				(font
					(size 0.7 0.7)
					(thickness 0.15)
				)
				(justify right top)
			)
		)
		(property "Value" "R_1k_0402"
			(at -1.011843 1.772046 90)
			(layer "F.Fab")
			(effects
				(font
					(size 0.7 0.7)
					(thickness 0.15)
				)
				(justify left bottom)
			)
		)
		(property "Datasheet" "https://www.bourns.com/docs/product-datasheets/cr.pdf"
			(at 0 0 90)
			(layer "F.Fab")
			(hide yes)
			(effects
				(font
					(size 1.27 1.27)
					(thickness 0.15)
				)
			)
		)
		(property "Description" "SMD Chip Resistor, 1 kohm, ± 1%, 63 mW, 0402 [1005 Metric], Thick Film, General Purpose"
			(at 0 0 90)
			(layer "F.Fab")
			(hide yes)
			(effects
				(font
					(size 1.27 1.27)
					(thickness 0.15)
				)
			)
		)
		(property "MPN" "CR0402-FX-1001GLF"
			(at 0 0 90)
			(unlocked yes)
			(layer "F.Fab")
			(hide yes)
			(effects
				(font
					(size 1 1)
					(thickness 0.15)
				)
			)
		)
		(property "Manufacturer" "Bourns"
			(at 0 0 90)
			(unlocked yes)
			(layer "F.Fab")
			(hide yes)
			(effects
				(font
					(size 1 1)
					(thickness 0.15)
				)
			)
		)
		(property "License" "Apache-2.0"
			(at 0 0 90)
			(unlocked yes)
			(layer "F.Fab")
			(hide yes)
			(effects
				(font
					(size 1 1)
					(thickness 0.15)
				)
			)
		)
		(property "Author" "Antmicro"
			(at 0 0 90)
			(unlocked yes)
			(layer "F.Fab")
			(hide yes)
			(effects
				(font
					(size 1 1)
					(thickness 0.15)
				)
			)
		)
		(property "Val" "1k"
			(at 0 0 90)
			(unlocked yes)
			(layer "F.Fab")
			(hide yes)
			(effects
				(font
					(size 1 1)
					(thickness 0.15)
				)
			)
		)
		(property "Tolerance" "1%"
			(at 0 0 90)
			(unlocked yes)
			(layer "F.Fab")
			(hide yes)
			(effects
				(font
					(size 1 1)
					(thickness 0.15)
				)
			)
		)
		(sheetname "/USB-PD/")
		(sheetfile "usb-pd.kicad_sch")
		(attr smd)
		(fp_rect
			(start -0.925 -0.47)
			(end 0.925 0.47)
			(stroke
				(width 0.05)
				(type default)
			)
			(fill no)
			(layer "F.CrtYd")
		)
		(fp_rect
			(start -0.5 -0.25)
			(end 0.5 0.25)
			(stroke
				(width 0.15)
				(type solid)
			)
			(fill no)
			(layer "F.Fab")
		)
		(fp_text user "Author: Antmicro"
			(at -0.95 4.169 90)
			(layer "F.Fab")
			(effects
				(font
					(size 0.7 0.7)
					(thickness 0.15)
				)
				(justify left bottom)
			)
		)
		(fp_text user "${REFERENCE}"
			(at 0 0 270)
			(layer "F.Fab")
			(effects
				(font
					(size 0.7 0.7)
					(thickness 0.15)
				)
				(justify right top)
			)
		)
		(fp_text user "License: Apache-2.0"
			(at -0.949999 5.169 90)
			(layer "F.Fab")
			(effects
				(font
					(size 0.7 0.7)
					(thickness 0.15)
				)
				(justify left bottom)
			)
		)
		(pad "1" smd roundrect
			(at -0.48 0 90)
			(size 0.59 0.64)
			(layers "F.Cu" "F.Mask" "F.Paste")
			(roundrect_rratio 0.25)
			(net 173 "/USB-PD/~{FAULT}")
			(pintype "passive")
		)
		(pad "2" smd roundrect
			(at 0.48 0 90)
			(size 0.59 0.64)
			(layers "F.Cu" "F.Mask" "F.Paste")
			(roundrect_rratio 0.25)
			(net 117 "/USB-PD/VDDD_3V3")
			(pintype "passive")
		)
	)
	(footprint "antmicro-footprints:R_0402_1005Metric"
		(layer "F.Cu")
		(at 140.6 50.8 -90)
		(descr "Resistor SMD 0402")
		(tags "resistor SMD 0402")
		(property "Reference" "R1"
			(at 0.95 0.4 270)
			(layer "F.SilkS")
			(effects
				(font
					(size 0.7 0.7)
					(thickness 0.15)
				)
				(justify right top)
			)
		)
		(property "Value" "R_0R_0402"
			(at -1.011843 1.772046 90)
			(layer "F.Fab")
			(effects
				(font
					(size 0.7 0.7)
					(thickness 0.15)
				)
				(justify right top)
			)
		)
		(property "Datasheet" "https://industrial.panasonic.com/cdbs/www-data/pdf/RDA0000/AOA0000C301.pdf"
			(at 0 0 90)
			(layer "F.Fab")
			(hide yes)
			(effects
				(font
					(size 1.27 1.27)
					(thickness 0.15)
				)
			)
		)
		(property "Description" "SMD Chip Resistor, Jumper, 0 ohm, 100 mW, 0402 [1005 Metric], Thick Film, General Purpose"
			(at 0 0 90)
			(layer "F.Fab")
			(hide yes)
			(effects
				(font
					(size 1.27 1.27)
					(thickness 0.15)
				)
			)
		)
		(property "MPN" "ERJ2GE0R00X"
			(at 0 0 270)
			(unlocked yes)
			(layer "F.Fab")
			(hide yes)
			(effects
				(font
					(size 1 1)
					(thickness 0.15)
				)
			)
		)
		(property "Manufacturer" "Panasonic"
			(at 0 0 270)
			(unlocked yes)
			(layer "F.Fab")
			(hide yes)
			(effects
				(font
					(size 1 1)
					(thickness 0.15)
				)
			)
		)
		(property "License" "Apache-2.0"
			(at 0 0 270)
			(unlocked yes)
			(layer "F.Fab")
			(hide yes)
			(effects
				(font
					(size 1 1)
					(thickness 0.15)
				)
			)
		)
		(property "Author" "Antmicro"
			(at 0 0 270)
			(unlocked yes)
			(layer "F.Fab")
			(hide yes)
			(effects
				(font
					(size 1 1)
					(thickness 0.15)
				)
			)
		)
		(property "Val" "0R"
			(at 0 0 270)
			(unlocked yes)
			(layer "F.Fab")
			(hide yes)
			(effects
				(font
					(size 1 1)
					(thickness 0.15)
				)
			)
		)
		(property "Tolerance" ""
			(at 0 0 270)
			(unlocked yes)
			(layer "F.Fab")
			(hide yes)
			(effects
				(font
					(size 1 1)
					(thickness 0.15)
				)
			)
		)
		(property "Current" "1A"
			(at 0 0 270)
			(unlocked yes)
			(layer "F.Fab")
			(hide yes)
			(effects
				(font
					(size 1 1)
					(thickness 0.15)
				)
			)
		)
		(sheetname "/OCuLink/")
		(sheetfile "oculink.kicad_sch")
		(attr smd dnp)
		(fp_rect
			(start -0.925 -0.47)
			(end 0.925 0.47)
			(stroke
				(width 0.05)
				(type default)
			)
			(fill no)
			(layer "F.CrtYd")
		)
		(fp_rect
			(start -0.5 -0.25)
			(end 0.5 0.25)
			(stroke
				(width 0.15)
				(type solid)
			)
			(fill no)
			(layer "F.Fab")
		)
		(fp_text user "${REFERENCE}"
			(at 0 0 90)
			(layer "F.Fab")
			(effects
				(font
					(size 0.7 0.7)
					(thickness 0.15)
				)
				(justify right top)
			)
		)
		(fp_text user "License: Apache-2.0"
			(at -0.949999 5.169 90)
			(layer "F.Fab")
			(effects
				(font
					(size 0.7 0.7)
					(thickness 0.15)
				)
				(justify right top)
			)
		)
		(fp_text user "Author: Antmicro"
			(at -0.95 4.169 90)
			(layer "F.Fab")
			(effects
				(font
					(size 0.7 0.7)
					(thickness 0.15)
				)
				(justify right top)
			)
		)
		(pad "1" smd roundrect
			(at -0.48 0 270)
			(size 0.59 0.64)
			(layers "F.Cu" "F.Mask" "F.Paste")
			(roundrect_rratio 0.25)
			(net 101 "/OCuLink/I2C0C_SCL")
			(pintype "passive")
		)
		(pad "2" smd roundrect
			(at 0.48 0 270)
			(size 0.59 0.64)
			(layers "F.Cu" "F.Mask" "F.Paste")
			(roundrect_rratio 0.25)
			(net 102 "/OCuLink/I2C0.SCL")
			(pintype "passive")
		)
	)
	(footprint "antmicro-footprints:R_0402_1005Metric"
		(layer "F.Cu")
		(at 148.151999 93.000001 180)
		(descr "Resistor SMD 0402")
		(tags "resistor SMD 0402")
		(property "Reference" "R33"
			(at -3.448001 0.400001 180)
			(layer "F.SilkS")
			(effects
				(font
					(size 0.7 0.7)
					(thickness 0.15)
				)
				(justify right top)
			)
		)
		(property "Value" "R_158k_0402"
			(at -1.011843 1.772046 0)
			(layer "F.Fab")
			(effects
				(font
					(size 0.7 0.7)
					(thickness 0.15)
				)
				(justify right top)
			)
		)
		(property "Datasheet" "https://www.bourns.com/docs/product-datasheets/cr.pdf"
			(at 0 0 0)
			(layer "F.Fab")
			(hide yes)
			(effects
				(font
					(size 1.27 1.27)
					(thickness 0.15)
				)
			)
		)
		(property "Description" "SMD Chip Resistor, 158 kohm, ± 1%, 100 mW, 0402 [1005 Metric], Thick Film, Precision"
			(at 0 0 0)
			(layer "F.Fab")
			(hide yes)
			(effects
				(font
					(size 1.27 1.27)
					(thickness 0.15)
				)
			)
		)
		(property "MPN" "CR0402-FX-1583GLF"
			(at 0 0 180)
			(unlocked yes)
			(layer "F.Fab")
			(hide yes)
			(effects
				(font
					(size 1 1)
					(thickness 0.15)
				)
			)
		)
		(property "Manufacturer" "Bourns"
			(at 0 0 180)
			(unlocked yes)
			(layer "F.Fab")
			(hide yes)
			(effects
				(font
					(size 1 1)
					(thickness 0.15)
				)
			)
		)
		(property "License" "Apache-2.0"
			(at 0 0 180)
			(unlocked yes)
			(layer "F.Fab")
			(hide yes)
			(effects
				(font
					(size 1 1)
					(thickness 0.15)
				)
			)
		)
		(property "Author" "Antmicro"
			(at 0 0 180)
			(unlocked yes)
			(layer "F.Fab")
			(hide yes)
			(effects
				(font
					(size 1 1)
					(thickness 0.15)
				)
			)
		)
		(property "Val" "158k"
			(at 0 0 180)
			(unlocked yes)
			(layer "F.Fab")
			(hide yes)
			(effects
				(font
					(size 1 1)
					(thickness 0.15)
				)
			)
		)
		(property "Tolerance" "1%"
			(at 0 0 180)
			(unlocked yes)
			(layer "F.Fab")
			(hide yes)
			(effects
				(font
					(size 1 1)
					(thickness 0.15)
				)
			)
		)
		(sheetname "/USB-PD/")
		(sheetfile "usb-pd.kicad_sch")
		(attr smd)
		(fp_rect
			(start -0.925 -0.47)
			(end 0.925 0.47)
			(stroke
				(width 0.05)
				(type default)
			)
			(fill no)
			(layer "F.CrtYd")
		)
		(fp_rect
			(start -0.5 -0.25)
			(end 0.5 0.25)
			(stroke
				(width 0.15)
				(type solid)
			)
			(fill no)
			(layer "F.Fab")
		)
		(fp_text user "${REFERENCE}"
			(at 0 0 0)
			(layer "F.Fab")
			(effects
				(font
					(size 0.7 0.7)
					(thickness 0.15)
				)
				(justify right top)
			)
		)
		(fp_text user "Author: Antmicro"
			(at -0.95 4.169 0)
			(layer "F.Fab")
			(effects
				(font
					(size 0.7 0.7)
					(thickness 0.15)
				)
				(justify right top)
			)
		)
		(fp_text user "License: Apache-2.0"
			(at -0.949999 5.169 0)
			(layer "F.Fab")
			(effects
				(font
					(size 0.7 0.7)
					(thickness 0.15)
				)
				(justify right top)
			)
		)
		(pad "1" smd roundrect
			(at -0.48 0 180)
			(size 0.59 0.64)
			(layers "F.Cu" "F.Mask" "F.Paste")
			(roundrect_rratio 0.25)
			(net 66 "GND")
			(pintype "passive")
		)
		(pad "2" smd roundrect
			(at 0.48 0 180)
			(size 0.59 0.64)
			(layers "F.Cu" "F.Mask" "F.Paste")
			(roundrect_rratio 0.25)
			(net 157 "/USB-PD/12V_FSW")
			(pintype "passive")
		)
	)
	(gr_line
		(start 159.6 31)
		(end 101.6 31)
		(stroke
			(width 0.05)
			(type default)
		)
		(layer "Edge.Cuts")
	)
	(gr_line
		(start 101.6 31)
		(end 101.6 166)
		(stroke
			(width 0.05)
			(type default)
		)
		(layer "Edge.Cuts")
	)
	(gr_line
		(start 101.6 166)
		(end 159.6 166)
		(stroke
			(width 0.05)
			(type default)
		)
		(layer "Edge.Cuts")
	)
	(gr_line
		(start 159.6 166)
		(end 159.599999 31)
		(stroke
			(width 0.05)
			(type default)
		)
		(layer "Edge.Cuts")
	)
	(segment
		(start 114.774 115.1)
		(end 116.448 115.1)
		(width 0.5)
		(layer "F.Cu")
		(net 66)
	)
	(segment
		(start 116.198 85.102)
		(end 116.2 85.1)
		(width 0.2)
		(layer "F.Cu")
		(net 66)
	)
	(segment
		(start 114.774 84.102)
		(end 116.198 84.102)
		(width 0.2)
		(layer "F.Cu")
		(net 66)
	)
	(segment
		(start 114.773999 59.099999)
		(end 116.199 59.099999)
		(width 0.2)
		(layer "F.Cu")
		(net 66)
	)
	(segment
		(start 124.5 108.25)
		(end 126.25 108.25)
		(width 1)
		(layer "F.Cu")
		(net 66)
	)
	(segment
		(start 144.429001 108.970999)
		(end 145 108.4)
		(width 1)
		(layer "F.Cu")
		(net 66)
	)
	(segment
		(start 122.099999 113.8)
		(end 122.099999 114.6)
		(width 1)
		(layer "F.Cu")
		(net 66)
	)
	(segment
		(start 121.699998 114.2)
		(end 122.099999 113.8)
		(width 1)
		(layer "F.Cu")
		(net 66)
	)
	(segment
		(start 144.429001 135)
		(end 144.429001 133.429001)
		(width 1)
		(layer "F.Cu")
		(net 66)
	)
	(segment
		(start 107.574 74.102)
		(end 106.1 74.102)
		(width 0.2)
		(layer "F.Cu")
		(net 66)
	)
	(segment
		(start 141.48 122.152999)
		(end 141.48 121.622999)
		(width 0.3)
		(layer "F.Cu")
		(net 66)
	)
	(segment
		(start 122 123.6)
		(end 123.2 123.6)
		(width 1)
		(layer "F.Cu")
		(net 66)
	)
	(segment
		(start 104.599999 118.300001)
		(end 103.8 118.300001)
		(width 1)
		(layer "F.Cu")
		(net 66)
	)
	(segment
		(start 105 117.900001)
		(end 105 118.700001)
		(width 1)
		(layer "F.Cu")
		(net 66)
	)
	(segment
		(start 107.574 96.1)
		(end 106.1 96.1)
		(width 0.2)
		(layer "F.Cu")
		(net 66)
	)
	(segment
		(start 122.8 137.6)
		(end 123.2 137.2)
		(width 0.3)
		(layer "F.Cu")
		(net 66)
	)
	(segment
		(start 122.8 138.12)
		(end 122.8 137.6)
		(width 0.3)
		(layer "F.Cu")
		(net 66)
	)
	(segment
		(start 107.574 50.103)
		(end 106.1 50.103)
		(width 0.2)
		(layer "F.Cu")
		(net 66)
	)
	(segment
		(start 114.774 118.1)
		(end 116.448 118.1)
		(width 0.5)
		(layer "F.Cu")
		(net 66)
	)
	(segment
		(start 133.96 39.915)
		(end 135.015 39.915)
		(width 0.2)
		(layer "F.Cu")
		(net 66)
	)
	(segment
		(start 124.5 114.25)
		(end 126.25 114.25)
		(width 1)
		(layer "F.Cu")
		(net 66)
	)
	(segment
		(start 133.633499 72.45)
		(end 133.6265 72.443001)
		(width 0.2)
		(layer "F.Cu")
		(net 66)
	)
	(segment
		(start 123.6 123.2)
		(end 123.6 124)
		(width 1)
		(layer "F.Cu")
		(net 66)
	)
	(segment
		(start 134.6 45.935)
		(end 134.579 45.914)
		(width 0.125)
		(layer "F.Cu")
		(net 66)
	)
	(segment
		(start 114.773999 52.101999)
		(end 116.198 52.101999)
		(width 0.2)
		(layer "F.Cu")
		(net 66)
	)
	(segment
		(start 107.574 75.102)
		(end 106.1 75.102)
		(width 0.2)
		(layer "F.Cu")
		(net 66)
	)
	(segment
		(start 104.599999 118.300001)
		(end 105 117.900001)
		(width 1)
		(layer "F.Cu")
		(net 66)
	)
	(segment
		(start 107.574 82.101)
		(end 106.1 82.101)
		(width 0.2)
		(layer "F.Cu")
		(net 66)
	)
	(segment
		(start 116.199001 76.100999)
		(end 116.2 76.1)
		(width 0.2)
		(layer "F.Cu")
		(net 66)
	)
	(segment
		(start 134.6 46.614)
		(end 134.6 45.935)
		(width 0.125)
		(layer "F.Cu")
		(net 66)
	)
	(segment
		(start 122.3 38.115)
		(end 122.3 37.3)
		(width 0.125)
		(layer "F.Cu")
		(net 66)
	)
	(segment
		(start 145 108.4)
		(end 144 108.4)
		(width 1)
		(layer "F.Cu")
		(net 66)
	)
	(segment
		(start 114.774 91.101)
		(end 116.199 91.101)
		(width 0.2)
		(layer "F.Cu")
		(net 66)
	)
	(segment
		(start 107.574 118.1)
		(end 106 118.1)
		(width 0.5)
		(layer "F.Cu")
		(net 66)
	)
	(segment
		(start 149.737 57.855999)
		(end 149.737 58.526)
		(width 0.3)
		(layer "F.Cu")
		(net 66)
	)
	(segment
		(start 114.774001 85.102)
		(end 116.198 85.102)
		(width 0.2)
		(layer "F.Cu")
		(net 66)
	)
	(segment
		(start 114.774 68.101)
		(end 116.197999 68.101)
		(width 0.2)
		(layer "F.Cu")
		(net 66)
	)
	(segment
		(start 121.699998 114.2)
		(end 120.899999 114.2)
		(width 1)
		(layer "F.Cu")
		(net 66)
	)
	(segment
		(start 147.812 51.851001)
		(end 147.812 51.501)
		(width 0.25)
		(layer "F.Cu")
		(net 66)
	)
	(segment
		(start 124.203 131.627001)
		(end 124.203 132.572001)
		(width 0.3)
		(layer "F.Cu")
		(net 66)
	)
	(segment
		(start 107.574 78.102)
		(end 106.1 78.102)
		(width 0.2)
		(layer "F.Cu")
		(net 66)
	)
	(segment
		(start 107.574 86.102)
		(end 106.1 86.102)
		(width 0.2)
		(layer "F.Cu")
		(net 66)
	)
	(segment
		(start 135.6 108.8)
		(end 136.4 108.8)
		(width 0.3)
		(layer "F.Cu")
		(net 66)
	)
	(segment
		(start 144 42.05)
		(end 144 41.2)
		(width 0.125)
		(layer "F.Cu")
		(net 66)
	)
	(segment
		(start 121.7045 150.154999)
		(end 122.374999 150.154999)
		(width 0.2)
		(layer "F.Cu")
		(net 66)
	)
	(segment
		(start 104.599999 116.299999)
		(end 103.8 116.299999)
		(width 1)
		(layer "F.Cu")
		(net 66)
	)
	(segment
		(start 137.85 67.57)
		(end 137.85 66.916501)
		(width 0.2)
		(layer "F.Cu")
		(net 66)
	)
	(segment
		(start 120.14 35.195)
		(end 120.14 32.859998)
		(width 0.2)
		(layer "F.Cu")
		(net 66)
	)
	(segment
		(start 116.199 77.101)
		(end 116.2 77.1)
		(width 0.2)
		(layer "F.Cu")
		(net 66)
	)
	(segment
		(start 123.8 38.115)
		(end 123.8 37.3)
		(width 0.125)
		(layer "F.Cu")
		(net 66)
	)
	(segment
		(start 130.3 40.305)
		(end 130.3 41.1)
		(width 0.125)
		(layer "F.Cu")
		(net 66)
	)
	(segment
		(start 123.75 134.426002)
		(end 123.75 135.05)
		(width 0.3)
		(layer "F.Cu")
		(net 66)
	)
	(segment
		(start 141.003 119.905999)
		(end 141 119.902999)
		(width 0.3)
		(layer "F.Cu")
		(net 66)
	)
	(segment
		(start 148.311999 53.499999)
		(end 150 53.5)
		(width 0.25)
		(layer "F.Cu")
		(net 66)
	)
	(segment
		(start 127.298001 43)
		(end 127.298 42.286999)
		(width 0.125)
		(layer "F.Cu")
		(net 66)
	)
	(segment
		(start 114.774001 80.101)
		(end 116.199 80.101)
		(width 0.2)
		(layer "F.Cu")
		(net 66)
	)
	(segment
		(start 107.574 69.101)
		(end 106.1 69.101)
		(width 0.2)
		(layer "F.Cu")
		(net 66)
	)
	(segment
		(start 116.198001 81.101999)
		(end 116.2 81.1)
		(width 0.2)
		(layer "F.Cu")
		(net 66)
	)
	(segment
		(start 135.452999 108.652999)
		(end 135.6 108.8)
		(width 0.3)
		(layer "F.Cu")
		(net 66)
	)
	(segment
		(start 144.482 95.55)
		(end 144.481999 96.219999)
		(width 0.3)
		(layer "F.Cu")
		(net 66)
	)
	(segment
		(start 148.631999 90)
		(end 149.302 90.000001)
		(width 0.3)
		(layer "F.Cu")
		(net 66)
	)
	(segment
		(start 131.8 40.305)
		(end 131.8 41.1)
		(width 0.125)
		(layer "F.Cu")
		(net 66)
	)
	(segment
		(start 121.699998 117.4)
		(end 122.099999 117)
		(width 1)
		(layer "F.Cu")
		(net 66)
	)
	(segment
		(start 116.199 91.101)
		(end 116.2 91.1)
		(width 0.2)
		(layer "F.Cu")
		(net 66)
	)
	(segment
		(start 116.198999 63.1)
		(end 116.199999 63.099)
		(width 0.2)
		(layer "F.Cu")
		(net 66)
	)
	(segment
		(start 137.033499 72.45)
		(end 137.0265 72.443001)
		(width 0.2)
		(layer "F.Cu")
		(net 66)
	)
	(segment
		(start 139.9 63.7)
		(end 139.9 63.403)
		(width 0.2)
		(layer "F.Cu")
		(net 66)
	)
	(segment
		(start 135.452999 107.7)
		(end 135.452999 108.652999)
		(width 0.3)
		(layer "F.Cu")
		(net 66)
	)
	(segment
		(start 155.37 36.47)
		(end 155.3 36.4)
		(width 0.3)
		(layer "F.Cu")
		(net 66)
	)
	(segment
		(start 116.199 47.100999)
		(end 116.199999 47.1)
		(width 0.2)
		(layer "F.Cu")
		(net 66)
	)
	(segment
		(start 116.199001 43.100998)
		(end 116.2 43.099999)
		(width 0.2)
		(layer "F.Cu")
		(net 66)
	)
	(segment
		(start 146.48 64)
		(end 147.2 64)
		(width 0.125)
		(layer "F.Cu")
		(net 66)
	)
	(segment
		(start 144.25 94.272998)
		(end 144.25 92.199999)
		(width 0.3)
		(layer "F.Cu")
		(net 66)
	)
	(segment
		(start 141 145.74)
		(end 141 144.5)
		(width 0.3)
		(layer "F.Cu")
		(net 66)
	)
	(segment
		(start 114.774 104.1)
		(end 116.2 104.1)
		(width 0.2)
		(layer "F.Cu")
		(net 66)
	)
	(segment
		(start 148.631998 97)
		(end 149.301998 97)
		(width 0.3)
		(layer "F.Cu")
		(net 66)
	)
	(segment
		(start 130.298 43)
		(end 130.298 42.287)
		(width 0.125)
		(layer "F.Cu")
		(net 66)
	)
	(segment
		(start 129.8 38.115)
		(end 129.8 37.3)
		(width 0.125)
		(layer "F.Cu")
		(net 66)
	)
	(segment
		(start 137.6995 72.45)
		(end 137.033499 72.45)
		(width 0.2)
		(layer "F.Cu")
		(net 66)
	)
	(segment
		(start 155.37 38.87)
		(end 155.3 38.8)
		(width 0.3)
		(layer "F.Cu")
		(net 66)
	)
	(segment
		(start 139.62 60)
		(end 138.9 60)
		(width 0.2)
		(layer "F.Cu")
		(net 66)
	)
	(segment
		(start 124.203 130.203)
		(end 124.2 130.2)
		(width 0.3)
		(layer "F.Cu")
		(net 66)
	)
	(segment
		(start 107.574 93.101)
		(end 106.1 93.101)
		(width 0.2)
		(layer "F.Cu")
		(net 66)
	)
	(segment
		(start 119.4 129.8)
		(end 120.019999 129.799999)
		(width 0.2)
		(layer "F.Cu")
		(net 66)
	)
	(segment
		(start 131.3 38.115)
		(end 131.3 37.3)
		(width 0.125)
		(layer "F.Cu")
		(net 66)
	)
	(segment
		(start 114.774 43.100998)
		(end 116.199001 43.100998)
		(width 0.2)
		(layer "F.Cu")
		(net 66)
	)
	(segment
		(start 114.774 44.100999)
		(end 116.199 44.100999)
		(width 0.2)
		(layer "F.Cu")
		(net 66)
	)
	(segment
		(start 139 63.75)
		(end 139.85 63.75)
		(width 0.2)
		(layer "F.Cu")
		(net 66)
	)
	(segment
		(start 137.85 66.916501)
		(end 137.8265 66.893001)
		(width 0.2)
		(layer "F.Cu")
		(net 66)
	)
	(segment
		(start 141.48 146.75)
		(end 141.48 146.22)
		(width 0.3)
		(layer "F.Cu")
		(net 66)
	)
	(segment
		(start 137.6 108.8)
		(end 138.03 108.37)
		(width 0.3)
		(layer "F.Cu")
		(net 66)
	)
	(segment
		(start 114.774 88.101)
		(end 116.199 88.101)
		(width 0.2)
		(layer "F.Cu")
		(net 66)
	)
	(segment
		(start 138.03 108.37)
		(end 138.499999 108.37)
		(width 0.3)
		(layer "F.Cu")
		(net 66)
	)
	(segment
		(start 131.24 153.999999)
		(end 130.22 153.999999)
		(width 0.125)
		(layer "F.Cu")
		(net 66)
	)
	(segment
		(start 114.773999 55.102)
		(end 116.197999 55.102)
		(width 0.2)
		(layer "F.Cu")
		(net 66)
	)
	(segment
		(start 140.5 41.774)
		(end 140.8 41.474)
		(width 0.2)
		(layer "F.Cu")
		(net 66)
	)
	(segment
		(start 122.8 40.305)
		(end 122.8 41.1)
		(width 0.125)
		(layer "F.Cu")
		(net 66)
	)
	(segment
		(start 125.332999 152.556999)
		(end 125.332999 153.326998)
		(width 0.15)
		(layer "F.Cu")
		(net 66)
	)
	(segment
		(start 104.599999 116.299999)
		(end 105 116.699999)
		(width 1)
		(layer "F.Cu")
		(net 66)
	)
	(segment
		(start 134.6 47.386)
		(end 134.6 46.614)
		(width 0.2)
		(layer "F.Cu")
		(net 66)
	)
	(segment
		(start 107.574 108.1)
		(end 106.1 108.1)
		(width 0.2)
		(layer "F.Cu")
		(net 66)
	)
	(segment
		(start 114.773999 64.100999)
		(end 116.198 64.100999)
		(width 0.2)
		(layer "F.Cu")
		(net 66)
	)
	(segment
		(start 143.5 144.52)
		(end 142.117 144.52)
		(width 0.3)
		(layer "F.Cu")
		(net 66)
	)
	(segment
		(start 124.5 116)
		(end 126.25 116)
		(width 1)
		(layer "F.Cu")
		(net 66)
	)
	(segment
		(start 144.25 95.317999)
		(end 144.482 95.55)
		(width 0.2)
		(layer "F.Cu")
		(net 66)
	)
	(segment
		(start 116.199 88.101)
		(end 116.2 88.1)
		(width 0.2)
		(layer "F.Cu")
		(net 66)
	)
	(segment
		(start 145 133)
		(end 144 133)
		(width 1)
		(layer "F.Cu")
		(net 66)
	)
	(segment
		(start 133.96 32.460001)
		(end 133.499999 32)
		(width 0.2)
		(layer "F.Cu")
		(net 66)
	)
	(segment
		(start 116.198 84.102)
		(end 116.2 84.1)
		(width 0.2)
		(layer "F.Cu")
		(net 66)
	)
	(segment
		(start 107.574 61.102)
		(end 106.1 61.102)
		(width 0.2)
		(layer "F.Cu")
		(net 66)
	)
	(segment
		(start 127.581999 150.426999)
		(end 127.581999 149.656999)
		(width 0.3)
		(layer "F.Cu")
		(net 66)
	)
	(segment
		(start 116.198999 60.1)
		(end 116.199999 60.099)
		(width 0.2)
		(layer "F.Cu")
		(net 66)
	)
	(segment
		(start 142.117 144.52)
		(end 142.1 144.503)
		(width 0.3)
		(layer "F.Cu")
		(net 66)
	)
	(segment
		(start 107.574 54.102)
		(end 106.1 54.102)
		(width 0.2)
		(layer "F.Cu")
		(net 66)
	)
	(segment
		(start 134.651 66.968501)
		(end 134.676501 66.943001)
		(width 0.2)
		(layer "F.Cu")
		(net 66)
	)
	(segment
		(start 147.737 57.856)
		(end 147.737 58.525999)
		(width 0.3)
		(layer "F.Cu")
		(net 66)
	)
	(segment
		(start 124.882999 149.534998)
		(end 125.574998 149.534999)
		(width 0.3)
		(layer "F.Cu")
		(net 66)
	)
	(segment
		(start 121.699998 117.4)
		(end 120.899999 117.4)
		(width 1)
		(layer "F.Cu")
		(net 66)
	)
	(segment
		(start 134.651 67.57)
		(end 134.651 66.968501)
		(width 0.2)
		(layer "F.Cu")
		(net 66)
	)
	(segment
		(start 129.72 157.448999)
		(end 129.771 157.499999)
		(width 0.125)
		(layer "F.Cu")
		(net 66)
	)
	(segment
		(start 126.9 129.950001)
		(end 126.9 128.750001)
		(width 1)
		(layer "F.Cu")
		(net 66)
	)
	(segment
		(start 114.774 40.101)
		(end 116.199 40.101)
		(width 0.2)
		(layer "F.Cu")
		(net 66)
	)
	(segment
		(start 141.447001 118.955998)
		(end 141 119.402999)
		(width 0.3)
		(layer "F.Cu")
		(net 66)
	)
	(segment
		(start 142.1 118.955998)
		(end 141.447001 118.955998)
		(width 0.3)
		(layer "F.Cu")
		(net 66)
	)
	(segment
		(start 138.579 45.947999)
		(end 138.558 45.926999)
		(width 0.125)
		(layer "F.Cu")
		(net 66)
	)
	(segment
		(start 141 121.142999)
		(end 141 119.902999)
		(width 0.3)
		(layer "F.Cu")
		(net 66)
	)
	(segment
		(start 114.774 94.100999)
		(end 116.199001 94.100999)
		(width 0.2)
		(layer "F.Cu")
		(net 66)
	)
	(segment
		(start 139.3 42.42)
		(end 139.3 41.574)
		(width 0.2)
		(layer "F.Cu")
		(net 66)
	)
	(segment
		(start 141.199501 72.6)
		(end 141.049501 72.45)
		(width 0.2)
		(layer "F.Cu")
		(net 66)
	)
	(segment
		(start 116.199 80.101)
		(end 116.2 80.1)
		(width 0.2)
		(layer "F.Cu")
		(net 66)
	)
	(segment
		(start 143.5 119.922999)
		(end 142.117 119.922999)
		(width 0.3)
		(layer "F.Cu")
		(net 66)
	)
	(segment
		(start 114.774001 107.1)
		(end 116.2 107.1)
		(width 0.2)
		(layer "F.Cu")
		(net 66)
	)
	(segment
		(start 153.737002 57.856)
		(end 153.737 58.525999)
		(width 0.3)
		(layer "F.Cu")
		(net 66)
	)
	(segment
		(start 122.073999 147.855999)
		(end 122.074999 147.855)
		(width 0.2)
		(layer "F.Cu")
		(net 66)
	)
	(segment
		(start 116.197999 56.102)
		(end 116.199999 56.1)
		(width 0.2)
		(layer "F.Cu")
		(net 66)
	)
	(segment
		(start 118.815 39.915)
		(end 118.8 39.9)
		(width 0.2)
		(layer "F.Cu")
		(net 66)
	)
	(segment
		(start 142.1 119.905999)
		(end 141.003 119.905999)
		(width 0.3)
		(layer "F.Cu")
		(net 66)
	)
	(segment
		(start 114.774 63.1)
		(end 116.198999 63.1)
		(width 0.2)
		(layer "F.Cu")
		(net 66)
	)
	(segment
		(start 146.025 91.997)
		(end 144.947 91.997)
		(width 0.2)
		(layer "F.Cu")
		(net 66)
	)
	(segment
		(start 114.774 73.101)
		(end 116.199 73.101)
		(width 0.2)
		(layer "F.Cu")
		(net 66)
	)
	(segment
		(start 114.774 56.102)
		(end 116.197999 56.102)
		(width 0.2)
		(layer "F.Cu")
		(net 66)
	)
	(segment
		(start 116.199 40.101)
		(end 116.2 40.1)
		(width 0.2)
		(layer "F.Cu")
		(net 66)
	)
	(segment
		(start 107.574 57.103)
		(end 106.1 57.103)
		(width 0.2)
		(layer "F.Cu")
		(net 66)
	)
	(segment
		(start 114.773999 60.1)
		(end 116.198999 60.1)
		(width 0.2)
		(layer "F.Cu")
		(net 66)
	)
	(segment
		(start 130.569 157.499999)
		(end 130.62 157.448999)
		(width 0.125)
		(layer "F.Cu")
		(net 66)
	)
	(segment
		(start 136.439998 107.663002)
		(end 136.403 107.7)
		(width 0.3)
		(layer "F.Cu")
		(net 66)
	)
	(segment
		(start 123.75 133.025001)
		(end 123.75 134.426002)
		(width 0.3)
		(layer "F.Cu")
		(net 66)
	)
	(segment
		(start 114.774001 98.1)
		(end 116.2 98.1)
		(width 0.2)
		(layer "F.Cu")
		(net 66)
	)
	(segment
		(start 127.298001 43)
		(end 127.298 43.772)
		(width 0.125)
		(layer "F.Cu")
		(net 66)
	)
	(segment
		(start 107.574 105.1)
		(end 106.1 105.1)
		(width 0.2)
		(layer "F.Cu")
		(net 66)
	)
	(segment
		(start 148.312 52.000998)
		(end 147.962 52.001)
		(width 0.25)
		(layer "F.Cu")
		(net 66)
	)
	(segment
		(start 107.574 100.1)
		(end 106.1 100.1)
		(width 0.2)
		(layer "F.Cu")
		(net 66)
	)
	(segment
		(start 146.48 63)
		(end 147.2 63)
		(width 0.125)
		(layer "F.Cu")
		(net 66)
	)
	(segment
		(start 122.073999 148.704998)
		(end 122.073999 147.855999)
		(width 0.2)
		(layer "F.Cu")
		(net 66)
	)
	(segment
		(start 116.199 71.100999)
		(end 116.2 71.099999)
		(width 0.2)
		(layer "F.Cu")
		(net 66)
	)
	(segment
		(start 121.699998 117.4)
		(end 122.099999 117.8)
		(width 1)
		(layer "F.Cu")
		(net 66)
	)
	(segment
		(start 107.574 42.102)
		(end 106.1 42.102)
		(width 0.2)
		(layer "F.Cu")
		(net 66)
	)
	(segment
		(start 146.082 55.000999)
		(end 145.412 55.001)
		(width 0.3)
		(layer "F.Cu")
		(net 66)
	)
	(segment
		(start 139.9 63.403)
		(end 140.303 63)
		(width 0.2)
		(layer "F.Cu")
		(net 66)
	)
	(segment
		(start 136.403 108.797)
		(end 136.4 108.8)
		(width 0.3)
		(layer "F.Cu")
		(net 66)
	)
	(segment
		(start 142.1 144.503)
		(end 141.003 144.503)
		(width 0.3)
		(layer "F.Cu")
		(net 66)
	)
	(segment
		(start 146.082 53.001)
		(end 145.412 53.000999)
		(width 0.3)
		(layer "F.Cu")
		(net 66)
	)
	(segment
		(start 148.632 92)
		(end 149.302 92.000001)
		(width 0.3)
		(layer "F.Cu")
		(net 66)
	)
	(segment
		(start 124.5 111.75)
		(end 126.25 111.75)
		(width 1)
		(layer "F.Cu")
		(net 66)
	)
	(segment
		(start 139 63.75)
		(end 138.25 63.75)
		(width 0.2)
		(layer "F.Cu")
		(net 66)
	)
	(segment
		(start 116.198 64.100999)
		(end 116.199999 64.099)
		(width 0.2)
		(layer "F.Cu")
		(net 66)
	)
	(segment
		(start 139.27 41.544)
		(end 139.2 41.474)
		(width 0.3)
		(layer "F.Cu")
		(net 66)
	)
	(segment
		(start 114.774 102.100001)
		(end 116.2 102.1)
		(width 0.2)
		(layer "F.Cu")
		(net 66)
	)
	(segment
		(start 135.015 39.915)
		(end 135.3 40.2)
		(width 0.2)
		(layer "F.Cu")
		(net 66)
	)
	(segment
		(start 114.773999 47.100999)
		(end 116.199 47.100999)
		(width 0.2)
		(layer "F.Cu")
		(net 66)
	)
	(segment
		(start 124.5 110)
		(end 126.25 110)
		(width 1)
		(layer "F.Cu")
		(net 66)
	)
	(segment
		(start 114.774 99.1)
		(end 116.2 99.1)
		(width 0.2)
		(layer "F.Cu")
		(net 66)
	)
	(segment
		(start 120.14 39.915)
		(end 118.815 39.915)
		(width 0.2)
		(layer "F.Cu")
		(net 66)
	)
	(segment
		(start 111.1735 35)
		(end 114.4 35)
		(width 0.3)
		(layer "F.Cu")
		(net 66)
	)
	(segment
		(start 140.5 42.5)
		(end 140.5 41.774)
		(width 0.2)
		(layer "F.Cu")
		(net 66)
	)
	(segment
		(start 147.671998 95.999999)
		(end 147.002 96)
		(width 0.3)
		(layer "F.Cu")
		(net 66)
	)
	(segment
		(start 144.429001 108.829001)
		(end 144 108.4)
		(width 1)
		(layer "F.Cu")
		(net 66)
	)
	(segment
		(start 147.67 41.37)
		(end 147.6 41.3)
		(width 0.3)
		(layer "F.Cu")
		(net 66)
	)
	(segment
		(start 144.429001 110.4)
		(end 144.429001 108.829001)
		(width 1)
		(layer "F.Cu")
		(net 66)
	)
	(segment
		(start 141.003 144.503)
		(end 141 144.5)
		(width 0.3)
		(layer "F.Cu")
		(net 66)
	)
	(segment
		(start 136.439998 106.35)
		(end 136.439998 107.663002)
		(width 0.3)
		(layer "F.Cu")
		(net 66)
	)
	(segment
		(start 116.199 95.101)
		(end 116.2 95.1)
		(width 0.2)
		(layer "F.Cu")
		(net 66)
	)
	(segment
		(start 138.579 47.399)
		(end 138.579 46.627)
		(width 0.2)
		(layer "F.Cu")
		(net 66)
	)
	(segment
		(start 123.75 131.627001)
		(end 123.75 130.55)
		(width 0.3)
		(layer "F.Cu")
		(net 66)
	)
	(segment
		(start 122.099999 117)
		(end 122.099999 117.8)
		(width 1)
		(layer "F.Cu")
		(net 66)
	)
	(segment
		(start 107.574 92.101)
		(end 106.1 92.101)
		(width 0.2)
		(layer "F.Cu")
		(net 66)
	)
	(segment
		(start 126.8 38.115)
		(end 126.8 37.3)
		(width 0.125)
		(layer "F.Cu")
		(net 66)
	)
	(segment
		(start 123.75 135.05)
		(end 123.2 135.6)
		(width 0.3)
		(layer "F.Cu")
		(net 66)
	)
	(segment
		(start 114.774 51.101)
		(end 116.198999 51.101)
		(width 0.2)
		(layer "F.Cu")
		(net 66)
	)
	(segment
		(start 107.574 45.101)
		(end 106.1 45.101)
		(width 0.2)
		(layer "F.Cu")
		(net 66)
	)
	(segment
		(start 134.349001 72.45)
		(end 133.633499 72.45)
		(width 0.2)
		(layer "F.Cu")
		(net 66)
	)
	(segment
		(start 144.250001 94.273)
		(end 144.25 95.317999)
		(width 0.2)
		(layer "F.Cu")
		(net 66)
	)
	(segment
		(start 107.574 58.103)
		(end 106.1 58.103)
		(width 0.2)
		(layer "F.Cu")
		(net 66)
	)
	(segment
		(start 144.429001 133.429001)
		(end 144 133)
		(width 1)
		(layer "F.Cu")
		(net 66)
	)
	(segment
		(start 144.25 92.199999)
		(end 144.7 91.749999)
		(width 0.3)
		(layer "F.Cu")
		(net 66)
	)
	(segment
		(start 128.900001 129.950001)
		(end 128.900001 128.750001)
		(width 1)
		(layer "F.Cu")
		(net 66)
	)
	(segment
		(start 107.574 89.101)
		(end 106.1 89.101)
		(width 0.2)
		(layer "F.Cu")
		(net 66)
	)
	(segment
		(start 131.239999 152.999999)
		(end 130.220001 152.999999)
		(width 0.125)
		(layer "F.Cu")
		(net 66)
	)
	(segment
		(start 129.771 157.499999)
		(end 130.569 157.499999)
		(width 0.125)
		(layer "F.Cu")
		(net 66)
	)
	(segment
		(start 105 115.899999)
		(end 105 116.699999)
		(width 1)
		(layer "F.Cu")
		(net 66)
	)
	(segment
		(start 142.1 143.552999)
		(end 141.447001 143.552999)
		(width 0.3)
		(layer "F.Cu")
		(net 66)
	)
	(segment
		(start 107.574 49.103)
		(end 106.1 49.103)
		(width 0.2)
		(layer "F.Cu")
		(net 66)
	)
	(segment
		(start 107.574 38.101)
		(end 106.1 38.101)
		(width 0.2)
		(layer "F.Cu")
		(net 66)
	)
	(segment
		(start 107.574 71.101)
		(end 106.1 71.101)
		(width 0.2)
		(layer "F.Cu")
		(net 66)
	)
	(segment
		(start 116.197999 55.102)
		(end 116.199999 55.1)
		(width 0.2)
		(layer "F.Cu")
		(net 66)
	)
	(segment
		(start 116.197999 67.101)
		(end 116.199999 67.099)
		(width 0.2)
		(layer "F.Cu")
		(net 66)
	)
	(segment
		(start 124.298 43.772)
		(end 124.298 43)
		(width 0.125)
		(layer "F.Cu")
		(net 66)
	)
	(segment
		(start 128.8 40.305)
		(end 128.8 41.1)
		(width 0.125)
		(layer "F.Cu")
		(net 66)
	)
	(segment
		(start 104.599999 116.299999)
		(end 105 115.899999)
		(width 1)
		(layer "F.Cu")
		(net 66)
	)
	(segment
		(start 107.574 97.1)
		(end 106.1 97.1)
		(width 0.2)
		(layer "F.Cu")
		(net 66)
	)
	(segment
		(start 116.199 44.100999)
		(end 116.2 44.099999)
		(width 0.2)
		(layer "F.Cu")
		(net 66)
	)
	(segment
		(start 120.02 133.8)
		(end 119.4 133.8)
		(width 0.2)
		(layer "F.Cu")
		(net 66)
	)
	(segment
		(start 107.574 65.101)
		(end 106.1 65.101)
		(width 0.2)
		(layer "F.Cu")
		(net 66)
	)
	(segment
		(start 107.574 102.1)
		(end 106.1 102.1)
		(width 0.2)
		(layer "F.Cu")
		(net 66)
	)
	(segment
		(start 124.203 131.627001)
		(end 124.203 130.203)
		(width 0.3)
		(layer "F.Cu")
		(net 66)
	)
	(segment
		(start 107.574 53.102)
		(end 106.1 53.102)
		(width 0.2)
		(layer "F.Cu")
		(net 66)
	)
	(segment
		(start 139.3 41.574)
		(end 139.2 41.474)
		(width 0.2)
		(layer "F.Cu")
		(net 66)
	)
	(segment
		(start 123.75 130.55)
		(end 123.4 130.2)
		(width 0.3)
		(layer "F.Cu")
		(net 66)
	)
	(segment
		(start 107.574 83.101)
		(end 106.1 83.101)
		(width 0.2)
		(layer "F.Cu")
		(net 66)
	)
	(segment
		(start 139.85 63.75)
		(end 139.9 63.7)
		(width 0.2)
		(layer "F.Cu")
		(net 66)
	)
	(segment
		(start 141 119.402999)
		(end 141 119.902999)
		(width 0.3)
		(layer "F.Cu")
		(net 66)
	)
	(segment
		(start 150 53.5)
		(end 150.250001 53.25)
		(width 0.25)
		(layer "F.Cu")
		(net 66)
	)
	(segment
		(start 114.773999 48.101)
		(end 116.198999 48.101)
		(width 0.2)
		(layer "F.Cu")
		(net 66)
	)
	(segment
		(start 138.579 46.627)
		(end 138.579 45.947999)
		(width 0.125)
		(layer "F.Cu")
		(net 66)
	)
	(segment
		(start 114.774 76.100999)
		(end 116.199001 76.100999)
		(width 0.2)
		(layer "F.Cu")
		(net 66)
	)
	(segment
		(start 130.298 43)
		(end 130.297999 43.772)
		(width 0.125)
		(layer "F.Cu")
		(net 66)
	)
	(segment
		(start 116.199001 94.100999)
		(end 116.2 94.1)
		(width 0.2)
		(layer "F.Cu")
		(net 66)
	)
	(segment
		(start 122.8 137.6)
		(end 122.4 137.2)
		(width 0.3)
		(layer "F.Cu")
		(net 66)
	)
	(segment
		(start 111.174 124.1)
		(end 111.174 126.574)
		(width 0.3)
		(layer "F.Cu")
		(net 66)
	)
	(segment
		(start 104.599999 118.300001)
		(end 105 118.700001)
		(width 1)
		(layer "F.Cu")
		(net 66)
	)
	(segment
		(start 133.96 35.195)
		(end 133.96 32.460001)
		(width 0.2)
		(layer "F.Cu")
		(net 66)
	)
	(segment
		(start 116.197999 68.101)
		(end 116.199999 68.099)
		(width 0.2)
		(layer "F.Cu")
		(net 66)
	)
	(segment
		(start 128.3 38.115)
		(end 128.3 37.3)
		(width 0.125)
		(layer "F.Cu")
		(net 66)
	)
	(segment
		(start 107.574 66.101)
		(end 106.1 66.101)
		(width 0.2)
		(layer "F.Cu")
		(net 66)
	)
	(segment
		(start 144.429001 110.4)
		(end 144.429001 108.970999)
		(width 1)
		(layer "F.Cu")
		(net 66)
	)
	(segment
		(start 142.579 45.866998)
		(end 142.581 45.864998)
		(width 0.125)
		(layer "F.Cu")
		(net 66)
	)
	(segment
		(start 141.48 146.22)
		(end 141 145.74)
		(width 0.3)
		(layer "F.Cu")
		(net 66)
	)
	(segment
		(start 116.198 52.101999)
		(end 116.199999 52.1)
		(width 0.2)
		(layer "F.Cu")
		(net 66)
	)
	(segment
		(start 107.574 41.102)
		(end 106.1 41.102)
		(width 0.2)
		(layer "F.Cu")
		(net 66)
	)
	(segment
		(start 128.332999 151.596999)
		(end 128.332999 150.826999)
		(width 0.15)
		(layer "F.Cu")
		(net 66)
	)
	(segment
		(start 141 144)
		(end 141 144.5)
		(width 0.3)
		(layer "F.Cu")
		(net 66)
	)
	(segment
		(start 141.447001 143.552999)
		(end 141 144)
		(width 0.3)
		(layer "F.Cu")
		(net 66)
	)
	(segment
		(start 147.672 95.000001)
		(end 147.001999 95)
		(width 0.3)
		(layer "F.Cu")
		(net 66)
	)
	(segment
		(start 124.298 43)
		(end 124.298 42.287)
		(width 0.125)
		(layer "F.Cu")
		(net 66)
	)
	(segment
		(start 127.3 40.305)
		(end 127.3 41.1)
		(width 0.125)
		(layer "F.Cu")
		(net 66)
	)
	(segment
		(start 107.574 62.102)
		(end 106.1 62.102)
		(width 0.2)
		(layer "F.Cu")
		(net 66)
	)
	(segment
		(start 148.631999 92.999999)
		(end 149.302 92.999999)
		(width 0.3)
		(layer "F.Cu")
		(net 66)
	)
	(segment
		(start 142.579 46.527999)
		(end 142.579 45.866998)
		(width 0.125)
		(layer "F.Cu")
		(net 66)
	)
	(segment
		(start 123.2 123.6)
		(end 123.6 124)
		(width 1)
		(layer "F.Cu")
		(net 66)
	)
	(segment
		(start 147.962 52.001)
		(end 147.812 51.851001)
		(width 0.25)
		(layer "F.Cu")
		(net 66)
	)
	(segment
		(start 146.081999 52.001)
		(end 145.412 52.001)
		(width 0.3)
		(layer "F.Cu")
		(net 66)
	)
	(segment
		(start 120.02 130.8)
		(end 119.4 130.8)
		(width 0.2)
		(layer "F.Cu")
		(net 66)
	)
	(segment
		(start 142.579 47.299999)
		(end 142.579 46.528)
		(width 0.2)
		(layer "F.Cu")
		(net 66)
	)
	(segment
		(start 124.5 117.75)
		(end 126.25 117.75)
		(width 1)
		(layer "F.Cu")
		(net 66)
	)
	(segment
		(start 116.199 73.101)
		(end 116.2 73.1)
		(width 0.2)
		(layer "F.Cu")
		(net 66)
	)
	(segment
		(start 114.774 81.101999)
		(end 116.198001 81.101999)
		(width 0.2)
		(layer "F.Cu")
		(net 66)
	)
	(segment
		(start 141.48 121.622999)
		(end 141 121.142999)
		(width 0.3)
		(layer "F.Cu")
		(net 66)
	)
	(segment
		(start 146.082 54.001)
		(end 145.412 54.000999)
		(width 0.3)
		(layer "F.Cu")
		(net 66)
	)
	(segment
		(start 120.14 32.859998)
		(end 120.999998 32)
		(width 0.2)
		(layer "F.Cu")
		(net 66)
	)
	(segment
		(start 144.429001 135)
		(end 144.429001 133.570999)
		(width 1)
		(layer "F.Cu")
		(net 66)
	)
	(segment
		(start 124.203 132.572001)
		(end 123.75 133.025001)
		(width 0.3)
		(layer "F.Cu")
		(net 66)
	)
	(segment
		(start 141.8 72.6)
		(end 141.199501 72.6)
		(width 0.2)
		(layer "F.Cu")
		(net 66)
	)
	(segment
		(start 107.574 46.101)
		(end 106.1 46.101)
		(width 0.2)
		(layer "F.Cu")
		(net 66)
	)
	(segment
		(start 130.9 129.950001)
		(end 130.9 128.750001)
		(width 1)
		(layer "F.Cu")
		(net 66)
	)
	(segment
		(start 136.403 107.7)
		(end 136.403 108.797)
		(width 0.3)
		(layer "F.Cu")
		(net 66)
	)
	(segment
		(start 114.774 77.101)
		(end 116.199 77.101)
		(width 0.2)
		(layer "F.Cu")
		(net 66)
	)
	(segment
		(start 107.574 79.102)
		(end 106.1 79.102)
		(width 0.2)
		(layer "F.Cu")
		(net 66)
	)
	(segment
		(start 116.198999 51.101)
		(end 116.199999 51.1)
		(width 0.2)
		(layer "F.Cu")
		(net 66)
	)
	(segment
		(start 116.198999 48.101)
		(end 116.199999 48.1)
		(width 0.2)
		(layer "F.Cu")
		(net 66)
	)
	(segment
		(start 122.352 133.025001)
		(end 123.75 133.025001)
		(width 0.3)
		(layer "F.Cu")
		(net 66)
	)
	(segment
		(start 114.773999 67.101)
		(end 116.197999 67.101)
		(width 0.2)
		(layer "F.Cu")
		(net 66)
	)
	(segment
		(start 148.312001 53.5)
		(end 147.576001 53.5)
		(width 0.2)
		(layer "F.Cu")
		(net 66)
	)
	(segment
		(start 151.737 57.856)
		(end 151.737 58.525999)
		(width 0.3)
		(layer "F.Cu")
		(net 66)
	)
	(segment
		(start 114.774 95.101)
		(end 116.199 95.101)
		(width 0.2)
		(layer "F.Cu")
		(net 66)
	)
	(segment
		(start 125.8 40.305)
		(end 125.8 41.1)
		(width 0.125)
		(layer "F.Cu")
		(net 66)
	)
	(segment
		(start 120.02 134.8)
		(end 119.4 134.8)
		(width 0.2)
		(layer "F.Cu")
		(net 66)
	)
	(segment
		(start 148.631999 89)
		(end 149.302 89)
		(width 0.3)
		(layer "F.Cu")
		(net 66)
	)
	(segment
		(start 123.2 123.6)
		(end 123.6 123.2)
		(width 1)
		(layer "F.Cu")
		(net 66)
	)
	(segment
		(start 114.774 71.100999)
		(end 116.199 71.100999)
		(width 0.2)
		(layer "F.Cu")
		(net 66)
	)
	(segment
		(start 142.117 119.922999)
		(end 142.1 119.905999)
		(width 0.3)
		(layer "F.Cu")
		(net 66)
	)
	(segment
		(start 123.75 131.627001)
		(end 123.75 133.025001)
		(width 0.3)
		(layer "F.Cu")
		(net 66)
	)
	(segment
		(start 121.699998 114.2)
		(end 122.099999 114.6)
		(width 1)
		(layer "F.Cu")
		(net 66)
	)
	(segment
		(start 144.429001 133.570999)
		(end 145 133)
		(width 1)
		(layer "F.Cu")
		(net 66)
	)
	(segment
		(start 124.3 40.305)
		(end 124.3 41.1)
		(width 0.125)
		(layer "F.Cu")
		(net 66)
	)
	(segment
		(start 116.199 59.099999)
		(end 116.199999 59.099)
		(width 0.2)
		(layer "F.Cu")
		(net 66)
	)
	(segment
		(start 136.4 108.8)
		(end 137.6 108.8)
		(width 0.3)
		(layer "F.Cu")
		(net 66)
	)
	(segment
		(start 111.174 126.574)
		(end 111.2 126.6)
		(width 0.3)
		(layer "F.Cu")
		(net 66)
	)
	(segment
		(start 125.3 38.115)
		(end 125.3 37.3)
		(width 0.125)
		(layer "F.Cu")
		(net 66)
	)
	(via
		(at 147.737 58.525999)
		(size 0.55)
		(drill 0.15)
		(layers "F.Cu" "B.Cu")
		(net 66)
	)
	(via
		(at 130.6 90.5)
		(size 0.45)
		(drill 0.1)
		(layers "F.Cu" "B.Cu")
		(free yes)
		(net 66)
	)
	(via
		(at 111 32)
		(size 0.45)
		(drill 0.1)
		(layers "F.Cu" "B.Cu")
		(net 66)
	)
	(via
		(at 158.5 98)
		(size 0.45)
		(drill 0.1)
		(layers "F.Cu" "B.Cu")
		(net 66)
	)
	(via
		(at 158.5 138)
		(size 0.45)
		(drill 0.1)
		(layers "F.Cu" "B.Cu")
		(net 66)
	)
	(via
		(at 116.199999 56.1)
		(size 0.45)
		(drill 0.1)
		(layers "F.Cu" "B.Cu")
		(net 66)
	)
	(via
		(at 149.5 116.25)
		(size 0.45)
		(drill 0.1)
		(layers "F.Cu" "B.Cu")
		(net 66)
	)
	(via
		(at 140.8 39.874)
		(size 0.45)
		(drill 0.1)
		(layers "F.Cu" "B.Cu")
		(free yes)
		(net 66)
	)
	(via
		(at 130.6 91.5)
		(size 0.45)
		(drill 0.1)
		(layers "F.Cu" "B.Cu")
		(free yes)
		(net 66)
	)
	(via
		(at 106.1 41.102)
		(size 0.45)
		(drill 0.1)
		(layers "F.Cu" "B.Cu")
		(net 66)
	)
	(via
		(at 116.2 40.1)
		(size 0.45)
		(drill 0.1)
		(layers "F.Cu" "B.Cu")
		(net 66)
	)
	(via
		(at 118.8 39.9)
		(size 0.45)
		(drill 0.1)
		(layers "F.Cu" "B.Cu")
		(net 66)
	)
	(via
		(at 149.2 39.7)
		(size 0.45)
		(drill 0.1)
		(layers "F.Cu" "B.Cu")
		(free yes)
		(net 66)
	)
	(via
		(at 123.35 133.45)
		(size 0.45)
		(drill 0.1)
		(layers "F.Cu" "B.Cu")
		(free yes)
		(net 66)
	)
	(via
		(at 105 104.35)
		(size 0.45)
		(drill 0.1)
		(layers "F.Cu" "B.Cu")
		(net 66)
	)
	(via
		(at 138.499999 32)
		(size 0.45)
		(drill 0.1)
		(layers "F.Cu" "B.Cu")
		(net 66)
	)
	(via
		(at 155.3 36.4)
		(size 0.45)
		(drill 0.1)
		(layers "F.Cu" "B.Cu")
		(free yes)
		(net 66)
	)
	(via
		(at 122.099999 113.8)
		(size 0.45)
		(drill 0.1)
		(layers "F.Cu" "B.Cu")
		(net 66)
	)
	(via
		(at 147.576001 53.5)
		(size 0.45)
		(drill 0.1)
		(layers "F.Cu" "B.Cu")
		(net 66)
	)
	(via
		(at 126.25 114.25)
		(size 0.45)
		(drill 0.1)
		(layers "F.Cu" "B.Cu")
		(net 66)
	)
	(via
		(at 143.499999 32)
		(size 0.45)
		(drill 0.1)
		(layers "F.Cu" "B.Cu")
		(net 66)
	)
	(via
		(at 149.4 82.8)
		(size 0.45)
		(drill 0.1)
		(layers "F.Cu" "B.Cu")
		(net 66)
	)
	(via
		(at 102.6 39)
		(size 0.45)
		(drill 0.1)
		(layers "F.Cu" "B.Cu")
		(net 66)
	)
	(via
		(at 102.6 94)
		(size 0.45)
		(drill 0.1)
		(layers "F.Cu" "B.Cu")
		(net 66)
	)
	(via
		(at 102.6 106.5)
		(size 0.45)
		(drill 0.1)
		(layers "F.Cu" "B.Cu")
		(net 66)
	)
	(via
		(at 105 97.85)
		(size 0.45)
		(drill 0.1)
		(layers "F.Cu" "B.Cu")
		(net 66)
	)
	(via
		(at 158.5 95.5)
		(size 0.45)
		(drill 0.1)
		(layers "F.Cu" "B.Cu")
		(net 66)
	)
	(via
		(at 158.5 150.5)
		(size 0.45)
		(drill 0.1)
		(layers "F.Cu" "B.Cu")
		(net 66)
	)
	(via
		(at 102.6 136.5)
		(size 0.45)
		(drill 0.1)
		(layers "F.Cu" "B.Cu")
		(net 66)
	)
	(via
		(at 143.4 91.8)
		(size 0.45)
		(drill 0.1)
		(layers "F.Cu" "B.Cu")
		(net 66)
	)
	(via
		(at 111.2 126.6)
		(size 0.45)
		(drill 0.1)
		(layers "F.Cu" "B.Cu")
		(net 66)
	)
	(via
		(at 130.8 95.2)
		(size 0.45)
		(drill 0.1)
		(layers "F.Cu" "B.Cu")
		(free yes)
		(net 66)
	)
	(via
		(at 127.298 42.286999)
		(size 0.45)
		(drill 0.1)
		(layers "F.Cu" "B.Cu")
		(net 66)
	)
	(via
		(at 147.002 96)
		(size 0.55)
		(drill 0.15)
		(layers "F.Cu" "B.Cu")
		(net 66)
	)
	(via
		(at 104.975 93.85)
		(size 0.45)
		(drill 0.1)
		(layers "F.Cu" "B.Cu")
		(net 66)
	)
	(via
		(at 149.5 111.25)
		(size 0.45)
		(drill 0.1)
		(layers "F.Cu" "B.Cu")
		(net 66)
	)
	(via
		(at 124.15 132.65)
		(size 0.45)
		(drill 0.1)
		(layers "F.Cu" "B.Cu")
		(free yes)
		(net 66)
	)
	(via
		(at 116.2 104.1)
		(size 0.45)
		(drill 0.1)
		(layers "F.Cu" "B.Cu")
		(net 66)
	)
	(via
		(at 149.5 106.25)
		(size 0.45)
		(drill 0.1)
		(layers "F.Cu" "B.Cu")
		(net 66)
	)
	(via
		(at 155.3 35.6)
		(size 0.45)
		(drill 0.1)
		(layers "F.Cu" "B.Cu")
		(free yes)
		(net 66)
	)
	(via
		(at 128.500001 128.350001)
		(size 0.45)
		(drill 0.1)
		(layers "F.Cu" "B.Cu")
		(net 66)
	)
	(via
		(at 124.15 133.45)
		(size 0.45)
		(drill 0.1)
		(layers "F.Cu" "B.Cu")
		(free yes)
		(net 66)
	)
	(via
		(at 116.2 84.1)
		(size 0.45)
		(drill 0.1)
		(layers "F.Cu" "B.Cu")
		(net 66)
	)
	(via
		(at 132.5 84.5)
		(size 0.45)
		(drill 0.1)
		(layers "F.Cu" "B.Cu")
		(free yes)
		(net 66)
	)
	(via
		(at 140 45.9)
		(size 0.45)
		(drill 0.1)
		(layers "F.Cu" "B.Cu")
		(net 66)
	)
	(via
		(at 129.8 37.3)
		(size 0.45)
		(drill 0.1)
		(layers "F.Cu" "B.Cu")
		(net 66)
	)
	(via
		(at 149.5 103.75)
		(size 0.45)
		(drill 0.1)
		(layers "F.Cu" "B.Cu")
		(net 66)
	)
	(via
		(at 132.5 77.5)
		(size 0.45)
		(drill 0.1)
		(layers "F.Cu" "B.Cu")
		(free yes)
		(net 66)
	)
	(via
		(at 102.6 84)
		(size 0.45)
		(drill 0.1)
		(layers "F.Cu" "B.Cu")
		(net 66)
	)
	(via
		(at 158.5 58)
		(size 0.45)
		(drill 0.1)
		(layers "F.Cu" "B.Cu")
		(net 66)
	)
	(via
		(at 102.6 99)
		(size 0.45)
		(drill 0.1)
		(layers "F.Cu" "B.Cu")
		(net 66)
	)
	(via
		(at 122.374999 150.154999)
		(size 0.45)
		(drill 0.1)
		(layers "F.Cu" "B.Cu")
		(net 66)
	)
	(via
		(at 102.6 124)
		(size 0.45)
		(drill 0.1)
		(layers "F.Cu" "B.Cu")
		(net 66)
	)
	(via
		(at 116.2 98.1)
		(size 0.45)
		(drill 0.1)
		(layers "F.Cu" "B.Cu")
		(net 66)
	)
	(via
		(at 145.412 54.000999)
		(size 0.55)
		(drill 0.15)
		(layers "F.Cu" "B.Cu")
		(net 66)
	)
	(via
		(at 144.9 64.6)
		(size 0.45)
		(drill 0.1)
		(layers "F.Cu" "B.Cu")
		(net 66)
	)
	(via
		(at 144.7 93)
		(size 0.45)
		(drill 0.1)
		(layers "F.Cu" "B.Cu")
		(net 66)
	)
	(via
		(at 140.999999 32)
		(size 0.45)
		(drill 0.1)
		(layers "F.Cu" "B.Cu")
		(net 66)
	)
	(via
		(at 102.6 56.5)
		(size 0.45)
		(drill 0.1)
		(layers "F.Cu" "B.Cu")
		(net 66)
	)
	(via
		(at 125.8 41.1)
		(size 0.45)
		(drill 0.1)
		(layers "F.Cu" "B.Cu")
		(net 66)
	)
	(via
		(at 153.499999 32)
		(size 0.45)
		(drill 0.1)
		(layers "F.Cu" "B.Cu")
		(net 66)
	)
	(via
		(at 155.3 37.2)
		(size 0.45)
		(drill 0.1)
		(layers "F.Cu" "B.Cu")
		(free yes)
		(net 66)
	)
	(via
		(at 129.6 50.3)
		(size 0.45)
		(drill 0.1)
		(layers "F.Cu" "B.Cu")
		(net 66)
	)
	(via
		(at 139.2 40.674)
		(size 0.45)
		(drill 0.1)
		(layers "F.Cu" "B.Cu")
		(free yes)
		(net 66)
	)
	(via
		(at 106.1 105.1)
		(size 0.45)
		(drill 0.1)
		(layers "F.Cu" "B.Cu")
		(net 66)
	)
	(via
		(at 153 165)
		(size 0.45)
		(drill 0.1)
		(layers "F.Cu" "B.Cu")
		(net 66)
	)
	(via
		(at 158.5 113)
		(size 0.45)
		(drill 0.1)
		(layers "F.Cu" "B.Cu")
		(net 66)
	)
	(via
		(at 132.5 76.5)
		(size 0.45)
		(drill 0.1)
		(layers "F.Cu" "B.Cu")
		(free yes)
		(net 66)
	)
	(via
		(at 122.099999 114.6)
		(size 0.45)
		(drill 0.1)
		(layers "F.Cu" "B.Cu")
		(net 66)
	)
	(via
		(at 124.8 48.2)
		(size 0.45)
		(drill 0.1)
		(layers "F.Cu" "B.Cu")
		(net 66)
	)
	(via
		(at 148.4 41.3)
		(size 0.45)
		(drill 0.1)
		(layers "F.Cu" "B.Cu")
		(free yes)
		(net 66)
	)
	(via
		(at 158.5 155.5)
		(size 0.45)
		(drill 0.1)
		(layers "F.Cu" "B.Cu")
		(net 66)
	)
	(via
		(at 154.5 122.25)
		(size 0.45)
		(drill 0.1)
		(layers "F.Cu" "B.Cu")
		(net 66)
	)
	(via
		(at 127.3 41.1)
		(size 0.45)
		(drill 0.1)
		(layers "F.Cu" "B.Cu")
		(net 66)
	)
	(via
		(at 149.2 40.5)
		(size 0.45)
		(drill 0.1)
		(layers "F.Cu" "B.Cu")
		(free yes)
		(net 66)
	)
	(via
		(at 140.8 40.674)
		(size 0.45)
		(drill 0.1)
		(layers "F.Cu" "B.Cu")
		(free yes)
		(net 66)
	)
	(via
		(at 156.9 37.2)
		(size 0.45)
		(drill 0.1)
		(layers "F.Cu" "B.Cu")
		(free yes)
		(net 66)
	)
	(via
		(at 138.558 45.926999)
		(size 0.45)
		(drill 0.1)
		(layers "F.Cu" "B.Cu")
		(net 66)
	)
	(via
		(at 158.5 118)
		(size 0.45)
		(drill 0.1)
		(layers "F.Cu" "B.Cu")
		(net 66)
	)
	(via
		(at 116.2 94.1)
		(size 0.45)
		(drill 0.1)
		(layers "F.Cu" "B.Cu")
		(net 66)
	)
	(via
		(at 140 41.474)
		(size 0.45)
		(drill 0.1)
		(layers "F.Cu" "B.Cu")
		(free yes)
		(net 66)
	)
	(via
		(at 149.302 89)
		(size 0.55)
		(drill 0.15)
		(layers "F.Cu" "B.Cu")
		(net 66)
	)
	(via
		(at 124.3 41.1)
		(size 0.45)
		(drill 0.1)
		(layers "F.Cu" "B.Cu")
		(net 66)
	)
	(via
		(at 119.4 134.8)
		(size 0.45)
		(drill 0.1)
		(layers "F.Cu" "B.Cu")
		(net 66)
	)
	(via
		(at 139.499999 165)
		(size 0.45)
		(drill 0.1)
		(layers "F.Cu" "B.Cu")
		(net 66)
	)
	(via
		(at 158.5 158)
		(size 0.45)
		(drill 0.1)
		(layers "F.Cu" "B.Cu")
		(net 66)
	)
	(via
		(at 102.6 101.5)
		(size 0.45)
		(drill 0.1)
		(layers "F.Cu" "B.Cu")
		(net 66)
	)
	(via
		(at 144.8 80.6)
		(size 0.45)
		(drill 0.1)
		(layers "F.Cu" "B.Cu")
		(net 66)
	)
	(via
		(at 102.6 86.5)
		(size 0.45)
		(drill 0.1)
		(layers "F.Cu" "B.Cu")
		(net 66)
	)
	(via
		(at 106.1 89.101)
		(size 0.45)
		(drill 0.1)
		(layers "F.Cu" "B.Cu")
		(net 66)
	)
	(via
		(at 129.300001 128.350001)
		(size 0.45)
		(drill 0.1)
		(layers "F.Cu" "B.Cu")
		(net 66)
	)
	(via
		(at 126.5 128.350001)
		(size 0.45)
		(drill 0.1)
		(layers "F.Cu" "B.Cu")
		(net 66)
	)
	(via
		(at 126.25 110)
		(size 0.45)
		(drill 0.1)
		(layers "F.Cu" "B.Cu")
		(net 66)
	)
	(via
		(at 105 91.35)
		(size 0.45)
		(drill 0.1)
		(layers "F.Cu" "B.Cu")
		(net 66)
	)
	(via
		(at 126.25 108.25)
		(size 0.45)
		(drill 0.1)
		(layers "F.Cu" "B.Cu")
		(net 66)
	)
	(via
		(at 158.5 108)
		(size 0.45)
		(drill 0.1)
		(layers "F.Cu" "B.Cu")
		(net 66)
	)
	(via
		(at 123.35 132.65)
		(size 0.45)
		(drill 0.1)
		(layers "F.Cu" "B.Cu")
		(free yes)
		(net 66)
	)
	(via
		(at 158.5 100.5)
		(size 0.45)
		(drill 0.1)
		(layers "F.Cu" "B.Cu")
		(net 66)
	)
	(via
		(at 128.8 41.1)
		(size 0.45)
		(drill 0.1)
		(layers "F.Cu" "B.Cu")
		(net 66)
	)
	(via
		(at 123.6 124)
		(size 0.45)
		(drill 0.1)
		(layers "F.Cu" "B.Cu")
		(net 66)
	)
	(via
		(at 158.5 120.5)
		(size 0.45)
		(drill 0.1)
		(layers "F.Cu" "B.Cu")
		(net 66)
	)
	(via
		(at 116.199999 51.1)
		(size 0.45)
		(drill 0.1)
		(layers "F.Cu" "B.Cu")
		(net 66)
	)
	(via
		(at 131.6 88.5)
		(size 0.45)
		(drill 0.1)
		(layers "F.Cu" "B.Cu")
		(free yes)
		(net 66)
	)
	(via
		(at 138.9 60)
		(size 0.45)
		(drill 0.1)
		(layers "F.Cu" "B.Cu")
		(net 66)
	)
	(via
		(at 158.5 53)
		(size 0.45)
		(drill 0.1)
		(layers "F.Cu" "B.Cu")
		(net 66)
	)
	(via
		(at 116.199999 55.1)
		(size 0.45)
		(drill 0.1)
		(layers "F.Cu" "B.Cu")
		(net 66)
	)
	(via
		(at 158.5 115.5)
		(size 0.45)
		(drill 0.1)
		(layers "F.Cu" "B.Cu")
		(net 66)
	)
	(via
		(at 105 116.699999)
		(size 0.45)
		(drill 0.1)
		(layers "F.Cu" "B.Cu")
		(net 66)
	)
	(via
		(at 134.499999 165)
		(size 0.45)
		(drill 0.1)
		(layers "F.Cu" "B.Cu")
		(net 66)
	)
	(via
		(at 122.099999 117)
		(size 0.45)
		(drill 0.1)
		(layers "F.Cu" "B.Cu")
		(net 66)
	)
	(via
		(at 141.999999 165)
		(size 0.45)
		(drill 0.1)
		(layers "F.Cu" "B.Cu")
		(net 66)
	)
	(via
		(at 135.3 40.2)
		(size 0.45)
		(drill 0.1)
		(layers "F.Cu" "B.Cu")
		(net 66)
	)
	(via
		(at 156.9 34.8)
		(size 0.45)
		(drill 0.1)
		(layers "F.Cu" "B.Cu")
		(free yes)
		(net 66)
	)
	(via
		(at 158.5 143)
		(size 0.45)
		(drill 0.1)
		(layers "F.Cu" "B.Cu")
		(net 66)
	)
	(via
		(at 106.1 75.102)
		(size 0.45)
		(drill 0.1)
		(layers "F.Cu" "B.Cu")
		(net 66)
	)
	(via
		(at 140 40.674)
		(size 0.45)
		(drill 0.1)
		(layers "F.Cu" "B.Cu")
		(free yes)
		(net 66)
	)
	(via
		(at 124.298 42.287)
		(size 0.45)
		(drill 0.1)
		(layers "F.Cu" "B.Cu")
		(net 66)
	)
	(via
		(at 147.6 41.3)
		(size 0.45)
		(drill 0.1)
		(layers "F.Cu" "B.Cu")
		(free yes)
		(net 66)
	)
	(via
		(at 158.5 133)
		(size 0.45)
		(drill 0.1)
		(layers "F.Cu" "B.Cu")
		(net 66)
	)
	(via
		(at 158.5 130.5)
		(size 0.45)
		(drill 0.1)
		(layers "F.Cu" "B.Cu")
		(net 66)
	)
	(via
		(at 149.5 101.25)
		(size 0.45)
		(drill 0.1)
		(layers "F.Cu" "B.Cu")
		(net 66)
	)
	(via
		(at 102.6 141.5)
		(size 0.45)
		(drill 0.1)
		(layers "F.Cu" "B.Cu")
		(net 66)
	)
	(via
		(at 149.737 58.526)
		(size 0.55)
		(drill 0.15)
		(layers "F.Cu" "B.Cu")
		(net 66)
	)
	(via
		(at 116.2 102.1)
		(size 0.45)
		(drill 0.1)
		(layers "F.Cu" "B.Cu")
		(net 66)
	)
	(via
		(at 147.001999 95)
		(size 0.55)
		(drill 0.15)
		(layers "F.Cu" "B.Cu")
		(net 66)
	)
	(via
		(at 130.6 89.5)
		(size 0.45)
		(drill 0.1)
		(layers "F.Cu" "B.Cu")
		(free yes)
		(net 66)
	)
	(via
		(at 118.499998 32)
		(size 0.45)
		(drill 0.1)
		(layers "F.Cu" "B.Cu")
		(net 66)
	)
	(via
		(at 106.1 61.102)
		(size 0.45)
		(drill 0.1)
		(layers "F.Cu" "B.Cu")
		(net 66)
	)
	(via
		(at 158.5 128)
		(size 0.45)
		(drill 0.1)
		(layers "F.Cu" "B.Cu")
		(net 66)
	)
	(via
		(at 126.8 37.3)
		(size 0.45)
		(drill 0.1)
		(layers "F.Cu" "B.Cu")
		(net 66)
	)
	(via
		(at 102.6 154)
		(size 0.45)
		(drill 0.1)
		(layers "F.Cu" "B.Cu")
		(net 66)
	)
	(via
		(at 110.6 83.8)
		(size 0.45)
		(drill 0.1)
		(layers "F.Cu" "B.Cu")
		(net 66)
	)
	(via
		(at 149.2 41.3)
		(size 0.45)
		(drill 0.1)
		(layers "F.Cu" "B.Cu")
		(free yes)
		(net 66)
	)
	(via
		(at 102.6 151.5)
		(size 0.45)
		(drill 0.1)
		(layers "F.Cu" "B.Cu")
		(net 66)
	)
	(via
		(at 127.7 50)
		(size 0.45)
		(drill 0.1)
		(layers "F.Cu" "B.Cu")
		(net 66)
	)
	(via
		(at 119.4 129.8)
		(size 0.45)
		(drill 0.1)
		(layers "F.Cu" "B.Cu")
		(net 66)
	)
	(via
		(at 115.999998 32)
		(size 0.45)
		(drill 0.1)
		(layers "F.Cu" "B.Cu")
		(net 66)
	)
	(via
		(at 102.6 96.5)
		(size 0.45)
		(drill 0.1)
		(layers "F.Cu" "B.Cu")
		(net 66)
	)
	(via
		(at 131.6 89.5)
		(size 0.45)
		(drill 0.1)
		(layers "F.Cu" "B.Cu")
		(free yes)
		(net 66)
	)
	(via
		(at 158.5 63)
		(size 0.45)
		(drill 0.1)
		(layers "F.Cu" "B.Cu")
		(net 66)
	)
	(via
		(at 105.999999 165)
		(size 0.45)
		(drill 0.1)
		(layers "F.Cu" "B.Cu")
		(net 66)
	)
	(via
		(at 106.1 78.102)
		(size 0.45)
		(drill 0.1)
		(layers "F.Cu" "B.Cu")
		(net 66)
	)
	(via
		(at 102.6 74)
		(size 0.45)
		(drill 0.1)
		(layers "F.Cu" "B.Cu")
		(net 66)
	)
	(via
		(at 116.2 77.1)
		(size 0.45)
		(drill 0.1)
		(layers "F.Cu" "B.Cu")
		(net 66)
	)
	(via
		(at 132.6 89.5)
		(size 0.45)
		(drill 0.1)
		(layers "F.Cu" "B.Cu")
		(free yes)
		(net 66)
	)
	(via
		(at 102.6 146.5)
		(size 0.45)
		(drill 0.1)
		(layers "F.Cu" "B.Cu")
		(net 66)
	)
	(via
		(at 149.4 80.6)
		(size 0.45)
		(drill 0.1)
		(layers "F.Cu" "B.Cu")
		(net 66)
	)
	(via
		(at 126.25 117.75)
		(size 0.45)
		(drill 0.1)
		(layers "F.Cu" "B.Cu")
		(net 66)
	)
	(via
		(at 132.5 82.499999)
		(size 0.45)
		(drill 0.1)
		(layers "F.Cu" "B.Cu")
		(free yes)
		(net 66)
	)
	(via
		(at 156.1 35.6)
		(size 0.45)
		(drill 0.1)
		(layers "F.Cu" "B.Cu")
		(free yes)
		(net 66)
	)
	(via
		(at 106.1 50.103)
		(size 0.45)
		(drill 0.1)
		(layers "F.Cu" "B.Cu")
		(net 66)
	)
	(via
		(at 124.499999 165)
		(size 0.45)
		(drill 0.1)
		(layers "F.Cu" "B.Cu")
		(net 66)
	)
	(via
		(at 123.3 51.55)
		(size 0.45)
		(drill 0.1)
		(layers "F.Cu" "B.Cu")
		(net 66)
	)
	(via
		(at 136.4 108.8)
		(size 0.45)
		(drill 0.1)
		(layers "F.Cu" "B.Cu")
		(net 66)
	)
	(via
		(at 144.9 62.4)
		(size 0.45)
		(drill 0.1)
		(layers "F.Cu" "B.Cu")
		(net 66)
	)
	(via
		(at 130.8 94.2)
		(size 0.45)
		(drill 0.1)
		(layers "F.Cu" "B.Cu")
		(free yes)
		(net 66)
	)
	(via
		(at 144.7 90.6)
		(size 0.45)
		(drill 0.1)
		(layers "F.Cu" "B.Cu")
		(net 66)
	)
	(via
		(at 147 165)
		(size 0.45)
		(drill 0.1)
		(layers "F.Cu" "B.Cu")
		(net 66)
	)
	(via
		(at 123.2 137.2)
		(size 0.45)
		(drill 0.1)
		(layers "F.Cu" "B.Cu")
		(free yes)
		(net 66)
	)
	(via
		(at 125.999999 32)
		(size 0.45)
		(drill 0.1)
		(layers "F.Cu" "B.Cu")
		(net 66)
	)
	(via
		(at 123.4 127.8)
		(size 0.45)
		(drill 0.1)
		(layers "F.Cu" "B.Cu")
		(free yes)
		(net 66)
	)
	(via
		(at 158.5 145.5)
		(size 0.45)
		(drill 0.1)
		(layers "F.Cu" "B.Cu")
		(net 66)
	)
	(via
		(at 108.5 32)
		(size 0.45)
		(drill 0.1)
		(layers "F.Cu" "B.Cu")
		(net 66)
	)
	(via
		(at 105 102.85)
		(size 0.45)
		(drill 0.1)
		(layers "F.Cu" "B.Cu")
		(net 66)
	)
	(via
		(at 132.5 83.499999)
		(size 0.45)
		(drill 0.1)
		(layers "F.Cu" "B.Cu")
		(free yes)
		(net 66)
	)
	(via
		(at 122.4 135.6)
		(size 0.45)
		(drill 0.1)
		(layers "F.Cu" "B.Cu")
		(free yes)
		(net 66)
	)
	(via
		(at 155.3 34.8)
		(size 0.45)
		(drill 0.1)
		(layers "F.Cu" "B.Cu")
		(free yes)
		(net 66)
	)
	(via
		(at 119.4 133.8)
		(size 0.45)
		(drill 0.1)
		(layers "F.Cu" "B.Cu")
		(net 66)
	)
	(via
		(at 106.1 86.102)
		(size 0.45)
		(drill 0.1)
		(layers "F.Cu" "B.Cu")
		(net 66)
	)
	(via
		(at 102.6 144)
		(size 0.45)
		(drill 0.1)
		(layers "F.Cu" "B.Cu")
		(net 66)
	)
	(via
		(at 123.8 37.3)
		(size 0.45)
		(drill 0.1)
		(layers "F.Cu" "B.Cu")
		(net 66)
	)
	(via
		(at 133.079 45.914)
		(size 0.45)
		(drill 0.1)
		(layers "F.Cu" "B.Cu")
		(net 66)
	)
	(via
		(at 102.6 51.5)
		(size 0.45)
		(drill 0.1)
		(layers "F.Cu" "B.Cu")
		(net 66)
	)
	(via
		(at 102.6 159)
		(size 0.45)
		(drill 0.1)
		(layers "F.Cu" "B.Cu")
		(net 66)
	)
	(via
		(at 151.737 58.525999)
		(size 0.55)
		(drill 0.15)
		(layers "F.Cu" "B.Cu")
		(net 66)
	)
	(via
		(at 131.3 128.350001)
		(size 0.45)
		(drill 0.1)
		(layers "F.Cu" "B.Cu")
		(net 66)
	)
	(via
		(at 122.6 45.7)
		(size 0.45)
		(drill 0.1)
		(layers "F.Cu" "B.Cu")
		(net 66)
	)
	(via
		(at 156.1 37.2)
		(size 0.45)
		(drill 0.1)
		(layers "F.Cu" "B.Cu")
		(free yes)
		(net 66)
	)
	(via
		(at 152 122.25)
		(size 0.45)
		(drill 0.1)
		(layers "F.Cu" "B.Cu")
		(net 66)
	)
	(via
		(at 102.6 119)
		(size 0.45)
		(drill 0.1)
		(layers "F.Cu" "B.Cu")
		(net 66)
	)
	(via
		(at 127.581999 149.656999)
		(size 0.55)
		(drill 0.15)
		(layers "F.Cu" "B.Cu")
		(net 66)
	)
	(via
		(at 158.5 50.5)
		(size 0.45)
		(drill 0.1)
		(layers "F.Cu" "B.Cu")
		(net 66)
	)
	(via
		(at 158.5 80.5)
		(size 0.45)
		(drill 0.1)
		(layers "F.Cu" "B.Cu")
		(net 66)
	)
	(via
		(at 158.5 85.5)
		(size 0.45)
		(drill 0.1)
		(layers "F.Cu" "B.Cu")
		(net 66)
	)
	(via
		(at 140.8 41.474)
		(size 0.45)
		(drill 0.1)
		(layers "F.Cu" "B.Cu")
		(free yes)
		(net 66)
	)
	(via
		(at 156.9 36.4)
		(size 0.45)
		(drill 0.1)
		(layers "F.Cu" "B.Cu")
		(free yes)
		(net 66)
	)
	(via
		(at 127.3 128.350001)
		(size 0.45)
		(drill 0.1)
		(layers "F.Cu" "B.Cu")
		(net 66)
	)
	(via
		(at 156 32)
		(size 0.45)
		(drill 0.1)
		(layers "F.Cu" "B.Cu")
		(net 66)
	)
	(via
		(at 123.9 46.7)
		(size 0.45)
		(drill 0.1)
		(layers "F.Cu" "B.Cu")
		(net 66)
	)
	(via
		(at 123.2 136.4)
		(size 0.45)
		(drill 0.1)
		(layers "F.Cu" "B.Cu")
		(free yes)
		(net 66)
	)
	(via
		(at 123.4 129.4)
		(size 0.45)
		(drill 0.1)
		(layers "F.Cu" "B.Cu")
		(free yes)
		(net 66)
	)
	(via
		(at 141.15 45.9)
		(size 0.45)
		(drill 0.1)
		(layers "F.Cu" "B.Cu")
		(net 66)
	)
	(via
		(at 126.25 116)
		(size 0.45)
		(drill 0.1)
		(layers "F.Cu" "B.Cu")
		(net 66)
	)
	(via
		(at 158.5 68)
		(size 0.45)
		(drill 0.1)
		(layers "F.Cu" "B.Cu")
		(net 66)
	)
	(via
		(at 123.3 49.8)
		(size 0.45)
		(drill 0.1)
		(layers "F.Cu" "B.Cu")
		(net 66)
	)
	(via
		(at 102.6 49)
		(size 0.45)
		(drill 0.1)
		(layers "F.Cu" "B.Cu")
		(net 66)
	)
	(via
		(at 116.2 73.1)
		(size 0.45)
		(drill 0.1)
		(layers "F.Cu" "B.Cu")
		(net 66)
	)
	(via
		(at 152 98.5)
		(size 0.45)
		(drill 0.1)
		(layers "F.Cu" "B.Cu")
		(net 66)
	)
	(via
		(at 145 133)
		(size 0.45)
		(drill 0.1)
		(layers "F.Cu" "B.Cu")
		(net 66)
	)
	(via
		(at 102.6 116.5)
		(size 0.45)
		(drill 0.1)
		(layers "F.Cu" "B.Cu")
		(net 66)
	)
	(via
		(at 106.1 69.101)
		(size 0.45)
		(drill 0.1)
		(layers "F.Cu" "B.Cu")
		(net 66)
	)
	(via
		(at 124.2 129.4)
		(size 0.45)
		(drill 0.1)
		(layers "F.Cu" "B.Cu")
		(free yes)
		(net 66)
	)
	(via
		(at 132.6 92.5)
		(size 0.45)
		(drill 0.1)
		(layers "F.Cu" "B.Cu")
		(free yes)
		(net 66)
	)
	(via
		(at 102.6 64)
		(size 0.45)
		(drill 0.1)
		(layers "F.Cu" "B.Cu")
		(net 66)
	)
	(via
		(at 106.1 93.101)
		(size 0.45)
		(drill 0.1)
		(layers "F.Cu" "B.Cu")
		(net 66)
	)
	(via
		(at 133.499999 32)
		(size 0.45)
		(drill 0.1)
		(layers "F.Cu" "B.Cu")
		(net 66)
	)
	(via
		(at 123.2 135.6)
		(size 0.45)
		(drill 0.1)
		(layers "F.Cu" "B.Cu")
		(free yes)
		(net 66)
	)
	(via
		(at 116.999998 165)
		(size 0.45)
		(drill 0.1)
		(layers "F.Cu" "B.Cu")
		(net 66)
	)
	(via
		(at 131.8 41.1)
		(size 0.45)
		(drill 0.1)
		(layers "F.Cu" "B.Cu")
		(net 66)
	)
	(via
		(at 158.5 123)
		(size 0.45)
		(drill 0.1)
		(layers "F.Cu" "B.Cu")
		(net 66)
	)
	(via
		(at 125.332999 153.326998)
		(size 0.55)
		(drill 0.15)
		(layers "F.Cu" "B.Cu")
		(net 66)
	)
	(via
		(at 138.25 63.75)
		(size 0.45)
		(drill 0.1)
		(layers "F.Cu" "B.Cu")
		(net 66)
	)
	(via
		(at 148.499999 32)
		(size 0.45)
		(drill 0.1)
		(layers "F.Cu" "B.Cu")
		(net 66)
	)
	(via
		(at 106.1 62.102)
		(size 0.45)
		(drill 0.1)
		(layers "F.Cu" "B.Cu")
		(net 66)
	)
	(via
		(at 122.3 37.3)
		(size 0.45)
		(drill 0.1)
		(layers "F.Cu" "B.Cu")
		(net 66)
	)
	(via
		(at 106.1 92.101)
		(size 0.45)
		(drill 0.1)
		(layers "F.Cu" "B.Cu")
		(net 66)
	)
	(via
		(at 102.6 111.5)
		(size 0.45)
		(drill 0.1)
		(layers "F.Cu" "B.Cu")
		(net 66)
	)
	(via
		(at 106.1 102.1)
		(size 0.45)
		(drill 0.1)
		(layers "F.Cu" "B.Cu")
		(net 66)
	)
	(via
		(at 158.5 60.5)
		(size 0.45)
		(drill 0.1)
		(layers "F.Cu" "B.Cu")
		(net 66)
	)
	(via
		(at 149.301998 97)
		(size 0.55)
		(drill 0.15)
		(layers "F.Cu" "B.Cu")
		(net 66)
	)
	(via
		(at 116.2 95.1)
		(size 0.45)
		(drill 0.1)
		(layers "F.Cu" "B.Cu")
		(net 66)
	)
	(via
		(at 102.6 121.5)
		(size 0.45)
		(drill 0.1)
		(layers "F.Cu" "B.Cu")
		(net 66)
	)
	(via
		(at 106.1 83.101)
		(size 0.45)
		(drill 0.1)
		(layers "F.Cu" "B.Cu")
		(net 66)
	)
	(via
		(at 130.999999 32)
		(size 0.45)
		(drill 0.1)
		(layers "F.Cu" "B.Cu")
		(net 66)
	)
	(via
		(at 125.3 37.3)
		(size 0.45)
		(drill 0.1)
		(layers "F.Cu" "B.Cu")
		(net 66)
	)
	(via
		(at 106.1 66.101)
		(size 0.45)
		(drill 0.1)
		(layers "F.Cu" "B.Cu")
		(net 66)
	)
	(via
		(at 119.4 130.8)
		(size 0.45)
		(drill 0.1)
		(layers "F.Cu" "B.Cu")
		(net 66)
	)
	(via
		(at 156.9 35.6)
		(size 0.45)
		(drill 0.1)
		(layers "F.Cu" "B.Cu")
		(free yes)
		(net 66)
	)
	(via
		(at 136.079 45.914)
		(size 0.45)
		(drill 0.1)
		(layers "F.Cu" "B.Cu")
		(net 66)
	)
	(via
		(at 158.5 65.5)
		(size 0.45)
		(drill 0.1)
		(layers "F.Cu" "B.Cu")
		(net 66)
	)
	(via
		(at 120.15 46.95)
		(size 0.45)
		(drill 0.1)
		(layers "F.Cu" "B.Cu")
		(net 66)
	)
	(via
		(at 126.25 111.75)
		(size 0.45)
		(drill 0.1)
		(layers "F.Cu" "B.Cu")
		(net 66)
	)
	(via
		(at 128.332999 150.826999)
		(size 0.55)
		(drill 0.15)
		(layers "F.Cu" "B.Cu")
		(net 66)
	)
	(via
		(at 105 99.35)
		(size 0.45)
		(drill 0.1)
		(layers "F.Cu" "B.Cu")
		(net 66)
	)
	(via
		(at 158.5 45.5)
		(size 0.45)
		(drill 0.1)
		(layers "F.Cu" "B.Cu")
		(net 66)
	)
	(via
		(at 132.5 78.500001)
		(size 0.45)
		(drill 0.1)
		(layers "F.Cu" "B.Cu")
		(free yes)
		(net 66)
	)
	(via
		(at 106.1 100.1)
		(size 0.45)
		(drill 0.1)
		(layers "F.Cu" "B.Cu")
		(net 66)
	)
	(via
		(at 142 93.1)
		(size 0.45)
		(drill 0.1)
		(layers "F.Cu" "B.Cu")
		(net 66)
	)
	(via
		(at 102.6 81.5)
		(size 0.45)
		(drill 0.1)
		(layers "F.Cu" "B.Cu")
		(net 66)
	)
	(via
		(at 145 108.4)
		(size 0.45)
		(drill 0.1)
		(layers "F.Cu" "B.Cu")
		(net 66)
	)
	(via
		(at 158.5 110.5)
		(size 0.45)
		(drill 0.1)
		(layers "F.Cu" "B.Cu")
		(net 66)
	)
	(via
		(at 158.5 55.5)
		(size 0.45)
		(drill 0.1)
		(layers "F.Cu" "B.Cu")
		(net 66)
	)
	(via
		(at 135.999999 32)
		(size 0.45)
		(drill 0.1)
		(layers "F.Cu" "B.Cu")
		(net 66)
	)
	(via
		(at 102.6 149)
		(size 0.45)
		(drill 0.1)
		(layers "F.Cu" "B.Cu")
		(net 66)
	)
	(via
		(at 149.5 108.75)
		(size 0.45)
		(drill 0.1)
		(layers "F.Cu" "B.Cu")
		(net 66)
	)
	(via
		(at 130.220001 152.999999)
		(size 0.45)
		(drill 0.1)
		(layers "F.Cu" "B.Cu")
		(net 66)
	)
	(via
		(at 106.1 71.101)
		(size 0.45)
		(drill 0.1)
		(layers "F.Cu" "B.Cu")
		(net 66)
	)
	(via
		(at 158.5 148)
		(size 0.45)
		(drill 0.1)
		(layers "F.Cu" "B.Cu")
		(net 66)
	)
	(via
		(at 148.4 39.7)
		(size 0.45)
		(drill 0.1)
		(layers "F.Cu" "B.Cu")
		(free yes)
		(net 66)
	)
	(via
		(at 155.3 38)
		(size 0.45)
		(drill 0.1)
		(layers "F.Cu" "B.Cu")
		(free yes)
		(net 66)
	)
	(via
		(at 158.5 43)
		(size 0.45)
		(drill 0.1)
		(layers "F.Cu" "B.Cu")
		(net 66)
	)
	(via
		(at 147.2 63)
		(size 0.45)
		(drill 0.1)
		(layers "F.Cu" "B.Cu")
		(net 66)
	)
	(via
		(at 158.5 88)
		(size 0.45)
		(drill 0.1)
		(layers "F.Cu" "B.Cu")
		(net 66)
	)
	(via
		(at 106.1 82.101)
		(size 0.45)
		(drill 0.1)
		(layers "F.Cu" "B.Cu")
		(net 66)
	)
	(via
		(at 114.4 35)
		(size 0.45)
		(drill 0.1)
		(layers "F.Cu" "B.Cu")
		(net 66)
	)
	(via
		(at 158.5 140.5)
		(size 0.45)
		(drill 0.1)
		(layers "F.Cu" "B.Cu")
		(net 66)
	)
	(via
		(at 158.5 135.5)
		(size 0.45)
		(drill 0.1)
		(layers "F.Cu" "B.Cu")
		(net 66)
	)
	(via
		(at 116.2 85.1)
		(size 0.45)
		(drill 0.1)
		(layers "F.Cu" "B.Cu")
		(net 66)
	)
	(via
		(at 156.1 38)
		(size 0.45)
		(drill 0.1)
		(layers "F.Cu" "B.Cu")
		(free yes)
		(net 66)
	)
	(via
		(at 158.5 48)
		(size 0.45)
		(drill 0.1)
		(layers "F.Cu" "B.Cu")
		(net 66)
	)
	(via
		(at 149.5 121.25)
		(size 0.45)
		(drill 0.1)
		(layers "F.Cu" "B.Cu")
		(net 66)
	)
	(via
		(at 102.6 71.5)
		(size 0.45)
		(drill 0.1)
		(layers "F.Cu" "B.Cu")
		(net 66)
	)
	(via
		(at 145.412 55.001)
		(size 0.55)
		(drill 0.15)
		(layers "F.Cu" "B.Cu")
		(net 66)
	)
	(via
		(at 102.6 79)
		(size 0.45)
		(drill 0.1)
		(layers "F.Cu" "B.Cu")
		(net 66)
	)
	(via
		(at 144.5 165)
		(size 0.45)
		(drill 0.1)
		(layers "F.Cu" "B.Cu")
		(net 66)
	)
	(via
		(at 134.676501 66.943001)
		(size 0.45)
		(drill 0.1)
		(layers "F.Cu" "B.Cu")
		(net 66)
	)
	(via
		(at 131.3 37.3)
		(size 0.45)
		(drill 0.1)
		(layers "F.Cu" "B.Cu")
		(net 66)
	)
	(via
		(at 112 165)
		(size 0.45)
		(drill 0.1)
		(layers "F.Cu" "B.Cu")
		(net 66)
	)
	(via
		(at 158.5 83)
		(size 0.45)
		(drill 0.1)
		(layers "F.Cu" "B.Cu")
		(net 66)
	)
	(via
		(at 106 118.1)
		(size 0.45)
		(drill 0.1)
		(layers "F.Cu" "B.Cu")
		(net 66)
	)
	(via
		(at 102.6 41.5)
		(size 0.45)
		(drill 0.1)
		(layers "F.Cu" "B.Cu")
		(net 66)
	)
	(via
		(at 158.5 40.5)
		(size 0.45)
		(drill 0.1)
		(layers "F.Cu" "B.Cu")
		(net 66)
	)
	(via
		(at 123.499999 32)
		(size 0.45)
		(drill 0.1)
		(layers "F.Cu" "B.Cu")
		(net 66)
	)
	(via
		(at 109.5 165)
		(size 0.45)
		(drill 0.1)
		(layers "F.Cu" "B.Cu")
		(net 66)
	)
	(via
		(at 141.8 72.6)
		(size 0.45)
		(drill 0.1)
		(layers "F.Cu" "B.Cu")
		(net 66)
	)
	(via
		(at 149.302 90.000001)
		(size 0.55)
		(drill 0.15)
		(layers "F.Cu" "B.Cu")
		(net 66)
	)
	(via
		(at 129.499999 165)
		(size 0.45)
		(drill 0.1)
		(layers "F.Cu" "B.Cu")
		(net 66)
	)
	(via
		(at 158.5 125.5)
		(size 0.45)
		(drill 0.1)
		(layers "F.Cu" "B.Cu")
		(net 66)
	)
	(via
		(at 105 118.700001)
		(size 0.45)
		(drill 0.1)
		(layers "F.Cu" "B.Cu")
		(net 66)
	)
	(via
		(at 116.2 80.1)
		(size 0.45)
		(drill 0.1)
		(layers "F.Cu" "B.Cu")
		(net 66)
	)
	(via
		(at 158.5 105.5)
		(size 0.45)
		(drill 0.1)
		(layers "F.Cu" "B.Cu")
		(net 66)
	)
	(via
		(at 156.1 38.8)
		(size 0.45)
		(drill 0.1)
		(layers "F.Cu" "B.Cu")
		(free yes)
		(net 66)
	)
	(via
		(at 116.2 88.1)
		(size 0.45)
		(drill 0.1)
		(layers "F.Cu" "B.Cu")
		(net 66)
	)
	(via
		(at 105 115.899999)
		(size 0.45)
		(drill 0.1)
		(layers "F.Cu" "B.Cu")
		(net 66)
	)
	(via
		(at 131.999999 165)
		(size 0.45)
		(drill 0.1)
		(layers "F.Cu" "B.Cu")
		(net 66)
	)
	(via
		(at 116.448 118.1)
		(size 0.45)
		(drill 0.1)
		(layers "F.Cu" "B.Cu")
		(net 66)
	)
	(via
		(at 102.6 131.5)
		(size 0.45)
		(drill 0.1)
		(layers "F.Cu" "B.Cu")
		(net 66)
	)
	(via
		(at 149.5 98.75)
		(size 0.45)
		(drill 0.1)
		(layers "F.Cu" "B.Cu")
		(net 66)
	)
	(via
		(at 113.5 32)
		(size 0.45)
		(drill 0.1)
		(layers "F.Cu" "B.Cu")
		(net 66)
	)
	(via
		(at 158.5 78)
		(size 0.45)
		(drill 0.1)
		(layers "F.Cu" "B.Cu")
		(net 66)
	)
	(via
		(at 102.6 134)
		(size 0.45)
		(drill 0.1)
		(layers "F.Cu" "B.Cu")
		(net 66)
	)
	(via
		(at 106.1 38.101)
		(size 0.45)
		(drill 0.1)
		(layers "F.Cu" "B.Cu")
		(net 66)
	)
	(via
		(at 158.5 93)
		(size 0.45)
		(drill 0.1)
		(layers "F.Cu" "B.Cu")
		(net 66)
	)
	(via
		(at 132.6 88.5)
		(size 0.45)
		(drill 0.1)
		(layers "F.Cu" "B.Cu")
		(free yes)
		(net 66)
	)
	(via
		(at 130.5 128.350001)
		(size 0.45)
		(drill 0.1)
		(layers "F.Cu" "B.Cu")
		(net 66)
	)
	(via
		(at 126.999999 165)
		(size 0.45)
		(drill 0.1)
		(layers "F.Cu" "B.Cu")
		(net 66)
	)
	(via
		(at 116.199999 48.1)
		(size 0.45)
		(drill 0.1)
		(layers "F.Cu" "B.Cu")
		(net 66)
	)
	(via
		(at 120.999998 32)
		(size 0.45)
		(drill 0.1)
		(layers "F.Cu" "B.Cu")
		(net 66)
	)
	(via
		(at 122.4 137.2)
		(size 0.45)
		(drill 0.1)
		(layers "F.Cu" "B.Cu")
		(free yes)
		(net 66)
	)
	(via
		(at 116.2 71.099999)
		(size 0.45)
		(drill 0.1)
		(layers "F.Cu" "B.Cu")
		(net 66)
	)
	(via
		(at 134.579 45.914)
		(size 0.45)
		(drill 0.1)
		(layers "F.Cu" "B.Cu")
		(net 66)
	)
	(via
		(at 137.8265 66.893001)
		(size 0.45)
		(drill 0.1)
		(layers "F.Cu" "B.Cu")
		(net 66)
	)
	(via
		(at 102.6 129)
		(size 0.45)
		(drill 0.1)
		(layers "F.Cu" "B.Cu")
		(net 66)
	)
	(via
		(at 102.6 54)
		(size 0.45)
		(drill 0.1)
		(layers "F.Cu" "B.Cu")
		(net 66)
	)
	(via
		(at 106.1 45.101)
		(size 0.45)
		(drill 0.1)
		(layers "F.Cu" "B.Cu")
		(net 66)
	)
	(via
		(at 116.2 91.1)
		(size 0.45)
		(drill 0.1)
		(layers "F.Cu" "B.Cu")
		(net 66)
	)
	(via
		(at 102.6 139)
		(size 0.45)
		(drill 0.1)
		(layers "F.Cu" "B.Cu")
		(net 66)
	)
	(via
		(at 155.3 38.8)
		(size 0.45)
		(drill 0.1)
		(layers "F.Cu" "B.Cu")
		(free yes)
		(net 66)
	)
	(via
		(at 154.5 98.5)
		(size 0.45)
		(drill 0.1)
		(layers "F.Cu" "B.Cu")
		(net 66)
	)
	(via
		(at 145.999999 32)
		(size 0.45)
		(drill 0.1)
		(layers "F.Cu" "B.Cu")
		(net 66)
	)
	(via
		(at 128.499999 32)
		(size 0.45)
		(drill 0.1)
		(layers "F.Cu" "B.Cu")
		(net 66)
	)
	(via
		(at 142 91.8)
		(size 0.45)
		(drill 0.1)
		(layers "F.Cu" "B.Cu")
		(net 66)
	)
	(via
		(at 102.6 59)
		(size 0.45)
		(drill 0.1)
		(layers "F.Cu" "B.Cu")
		(net 66)
	)
	(via
		(at 117.95 46.95)
		(size 0.45)
		(drill 0.1)
		(layers "F.Cu" "B.Cu")
		(net 66)
	)
	(via
		(at 147.812 51.501)
		(size 0.55)
		(drill 0.15)
		(layers "F.Cu" "B.Cu")
		(net 66)
	)
	(via
		(at 137.058 45.926999)
		(size 0.45)
		(drill 0.1)
		(layers "F.Cu" "B.Cu")
		(net 66)
	)
	(via
		(at 140 39.874)
		(size 0.45)
		(drill 0.1)
		(layers "F.Cu" "B.Cu")
		(free yes)
		(net 66)
	)
	(via
		(at 106.1 57.103)
		(size 0.45)
		(drill 0.1)
		(layers "F.Cu" "B.Cu")
		(net 66)
	)
	(via
		(at 158.5 103)
		(size 0.45)
		(drill 0.1)
		(layers "F.Cu" "B.Cu")
		(net 66)
	)
	(via
		(at 116.2 76.1)
		(size 0.45)
		(drill 0.1)
		(layers "F.Cu" "B.Cu")
		(net 66)
	)
	(via
		(at 106.1 74.102)
		(size 0.45)
		(drill 0.1)
		(layers "F.Cu" "B.Cu")
		(net 66)
	)
	(via
		(at 106.1 42.102)
		(size 0.45)
		(drill 0.1)
		(layers "F.Cu" "B.Cu")
		(net 66)
	)
	(via
		(at 128.3 37.3)
		(size 0.45)
		(drill 0.1)
		(layers "F.Cu" "B.Cu")
		(net 66)
	)
	(via
		(at 124.2 128.6)
		(size 0.45)
		(drill 0.1)
		(layers "F.Cu" "B.Cu")
		(free yes)
		(net 66)
	)
	(via
		(at 149.499999 165)
		(size 0.45)
		(drill 0.1)
		(layers "F.Cu" "B.Cu")
		(net 66)
	)
	(via
		(at 116.199999 47.1)
		(size 0.45)
		(drill 0.1)
		(layers "F.Cu" "B.Cu")
		(net 66)
	)
	(via
		(at 123.5 47.4)
		(size 0.45)
		(drill 0.1)
		(layers "F.Cu" "B.Cu")
		(net 66)
	)
	(via
		(at 116.2 99.1)
		(size 0.45)
		(drill 0.1)
		(layers "F.Cu" "B.Cu")
		(net 66)
	)
	(via
		(at 132.6 90.5)
		(size 0.45)
		(drill 0.1)
		(layers "F.Cu" "B.Cu")
		(free yes)
		(net 66)
	)
	(via
		(at 148.4 40.5)
		(size 0.45)
		(drill 0.1)
		(layers "F.Cu" "B.Cu")
		(free yes)
		(net 66)
	)
	(via
		(at 114.5 165)
		(size 0.45)
		(drill 0.1)
		(layers "F.Cu" "B.Cu")
		(net 66)
	)
	(via
		(at 126.63934 48.93934)
		(size 0.45)
		(drill 0.1)
		(layers "F.Cu" "B.Cu")
		(net 66)
	)
	(via
		(at 130.6 92.5)
		(size 0.45)
		(drill 0.1)
		(layers "F.Cu" "B.Cu")
		(free yes)
		(net 66)
	)
	(via
		(at 132.6 91.5)
		(size 0.45)
		(drill 0.1)
		(layers "F.Cu" "B.Cu")
		(free yes)
		(net 66)
	)
	(via
		(at 119.499998 165)
		(size 0.45)
		(drill 0.1)
		(layers "F.Cu" "B.Cu")
		(net 66)
	)
	(via
		(at 112.2 83.8)
		(size 0.45)
		(drill 0.1)
		(layers "F.Cu" "B.Cu")
		(net 66)
	)
	(via
		(at 106.1 58.103)
		(size 0.45)
		(drill 0.1)
		(layers "F.Cu" "B.Cu")
		(net 66)
	)
	(via
		(at 149.302 92.999999)
		(size 0.55)
		(drill 0.15)
		(layers "F.Cu" "B.Cu")
		(net 66)
	)
	(via
		(at 116.199999 59.099)
		(size 0.45)
		(drill 0.1)
		(layers "F.Cu" "B.Cu")
		(net 66)
	)
	(via
		(at 102.6 76.5)
		(size 0.45)
		(drill 0.1)
		(layers "F.Cu" "B.Cu")
		(net 66)
	)
	(via
		(at 139.2 39.874)
		(size 0.45)
		(drill 0.1)
		(layers "F.Cu" "B.Cu")
		(free yes)
		(net 66)
	)
	(via
		(at 102.6 44)
		(size 0.45)
		(drill 0.1)
		(layers "F.Cu" "B.Cu")
		(net 66)
	)
	(via
		(at 144.481999 96.219999)
		(size 0.55)
		(drill 0.15)
		(layers "F.Cu" "B.Cu")
		(net 66)
	)
	(via
		(at 116.199999 52.1)
		(size 0.45)
		(drill 0.1)
		(layers "F.Cu" "B.Cu")
		(net 66)
	)
	(via
		(at 102.6 114)
		(size 0.45)
		(drill 0.1)
		(layers "F.Cu" "B.Cu")
		(net 66)
	)
	(via
		(at 106.1 46.101)
		(size 0.45)
		(drill 0.1)
		(layers "F.Cu" "B.Cu")
		(net 66)
	)
	(via
		(at 130.22 153.999999)
		(size 0.45)
		(drill 0.1)
		(layers "F.Cu" "B.Cu")
		(net 66)
	)
	(via
		(at 106.1 97.1)
		(size 0.45)
		(drill 0.1)
		(layers "F.Cu" "B.Cu")
		(net 66)
	)
	(via
		(at 102.6 69)
		(size 0.45)
		(drill 0.1)
		(layers "F.Cu" "B.Cu")
		(net 66)
	)
	(via
		(at 116.2 44.099999)
		(size 0.45)
		(drill 0.1)
		(layers "F.Cu" "B.Cu")
		(net 66)
	)
	(via
		(at 131.6 91.5)
		(size 0.45)
		(drill 0.1)
		(layers "F.Cu" "B.Cu")
		(free yes)
		(net 66)
	)
	(via
		(at 123.4 130.2)
		(size 0.45)
		(drill 0.1)
		(layers "F.Cu" "B.Cu")
		(free yes)
		(net 66)
	)
	(via
		(at 106.1 53.102)
		(size 0.45)
		(drill 0.1)
		(layers "F.Cu" "B.Cu")
		(net 66)
	)
	(via
		(at 116.2 43.099999)
		(size 0.45)
		(drill 0.1)
		(layers "F.Cu" "B.Cu")
		(net 66)
	)
	(via
		(at 144 133)
		(size 0.45)
		(drill 0.1)
		(layers "F.Cu" "B.Cu")
		(net 66)
	)
	(via
		(at 104.975 95.35)
		(size 0.45)
		(drill 0.1)
		(layers "F.Cu" "B.Cu")
		(net 66)
	)
	(via
		(at 121.999998 165)
		(size 0.45)
		(drill 0.1)
		(layers "F.Cu" "B.Cu")
		(net 66)
	)
	(via
		(at 129.72 157.448999)
		(size 0.45)
		(drill 0.1)
		(layers "F.Cu" "B.Cu")
		(net 66)
	)
	(via
		(at 102.6 89)
		(size 0.45)
		(drill 0.1)
		(layers "F.Cu" "B.Cu")
		(net 66)
	)
	(via
		(at 130.3 41.1)
		(size 0.45)
		(drill 0.1)
		(layers "F.Cu" "B.Cu")
		(net 66)
	)
	(via
		(at 153.737 58.525999)
		(size 0.55)
		(drill 0.15)
		(layers "F.Cu" "B.Cu")
		(net 66)
	)
	(via
		(at 106.1 49.103)
		(size 0.45)
		(drill 0.1)
		(layers "F.Cu" "B.Cu")
		(net 66)
	)
	(via
		(at 116.199999 68.099)
		(size 0.45)
		(drill 0.1)
		(layers "F.Cu" "B.Cu")
		(net 66)
	)
	(via
		(at 124.2 130.2)
		(size 0.45)
		(drill 0.1)
		(layers "F.Cu" "B.Cu")
		(free yes)
		(net 66)
	)
	(via
		(at 102.6 91.5)
		(size 0.45)
		(drill 0.1)
		(layers "F.Cu" "B.Cu")
		(net 66)
	)
	(via
		(at 122.074999 147.855)
		(size 0.45)
		(drill 0.1)
		(layers "F.Cu" "B.Cu")
		(net 66)
	)
	(via
		(at 144 41.2)
		(size 0.45)
		(drill 0.1)
		(layers "F.Cu" "B.Cu")
		(net 66)
	)
	(via
		(at 158.5 153)
		(size 0.45)
		(drill 0.1)
		(layers "F.Cu" "B.Cu")
		(net 66)
	)
	(via
		(at 105 89.85)
		(size 0.45)
		(drill 0.1)
		(layers "F.Cu" "B.Cu")
		(net 66)
	)
	(via
		(at 116.199999 64.099)
		(size 0.45)
		(drill 0.1)
		(layers "F.Cu" "B.Cu")
		(net 66)
	)
	(via
		(at 145.412 52.001)
		(size 0.55)
		(drill 0.15)
		(layers "F.Cu" "B.Cu")
		(net 66)
	)
	(via
		(at 128.53934 49.23934)
		(size 0.45)
		(drill 0.1)
		(layers "F.Cu" "B.Cu")
		(net 66)
	)
	(via
		(at 123.6 123.2)
		(size 0.45)
		(drill 0.1)
		(layers "F.Cu" "B.Cu")
		(net 66)
	)
	(via
		(at 158.5 75.5)
		(size 0.45)
		(drill 0.1)
		(layers "F.Cu" "B.Cu")
		(net 66)
	)
	(via
		(at 144 108.4)
		(size 0.45)
		(drill 0.1)
		(layers "F.Cu" "B.Cu")
		(net 66)
	)
	(via
		(at 149.4 85.3)
		(size 0.45)
		(drill 0.1)
		(layers "F.Cu" "B.Cu")
		(net 66)
	)
	(via
		(at 149.302 92.000001)
		(size 0.55)
		(drill 0.15)
		(layers "F.Cu" "B.Cu")
		(net 66)
	)
	(via
		(at 147.2 64)
		(size 0.45)
		(drill 0.1)
		(layers "F.Cu" "B.Cu")
		(net 66)
	)
	(via
		(at 133.6265 72.443001)
		(size 0.45)
		(drill 0.1)
		(layers "F.Cu" "B.Cu")
		(net 66)
	)
	(via
		(at 116.2 81.1)
		(size 0.45)
		(drill 0.1)
		(layers "F.Cu" "B.Cu")
		(net 66)
	)
	(via
		(at 106.1 54.102)
		(size 0.45)
		(drill 0.1)
		(layers "F.Cu" "B.Cu")
		(net 66)
	)
	(via
		(at 137.0265 72.443001)
		(size 0.45)
		(drill 0.1)
		(layers "F.Cu" "B.Cu")
		(net 66)
	)
	(via
		(at 144.7 91.8)
		(size 0.45)
		(drill 0.1)
		(layers "F.Cu" "B.Cu")
		(net 66)
	)
	(via
		(at 147.6 39.7)
		(size 0.45)
		(drill 0.1)
		(layers "F.Cu" "B.Cu")
		(free yes)
		(net 66)
	)
	(via
		(at 130.298 42.287)
		(size 0.45)
		(drill 0.1)
		(layers "F.Cu" "B.Cu")
		(net 66)
	)
	(via
		(at 136.999999 165)
		(size 0.45)
		(drill 0.1)
		(layers "F.Cu" "B.Cu")
		(net 66)
	)
	(via
		(at 102.6 66.5)
		(size 0.45)
		(drill 0.1)
		(layers "F.Cu" "B.Cu")
		(net 66)
	)
	(via
		(at 106.1 96.1)
		(size 0.45)
		(drill 0.1)
		(layers "F.Cu" "B.Cu")
		(net 66)
	)
	(via
		(at 116.199999 60.099)
		(size 0.45)
		(drill 0.1)
		(layers "F.Cu" "B.Cu")
		(net 66)
	)
	(via
		(at 116.199999 67.099)
		(size 0.45)
		(drill 0.1)
		(layers "F.Cu" "B.Cu")
		(net 66)
	)
	(via
		(at 156.9 38.8)
		(size 0.45)
		(drill 0.1)
		(layers "F.Cu" "B.Cu")
		(free yes)
		(net 66)
	)
	(via
		(at 142.581 45.864998)
		(size 0.45)
		(drill 0.1)
		(layers "F.Cu" "B.Cu")
		(net 66)
	)
	(via
		(at 116.448 115.1)
		(size 0.45)
		(drill 0.1)
		(layers "F.Cu" "B.Cu")
		(net 66)
	)
	(via
		(at 116.199999 63.099)
		(size 0.45)
		(drill 0.1)
		(layers "F.Cu" "B.Cu")
		(net 66)
	)
	(via
		(at 145.412 53.000999)
		(size 0.55)
		(drill 0.15)
		(layers "F.Cu" "B.Cu")
		(net 66)
	)
	(via
		(at 106.1 65.101)
		(size 0.45)
		(drill 0.1)
		(layers "F.Cu" "B.Cu")
		(net 66)
	)
	(via
		(at 141 144.5)
		(size 0.45)
		(drill 0.1)
		(layers "F.Cu" "B.Cu")
		(net 66)
	)
	(via
		(at 102.6 104)
		(size 0.45)
		(drill 0.1)
		(layers "F.Cu" "B.Cu")
		(net 66)
	)
	(via
		(at 131.6 92.5)
		(size 0.45)
		(drill 0.1)
		(layers "F.Cu" "B.Cu")
		(free yes)
		(net 66)
	)
	(via
		(at 102.6 46.5)
		(size 0.45)
		(drill 0.1)
		(layers "F.Cu" "B.Cu")
		(net 66)
	)
	(via
		(at 158.5 70.5)
		(size 0.45)
		(drill 0.1)
		(layers "F.Cu" "B.Cu")
		(net 66)
	)
	(via
		(at 125.574998 149.534999)
		(size 0.55)
		(drill 0.15)
		(layers "F.Cu" "B.Cu")
		(net 66)
	)
	(via
		(at 158.5 90.5)
		(size 0.45)
		(drill 0.1)
		(layers "F.Cu" "B.Cu")
		(net 66)
	)
	(via
		(at 116.2 107.1)
		(size 0.45)
		(drill 0.1)
		(layers "F.Cu" "B.Cu")
		(net 66)
	)
	(via
		(at 122.4 136.4)
		(size 0.45)
		(drill 0.1)
		(layers "F.Cu" "B.Cu")
		(free yes)
		(net 66)
	)
	(via
		(at 122.8 41.1)
		(size 0.45)
		(drill 0.1)
		(layers "F.Cu" "B.Cu")
		(net 66)
	)
	(via
		(at 139.2 41.474)
		(size 0.45)
		(drill 0.1)
		(layers "F.Cu" "B.Cu")
		(free yes)
		(net 66)
	)
	(via
		(at 149.5 118.75)
		(size 0.45)
		(drill 0.1)
		(layers "F.Cu" "B.Cu")
		(net 66)
	)
	(via
		(at 122.099999 117.8)
		(size 0.45)
		(drill 0.1)
		(layers "F.Cu" "B.Cu")
		(net 66)
	)
	(via
		(at 147.6 40.5)
		(size 0.45)
		(drill 0.1)
		(layers "F.Cu" "B.Cu")
		(free yes)
		(net 66)
	)
	(via
		(at 131.6 90.5)
		(size 0.45)
		(drill 0.1)
		(layers "F.Cu" "B.Cu")
		(free yes)
		(net 66)
	)
	(via
		(at 106.1 79.102)
		(size 0.45)
		(drill 0.1)
		(layers "F.Cu" "B.Cu")
		(net 66)
	)
	(via
		(at 149.5 113.75)
		(size 0.45)
		(drill 0.1)
		(layers "F.Cu" "B.Cu")
		(net 66)
	)
	(via
		(at 156.9 38)
		(size 0.45)
		(drill 0.1)
		(layers "F.Cu" "B.Cu")
		(free yes)
		(net 66)
	)
	(via
		(at 102.6 156.5)
		(size 0.45)
		(drill 0.1)
		(layers "F.Cu" "B.Cu")
		(net 66)
	)
	(via
		(at 130.6 88.5)
		(size 0.45)
		(drill 0.1)
		(layers "F.Cu" "B.Cu")
		(free yes)
		(net 66)
	)
	(via
		(at 156.1 36.4)
		(size 0.45)
		(drill 0.1)
		(layers "F.Cu" "B.Cu")
		(free yes)
		(net 66)
	)
	(via
		(at 146.9 80.6)
		(size 0.45)
		(drill 0.1)
		(layers "F.Cu" "B.Cu")
		(net 66)
	)
	(via
		(at 141.003 119.905999)
		(size 0.45)
		(drill 0.1)
		(layers "F.Cu" "B.Cu")
		(net 66)
	)
	(via
		(at 124.2 127.8)
		(size 0.45)
		(drill 0.1)
		(layers "F.Cu" "B.Cu")
		(free yes)
		(net 66)
	)
	(via
		(at 158.5 73)
		(size 0.45)
		(drill 0.1)
		(layers "F.Cu" "B.Cu")
		(net 66)
	)
	(via
		(at 147.65 65.1)
		(size 0.45)
		(drill 0.1)
		(layers "F.Cu" "B.Cu")
		(net 66)
	)
	(via
		(at 106.1 108.1)
		(size 0.45)
		(drill 0.1)
		(layers "F.Cu" "B.Cu")
		(net 66)
	)
	(via
		(at 156.1 34.8)
		(size 0.45)
		(drill 0.1)
		(layers "F.Cu" "B.Cu")
		(free yes)
		(net 66)
	)
	(via
		(at 123.4 128.6)
		(size 0.45)
		(drill 0.1)
		(layers "F.Cu" "B.Cu")
		(free yes)
		(net 66)
	)
	(via
		(at 102.6 61.5)
		(size 0.45)
		(drill 0.1)
		(layers "F.Cu" "B.Cu")
		(net 66)
	)
	(via
		(at 102.6 126.5)
		(size 0.45)
		(drill 0.1)
		(layers "F.Cu" "B.Cu")
		(net 66)
	)
	(via
		(at 102.6 109)
		(size 0.45)
		(drill 0.1)
		(layers "F.Cu" "B.Cu")
		(net 66)
	)
	(via
		(at 105 117.900001)
		(size 0.45)
		(drill 0.1)
		(layers "F.Cu" "B.Cu")
		(net 66)
	)
	(segment
		(start 105.525 90.401)
		(end 105.4 90.276)
		(width 0.2)
		(layer "F.Cu")
		(net 67)
	)
	(segment
		(start 123.3 42.587499)
		(end 123.3 43)
		(width 0.2)
		(layer "F.Cu")
		(net 67)
	)
	(segment
		(start 123.3 44.184501)
		(end 123.3 43.772)
		(width 0.2)
		(layer "F.Cu")
		(net 67)
	)
	(segment
		(start 123.3 40.987501)
		(end 123.35 41.037501)
		(width 0.2)
		(layer "F.Cu")
		(net 67)
	)
	(segment
		(start 123.35 45.967157)
		(end 123.35 44.234501)
		(width 0.2)
		(layer "F.Cu")
		(net 67)
	)
	(segment
		(start 123.35 44.234501)
		(end 123.3 44.184501)
		(width 0.2)
		(layer "F.Cu")
		(net 67)
	)
	(segment
		(start 122.77019 46.37019)
		(end 122.946967 46.37019)
		(width 0.2)
		(layer "F.Cu")
		(net 67)
	)
	(segment
		(start 107.574 90.101)
		(end 106.839 90.101)
		(width 0.2)
		(layer "F.Cu")
		(net 67)
	)
	(segment
		(start 123.35 42.537499)
		(end 123.3 42.587499)
		(width 0.2)
		(layer "F.Cu")
		(net 67)
	)
	(segment
		(start 122.946967 46.37019)
		(end 123.35 45.967157)
		(width 0.2)
		(layer "F.Cu")
		(net 67)
	)
	(segment
		(start 123.35 41.037501)
		(end 123.35 42.537499)
		(width 0.2)
		(layer "F.Cu")
		(net 67)
	)
	(segment
		(start 106.839 90.101)
		(end 106.539 90.401)
		(width 0.2)
		(layer "F.Cu")
		(net 67)
	)
	(segment
		(start 123.3 43.772)
		(end 123.3 43)
		(width 0.2)
		(layer "F.Cu")
		(net 67)
	)
	(segment
		(start 106.539 90.401)
		(end 105.525 90.401)
		(width 0.2)
		(layer "F.Cu")
		(net 67)
	)
	(segment
		(start 123.3 40.305)
		(end 123.3 40.987501)
		(width 0.2)
		(layer "F.Cu")
		(net 67)
	)
	(via
		(at 105.4 90.276)
		(size 0.45)
		(drill 0.1)
		(layers "F.Cu" "B.Cu")
		(net 67)
	)
	(via
		(at 122.77019 46.37019)
		(size 0.45)
		(drill 0.1)
		(layers "F.Cu" "B.Cu")
		(net 67)
	)
	(segment
		(start 110.833162 87.223946)
		(end 110.918017 87.139092)
		(width 0.2)
		(layer "B.Cu")
		(net 67)
	)
	(segment
		(start 105.525 90.401)
		(end 108.416156 90.401)
		(width 0.2)
		(layer "B.Cu")
		(net 67)
	)
	(segment
		(start 108.416156 90.401)
		(end 110.873775 87.943381)
		(width 0.2)
		(layer "B.Cu")
		(net 67)
	)
	(segment
		(start 115 83.817156)
		(end 115 54.317157)
		(width 0.2)
		(layer "B.Cu")
		(net 67)
	)
	(segment
		(start 111.257427 87.139093)
		(end 111.298041 87.179707)
		(width 0.2)
		(layer "B.Cu")
		(net 67)
	)
	(segment
		(start 111.722305 87.094852)
		(end 115 83.817156)
		(width 0.2)
		(layer "B.Cu")
		(net 67)
	)
	(segment
		(start 115 54.317157)
		(end 122.77019 46.546967)
		(width 0.2)
		(layer "B.Cu")
		(net 67)
	)
	(segment
		(start 111.637453 87.179706)
		(end 111.722305 87.094852)
		(width 0.2)
		(layer "B.Cu")
		(net 67)
	)
	(segment
		(start 110.873776 87.603969)
		(end 110.833163 87.563356)
		(width 0.2)
		(layer "B.Cu")
		(net 67)
	)
	(segment
		(start 105.4 90.276)
		(end 105.525 90.401)
		(width 0.2)
		(layer "B.Cu")
		(net 67)
	)
	(segment
		(start 122.77019 46.546967)
		(end 122.77019 46.37019)
		(width 0.2)
		(layer "B.Cu")
		(net 67)
	)
	(arc
		(start 110.833163 87.563356)
		(mid 110.762869 87.39365)
		(end 110.833162 87.223946)
		(width 0.2)
		(layer "B.Cu")
		(net 67)
	)
	(arc
		(start 110.918017 87.139092)
		(mid 111.087722 87.068798)
		(end 111.257427 87.139093)
		(width 0.2)
		(layer "B.Cu")
		(net 67)
	)
	(arc
		(start 110.873775 87.943381)
		(mid 110.94407 87.773675)
		(end 110.873776 87.603969)
		(width 0.2)
		(layer "B.Cu")
		(net 67)
	)
	(arc
		(start 111.298041 87.179707)
		(mid 111.467746 87.250002)
		(end 111.637453 87.179706)
		(width 0.2)
		(layer "B.Cu")
		(net 67)
	)
	(segment
		(start 105.525 90.801)
		(end 105.4 90.926)
		(width 0.2)
		(layer "F.Cu")
		(net 68)
	)
	(segment
		(start 123.75 46.132843)
		(end 123.75 44.234501)
		(width 0.2)
		(layer "F.Cu")
		(net 68)
	)
	(segment
		(start 123.8 43.772)
		(end 123.8 43)
		(width 0.2)
		(layer "F.Cu")
		(net 68)
	)
	(segment
		(start 123.75 42.537499)
		(end 123.8 42.587499)
		(width 0.2)
		(layer "F.Cu")
		(net 68)
	)
	(segment
		(start 106.539 90.801)
		(end 105.525 90.801)
		(width 0.2)
		(layer "F.Cu")
		(net 68)
	)
	(segment
		(start 123.8 40.305)
		(end 123.8 40.987501)
		(width 0.2)
		(layer "F.Cu")
		(net 68)
	)
	(segment
		(start 107.574 91.101)
		(end 106.839 91.101)
		(width 0.2)
		(layer "F.Cu")
		(net 68)
	)
	(segment
		(start 123.22981 46.653033)
		(end 123.75 46.132843)
		(width 0.2)
		(layer "F.Cu")
		(net 68)
	)
	(segment
		(start 123.75 44.234501)
		(end 123.8 44.184501)
		(width 0.2)
		(layer "F.Cu")
		(net 68)
	)
	(segment
		(start 123.75 41.037501)
		(end 123.75 42.537499)
		(width 0.2)
		(layer "F.Cu")
		(net 68)
	)
	(segment
		(start 123.8 44.184501)
		(end 123.8 43.772)
		(width 0.2)
		(layer "F.Cu")
		(net 68)
	)
	(segment
		(start 106.839 91.101)
		(end 106.539 90.801)
		(width 0.2)
		(layer "F.Cu")
		(net 68)
	)
	(segment
		(start 123.8 42.587499)
		(end 123.8 43)
		(width 0.2)
		(layer "F.Cu")
		(net 68)
	)
	(segment
		(start 123.22981 46.82981)
		(end 123.22981 46.653033)
		(width 0.2)
		(layer "F.Cu")
		(net 68)
	)
	(segment
		(start 123.8 40.987501)
		(end 123.75 41.037501)
		(width 0.2)
		(layer "F.Cu")
		(net 68)
	)
	(via
		(at 123.22981 46.82981)
		(size 0.45)
		(drill 0.1)
		(layers "F.Cu" "B.Cu")
		(net 68)
	)
	(via
		(at 105.4 90.926)
		(size 0.45)
		(drill 0.1)
		(layers "F.Cu" "B.Cu")
		(net 68)
	)
	(segment
		(start 115.4 54.482843)
		(end 115.4 83.982844)
		(width 0.2)
		(layer "B.Cu")
		(net 68)
	)
	(segment
		(start 105.525 90.801)
		(end 105.4 90.926)
		(width 0.2)
		(layer "B.Cu")
		(net 68)
	)
	(segment
		(start 108.581844 90.801)
		(end 105.525 90.801)
		(width 0.2)
		(layer "B.Cu")
		(net 68)
	)
	(segment
		(start 123.22981 46.82981)
		(end 123.053033 46.82981)
		(width 0.2)
		(layer "B.Cu")
		(net 68)
	)
	(segment
		(start 123.053033 46.82981)
		(end 115.4 54.482843)
		(width 0.2)
		(layer "B.Cu")
		(net 68)
	)
	(segment
		(start 115.4 83.982844)
		(end 108.581844 90.801)
		(width 0.2)
		(layer "B.Cu")
		(net 68)
	)
	(segment
		(start 115.809 100.4)
		(end 117.217156 100.4)
		(width 0.2)
		(layer "F.Cu")
		(net 69)
	)
	(segment
		(start 123.1 94.517156)
		(end 123.1 67.417156)
		(width 0.2)
		(layer "F.Cu")
		(net 69)
	)
	(segment
		(start 137.581 47.399)
		(end 137.581 46.627)
		(width 0.2)
		(layer "F.Cu")
		(net 69)
	)
	(segment
		(start 128.85 37.025)
		(end 128.725 36.9)
		(width 0.2)
		(layer "F.Cu")
		(net 69)
	)
	(segment
		(start 120.263587 97.353572)
		(end 120.348439 97.268718)
		(width 0.2)
		(layer "F.Cu")
		(net 69)
	)
	(segment
		(start 128.8 37.432499)
		(end 128.85 37.382499)
		(width 0.2)
		(layer "F.Cu")
		(net 69)
	)
	(segment
		(start 114.774 100.1)
		(end 115.509 100.1)
		(width 0.2)
		(layer "F.Cu")
		(net 69)
	)
	(segment
		(start 137.631 52.886156)
		(end 137.631 47.861501)
		(width 0.2)
		(layer "F.Cu")
		(net 69)
	)
	(segment
		(start 137.631 47.861501)
		(end 137.581 47.811501)
		(width 0.2)
		(layer "F.Cu")
		(net 69)
	)
	(segment
		(start 137.631 45.539)
		(end 137.506 45.414)
		(width 0.2)
		(layer "F.Cu")
		(net 69)
	)
	(segment
		(start 128.8 38.115)
		(end 128.8 37.432499)
		(width 0.2)
		(layer "F.Cu")
		(net 69)
	)
	(segment
		(start 119.459338 97.397854)
		(end 119.544193 97.313)
		(width 0.2)
		(layer "F.Cu")
		(net 69)
	)
	(segment
		(start 137.581 46.627)
		(end 137.581 46.214499)
		(width 0.2)
		(layer "F.Cu")
		(net 69)
	)
	(segment
		(start 120.348439 97.268718)
		(end 123.1 94.517156)
		(width 0.2)
		(layer "F.Cu")
		(net 69)
	)
	(segment
		(start 119.883603 97.313001)
		(end 119.924175 97.353573)
		(width 0.2)
		(layer "F.Cu")
		(net 69)
	)
	(segment
		(start 115.509 100.1)
		(end 115.809 100.4)
		(width 0.2)
		(layer "F.Cu")
		(net 69)
	)
	(segment
		(start 128.85 37.382499)
		(end 128.85 37.025)
		(width 0.2)
		(layer "F.Cu")
		(net 69)
	)
	(segment
		(start 123.1 67.417156)
		(end 137.631 52.886156)
		(width 0.2)
		(layer "F.Cu")
		(net 69)
	)
	(segment
		(start 117.217156 100.4)
		(end 119.499909 98.117247)
		(width 0.2)
		(layer "F.Cu")
		(net 69)
	)
	(segment
		(start 137.581 47.811501)
		(end 137.581 47.399)
		(width 0.2)
		(layer "F.Cu")
		(net 69)
	)
	(segment
		(start 137.581 46.214499)
		(end 137.631 46.164499)
		(width 0.2)
		(layer "F.Cu")
		(net 69)
	)
	(segment
		(start 119.49991 97.777835)
		(end 119.459339 97.737264)
		(width 0.2)
		(layer "F.Cu")
		(net 69)
	)
	(segment
		(start 137.631 46.164499)
		(end 137.631 45.539)
		(width 0.2)
		(layer "F.Cu")
		(net 69)
	)
	(via
		(at 128.725 36.9)
		(size 0.45)
		(drill 0.1)
		(layers "F.Cu" "B.Cu")
		(net 69)
	)
	(via
		(at 137.506 45.414)
		(size 0.45)
		(drill 0.1)
		(layers "F.Cu" "B.Cu")
		(net 69)
	)
	(arc
		(start 119.459339 97.737264)
		(mid 119.389045 97.567558)
		(end 119.459338 97.397854)
		(width 0.2)
		(layer "F.Cu")
		(net 69)
	)
	(arc
		(start 119.924175 97.353573)
		(mid 120.09388 97.423868)
		(end 120.263587 97.353572)
		(width 0.2)
		(layer "F.Cu")
		(net 69)
	)
	(arc
		(start 119.499909 98.117247)
		(mid 119.570204 97.947541)
		(end 119.49991 97.777835)
		(width 0.2)
		(layer "F.Cu")
		(net 69)
	)
	(arc
		(start 119.544193 97.313)
		(mid 119.713898 97.242706)
		(end 119.883603 97.313001)
		(width 0.2)
		(layer "F.Cu")
		(net 69)
	)
	(segment
		(start 137.631 44.313844)
		(end 137.631 45.289)
		(width 0.2)
		(layer "B.Cu")
		(net 69)
	)
	(segment
		(start 128.85 37.025)
		(end 128.85 39.732844)
		(width 0.2)
		(layer "B.Cu")
		(net 69)
	)
	(segment
		(start 137.631 45.289)
		(end 137.506 45.414)
		(width 0.2)
		(layer "B.Cu")
		(net 69)
	)
	(segment
		(start 133.717156 40.4)
		(end 137.631 44.313844)
		(width 0.2)
		(layer "B.Cu")
		(net 69)
	)
	(segment
		(start 129.517156 40.4)
		(end 133.717156 40.4)
		(width 0.2)
		(layer "B.Cu")
		(net 69)
	)
	(segment
		(start 128.85 39.732844)
		(end 129.517156 40.4)
		(width 0.2)
		(layer "B.Cu")
		(net 69)
	)
	(segment
		(start 128.725 36.9)
		(end 128.85 37.025)
		(width 0.2)
		(layer "B.Cu")
		(net 69)
	)
	(segment
		(start 115.509 97.1)
		(end 115.809 96.8)
		(width 0.2)
		(layer "F.Cu")
		(net 70)
	)
	(segment
		(start 114.774 97.1)
		(end 115.509 97.1)
		(width 0.2)
		(layer "F.Cu")
		(net 70)
	)
	(segment
		(start 135.55 46.151499)
		(end 135.55 45.489)
		(width 0.2)
		(layer "F.Cu")
		(net 70)
	)
	(segment
		(start 135.6 46.614)
		(end 135.6 46.201499)
		(width 0.2)
		(layer "F.Cu")
		(net 70)
	)
	(segment
		(start 124.8 37.432499)
		(end 124.75 37.382499)
		(width 0.2)
		(layer "F.Cu")
		(net 70)
	)
	(segment
		(start 117.182844 96.8)
		(end 121.1 92.882844)
		(width 0.2)
		(layer "F.Cu")
		(net 70)
	)
	(segment
		(start 135.55 51.932844)
		(end 135.55 47.848501)
		(width 0.2)
		(layer "F.Cu")
		(net 70)
	)
	(segment
		(start 135.55 47.848501)
		(end 135.6 47.798501)
		(width 0.2)
		(layer "F.Cu")
		(net 70)
	)
	(segment
		(start 135.55 45.489)
		(end 135.675 45.364)
		(width 0.2)
		(layer "F.Cu")
		(net 70)
	)
	(segment
		(start 135.6 46.201499)
		(end 135.55 46.151499)
		(width 0.2)
		(layer "F.Cu")
		(net 70)
	)
	(segment
		(start 115.809 96.8)
		(end 117.182844 96.8)
		(width 0.2)
		(layer "F.Cu")
		(net 70)
	)
	(segment
		(start 135.6 47.798501)
		(end 135.6 47.386)
		(width 0.2)
		(layer "F.Cu")
		(net 70)
	)
	(segment
		(start 124.8 38.115)
		(end 124.8 37.432499)
		(width 0.2)
		(layer "F.Cu")
		(net 70)
	)
	(segment
		(start 135.6 47.386)
		(end 135.6 46.614)
		(width 0.2)
		(layer "F.Cu")
		(net 70)
	)
	(segment
		(start 124.75 37.382499)
		(end 124.75 37.025)
		(width 0.2)
		(layer "F.Cu")
		(net 70)
	)
	(segment
		(start 121.1 66.382844)
		(end 135.55 51.932844)
		(width 0.2)
		(layer "F.Cu")
		(net 70)
	)
	(segment
		(start 121.1 92.882844)
		(end 121.1 66.382844)
		(width 0.2)
		(layer "F.Cu")
		(net 70)
	)
	(segment
		(start 124.75 37.025)
		(end 124.875 36.9)
		(width 0.2)
		(layer "F.Cu")
		(net 70)
	)
	(via
		(at 135.675 45.364)
		(size 0.45)
		(drill 0.1)
		(layers "F.Cu" "B.Cu")
		(net 70)
	)
	(via
		(at 124.875 36.9)
		(size 0.45)
		(drill 0.1)
		(layers "F.Cu" "B.Cu")
		(net 70)
	)
	(segment
		(start 135.55 44.067156)
		(end 135.55 45.239)
		(width 0.2)
		(layer "B.Cu")
		(net 70)
	)
	(segment
		(start 126.082844 42.8)
		(end 134.282844 42.8)
		(width 0.2)
		(layer "B.Cu")
		(net 70)
	)
	(segment
		(start 124.875 36.9)
		(end 124.75 37.025)
		(width 0.2)
		(layer "B.Cu")
		(net 70)
	)
	(segment
		(start 134.282844 42.8)
		(end 135.55 44.067156)
		(width 0.2)
		(layer "B.Cu")
		(net 70)
	)
	(segment
		(start 124.75 37.025)
		(end 124.75 38.967156)
		(width 0.2)
		(layer "B.Cu")
		(net 70)
	)
	(segment
		(start 124.75 38.967156)
		(end 125.2 39.417156)
		(width 0.2)
		(layer "B.Cu")
		(net 70)
	)
	(segment
		(start 125.2 41.917156)
		(end 126.082844 42.8)
		(width 0.2)
		(layer "B.Cu")
		(net 70)
	)
	(segment
		(start 135.55 45.239)
		(end 135.675 45.364)
		(width 0.2)
		(layer "B.Cu")
		(net 70)
	)
	(segment
		(start 125.2 39.417156)
		(end 125.2 41.917156)
		(width 0.2)
		(layer "B.Cu")
		(net 70)
	)
	(segment
		(start 129.3 40.987501)
		(end 129.3 40.305)
		(width 0.2)
		(layer "F.Cu")
		(net 71)
	)
	(segment
		(start 129.3 42.587499)
		(end 129.35 42.537499)
		(width 0.2)
		(layer "F.Cu")
		(net 71)
	)
	(segment
		(start 129.3 43)
		(end 129.3 43.772)
		(width 0.2)
		(layer "F.Cu")
		(net 71)
	)
	(segment
		(start 129.3 43)
		(end 129.3 42.587499)
		(width 0.2)
		(layer "F.Cu")
		(net 71)
	)
	(segment
		(start 106.839 98.1)
		(end 106.539 98.4)
		(width 0.2)
		(layer "F.Cu")
		(net 71)
	)
	(segment
		(start 129.3 44.184501)
		(end 129.35 44.234501)
		(width 0.2)
		(layer "F.Cu")
		(net 71)
	)
	(segment
		(start 127.446967 48.77019)
		(end 127.27019 48.77019)
		(width 0.2)
		(layer "F.Cu")
		(net 71)
	)
	(segment
		(start 129.35 42.537499)
		(end 129.35 41.037501)
		(width 0.2)
		(layer "F.Cu")
		(net 71)
	)
	(segment
		(start 107.574 98.1)
		(end 106.839 98.1)
		(width 0.2)
		(layer "F.Cu")
		(net 71)
	)
	(segment
		(start 129.35 41.037501)
		(end 129.3 40.987501)
		(width 0.2)
		(layer "F.Cu")
		(net 71)
	)
	(segment
		(start 106.539 98.4)
		(end 105.525 98.4)
		(width 0.2)
		(layer "F.Cu")
		(net 71)
	)
	(segment
		(start 105.525 98.4)
		(end 105.4 98.275)
		(width 0.2)
		(layer "F.Cu")
		(net 71)
	)
	(segment
		(start 129.35 46.867157)
		(end 127.446967 48.77019)
		(width 0.2)
		(layer "F.Cu")
		(net 71)
	)
	(segment
		(start 129.3 43.772)
		(end 129.3 44.184501)
		(width 0.2)
		(layer "F.Cu")
		(net 71)
	)
	(segment
		(start 129.35 44.234501)
		(end 129.35 46.867157)
		(width 0.2)
		(layer "F.Cu")
		(net 71)
	)
	(via
		(at 127.27019 48.77019)
		(size 0.45)
		(drill 0.1)
		(layers "F.Cu" "B.Cu")
		(net 71)
	)
	(via
		(at 105.4 98.275)
		(size 0.45)
		(drill 0.1)
		(layers "F.Cu" "B.Cu")
		(net 71)
	)
	(segment
		(start 120.6 55.617157)
		(end 120.6 91.417156)
		(width 0.2)
		(layer "B.Cu")
		(net 71)
	)
	(segment
		(start 120.6 91.417156)
		(end 118.585357 93.431799)
		(width 0.2)
		(layer "B.Cu")
		(net 71)
	)
	(segment
		(start 118.245945 93.431799)
		(end 118.205381 93.391235)
		(width 0.2)
		(layer "B.Cu")
		(net 71)
	)
	(segment
		(start 117.781117 93.815499)
		(end 117.82168 93.856062)
		(width 0.2)
		(layer "B.Cu")
		(net 71)
	)
	(segment
		(start 113.617156 98.4)
		(end 105.525 98.4)
		(width 0.2)
		(layer "B.Cu")
		(net 71)
	)
	(segment
		(start 127.27019 48.946967)
		(end 120.6 55.617157)
		(width 0.2)
		(layer "B.Cu")
		(net 71)
	)
	(segment
		(start 117.86597 93.391235)
		(end 117.781117 93.476087)
		(width 0.2)
		(layer "B.Cu")
		(net 71)
	)
	(segment
		(start 127.27019 48.77019)
		(end 127.27019 48.946967)
		(width 0.2)
		(layer "B.Cu")
		(net 71)
	)
	(segment
		(start 105.525 98.4)
		(end 105.4 98.275)
		(width 0.2)
		(layer "B.Cu")
		(net 71)
	)
	(segment
		(start 117.82168 94.195473)
		(end 117.736828 94.280327)
		(width 0.2)
		(layer "B.Cu")
		(net 71)
	)
	(segment
		(start 113.617156 98.4)
		(end 117.736828 94.280327)
		(width 0.2)
		(layer "B.Cu")
		(net 71)
	)
	(arc
		(start 118.585357 93.431799)
		(mid 118.415651 93.502094)
		(end 118.245945 93.431799)
		(width 0.2)
		(layer "B.Cu")
		(net 71)
	)
	(arc
		(start 117.781117 93.476087)
		(mid 117.710822 93.645793)
		(end 117.781117 93.815499)
		(width 0.2)
		(layer "B.Cu")
		(net 71)
	)
	(arc
		(start 118.205381 93.391235)
		(mid 118.035676 93.32094)
		(end 117.86597 93.391235)
		(width 0.2)
		(layer "B.Cu")
		(net 71)
	)
	(arc
		(start 117.82168 93.856062)
		(mid 117.891974 94.025768)
		(end 117.82168 94.195473)
		(width 0.2)
		(layer "B.Cu")
		(net 71)
	)
	(segment
		(start 130.75 37.382499)
		(end 130.75 37.025)
		(width 0.2)
		(layer "F.Cu")
		(net 72)
	)
	(segment
		(start 115.809 105.8)
		(end 118.182844 105.8)
		(width 0.2)
		(layer "F.Cu")
		(net 72)
	)
	(segment
		(start 118.182844 105.8)
		(end 125.7 98.282844)
		(width 0.2)
		(layer "F.Cu")
		(net 72)
	)
	(segment
		(start 139.529 46.164499)
		(end 139.529 45.539)
		(width 0.2)
		(layer "F.Cu")
		(net 72)
	)
	(segment
		(start 139.579 47.811501)
		(end 139.579 47.399)
		(width 0.2)
		(layer "F.Cu")
		(net 72)
	)
	(segment
		(start 139.529 47.861501)
		(end 139.579 47.811501)
		(width 0.2)
		(layer "F.Cu")
		(net 72)
	)
	(segment
		(start 114.774 106.1)
		(end 115.509 106.1)
		(width 0.2)
		(layer "F.Cu")
		(net 72)
	)
	(segment
		(start 139.579 46.214499)
		(end 139.529 46.164499)
		(width 0.2)
		(layer "F.Cu")
		(net 72)
	)
	(segment
		(start 115.509 106.1)
		(end 115.809 105.8)
		(width 0.2)
		(layer "F.Cu")
		(net 72)
	)
	(segment
		(start 139.529 45.539)
		(end 139.654 45.414)
		(width 0.2)
		(layer "F.Cu")
		(net 72)
	)
	(segment
		(start 139.579 47.399)
		(end 139.579 46.627)
		(width 0.2)
		(layer "F.Cu")
		(net 72)
	)
	(segment
		(start 130.75 37.025)
		(end 130.875 36.9)
		(width 0.2)
		(layer "F.Cu")
		(net 72)
	)
	(segment
		(start 139.579 46.627)
		(end 139.579 46.214499)
		(width 0.2)
		(layer "F.Cu")
		(net 72)
	)
	(segment
		(start 125.7 98.282844)
		(end 125.7 68.382844)
		(width 0.2)
		(layer "F.Cu")
		(net 72)
	)
	(segment
		(start 139.529 54.553844)
		(end 139.529 47.861501)
		(width 0.2)
		(layer "F.Cu")
		(net 72)
	)
	(segment
		(start 130.8 37.432499)
		(end 130.75 37.382499)
		(width 0.2)
		(layer "F.Cu")
		(net 72)
	)
	(segment
		(start 125.7 68.382844)
		(end 139.529 54.553844)
		(width 0.2)
		(layer "F.Cu")
		(net 72)
	)
	(segment
		(start 130.8 38.115)
		(end 130.8 37.432499)
		(width 0.2)
		(layer "F.Cu")
		(net 72)
	)
	(via
		(at 130.875 36.9)
		(size 0.45)
		(drill 0.1)
		(layers "F.Cu" "B.Cu")
		(net 72)
	)
	(via
		(at 139.654 45.414)
		(size 0.45)
		(drill 0.1)
		(layers "F.Cu" "B.Cu")
		(net 72)
	)
	(segment
		(start 136.9 41.017156)
		(end 139.529 43.646156)
		(width 0.2)
		(layer "B.Cu")
		(net 72)
	)
	(segment
		(start 130.75 37.025)
		(end 130.75 37.867156)
		(width 0.2)
		(layer "B.Cu")
		(net 72)
	)
	(segment
		(start 130.875 36.9)
		(end 130.75 37.025)
		(width 0.2)
		(layer "B.Cu")
		(net 72)
	)
	(segment
		(start 139.529 45.289)
		(end 139.654 45.414)
		(width 0.2)
		(layer "B.Cu")
		(net 72)
	)
	(segment
		(start 139.529 43.646156)
		(end 139.529 45.289)
		(width 0.2)
		(layer "B.Cu")
		(net 72)
	)
	(segment
		(start 130.75 37.867156)
		(end 131.482844 38.6)
		(width 0.2)
		(layer "B.Cu")
		(net 72)
	)
	(segment
		(start 136.9 40.217156)
		(end 136.9 41.017156)
		(width 0.2)
		(layer "B.Cu")
		(net 72)
	)
	(segment
		(start 135.282844 38.6)
		(end 136.9 40.217156)
		(width 0.2)
		(layer "B.Cu")
		(net 72)
	)
	(segment
		(start 131.482844 38.6)
		(end 135.282844 38.6)
		(width 0.2)
		(layer "B.Cu")
		(net 72)
	)
	(segment
		(start 107.574 103.1)
		(end 106.839 103.1)
		(width 0.2)
		(layer "F.Cu")
		(net 73)
	)
	(segment
		(start 106.539 103.4)
		(end 105.525 103.4)
		(width 0.2)
		(layer "F.Cu")
		(net 73)
	)
	(segment
		(start 130.85 42.044928)
		(end 130.848 42.046928)
		(width 0.2)
		(layer "F.Cu")
		(net 73)
	)
	(segment
		(start 130.798 43.772)
		(end 130.798 44.184501)
		(width 0.2)
		(layer "F.Cu")
		(net 73)
	)
	(segment
		(start 130.798 43)
		(end 130.798 43.772)
		(width 0.2)
		(layer "F.Cu")
		(net 73)
	)
	(segment
		(start 106.839 103.1)
		(end 106.539 103.4)
		(width 0.2)
		(layer "F.Cu")
		(net 73)
	)
	(segment
		(start 130.848 42.537499)
		(end 130.798 42.587499)
		(width 0.2)
		(layer "F.Cu")
		(net 73)
	)
	(segment
		(start 130.848 47.669157)
		(end 129.346967 49.17019)
		(width 0.2)
		(layer "F.Cu")
		(net 73)
	)
	(segment
		(start 130.848 44.234501)
		(end 130.848 47.669157)
		(width 0.2)
		(layer "F.Cu")
		(net 73)
	)
	(segment
		(start 105.525 103.4)
		(end 105.4 103.275)
		(width 0.2)
		(layer "F.Cu")
		(net 73)
	)
	(segment
		(start 130.798 44.184501)
		(end 130.848 44.234501)
		(width 0.2)
		(layer "F.Cu")
		(net 73)
	)
	(segment
		(start 130.798 42.587499)
		(end 130.798 43)
		(width 0.2)
		(layer "F.Cu")
		(net 73)
	)
	(segment
		(start 130.8 40.987501)
		(end 130.85 41.037501)
		(width 0.2)
		(layer "F.Cu")
		(net 73)
	)
	(segment
		(start 129.346967 49.17019)
		(end 129.17019 49.17019)
		(width 0.2)
		(layer "F.Cu")
		(net 73)
	)
	(segment
		(start 130.85 41.037501)
		(end 130.85 42.044928)
		(width 0.2)
		(layer "F.Cu")
		(net 73)
	)
	(segment
		(start 130.848 42.046928)
		(end 130.848 42.537499)
		(width 0.2)
		(layer "F.Cu")
		(net 73)
	)
	(segment
		(start 130.8 40.305)
		(end 130.8 40.987501)
		(width 0.2)
		(layer "F.Cu")
		(net 73)
	)
	(via
		(at 129.17019 49.17019)
		(size 0.45)
		(drill 0.1)
		(layers "F.Cu" "B.Cu")
		(net 73)
	)
	(via
		(at 105.4 103.275)
		(size 0.45)
		(drill 0.1)
		(layers "F.Cu" "B.Cu")
		(net 73)
	)
	(segment
		(start 127.7 51.917156)
		(end 123.1 56.517156)
		(width 0.2)
		(layer "B.Cu")
		(net 73)
	)
	(segment
		(start 120.782177 95.834976)
		(end 120.697325 95.91983)
		(width 0.2)
		(layer "B.Cu")
		(net 73)
	)
	(segment
		(start 123.1 93.517156)
		(end 121.545854 95.071302)
		(width 0.2)
		(layer "B.Cu")
		(net 73)
	)
	(segment
		(start 127.7 50.817157)
		(end 127.7 51.917156)
		(width 0.2)
		(layer "B.Cu")
		(net 73)
	)
	(segment
		(start 129.17019 49.17019)
		(end 129.17019 49.346967)
		(width 0.2)
		(layer "B.Cu")
		(net 73)
	)
	(segment
		(start 121.206442 95.071302)
		(end 121.165878 95.030738)
		(width 0.2)
		(layer "B.Cu")
		(net 73)
	)
	(segment
		(start 123.1 56.517156)
		(end 123.1 93.517156)
		(width 0.2)
		(layer "B.Cu")
		(net 73)
	)
	(segment
		(start 113.217156 103.4)
		(end 120.697325 95.91983)
		(width 0.2)
		(layer "B.Cu")
		(net 73)
	)
	(segment
		(start 120.826467 95.030738)
		(end 120.741614 95.11559)
		(width 0.2)
		(layer "B.Cu")
		(net 73)
	)
	(segment
		(start 105.525 103.4)
		(end 105.4 103.275)
		(width 0.2)
		(layer "B.Cu")
		(net 73)
	)
	(segment
		(start 113.217156 103.4)
		(end 105.525 103.4)
		(width 0.2)
		(layer "B.Cu")
		(net 73)
	)
	(segment
		(start 120.741614 95.455002)
		(end 120.782177 95.495565)
		(width 0.2)
		(layer "B.Cu")
		(net 73)
	)
	(segment
		(start 129.17019 49.346967)
		(end 127.7 50.817157)
		(width 0.2)
		(layer "B.Cu")
		(net 73)
	)
	(arc
		(start 120.741614 95.11559)
		(mid 120.671319 95.285296)
		(end 120.741614 95.455002)
		(width 0.2)
		(layer "B.Cu")
		(net 73)
	)
	(arc
		(start 121.545854 95.071302)
		(mid 121.376148 95.141597)
		(end 121.206442 95.071302)
		(width 0.2)
		(layer "B.Cu")
		(net 73)
	)
	(arc
		(start 120.782177 95.495565)
		(mid 120.852471 95.665271)
		(end 120.782177 95.834976)
		(width 0.2)
		(layer "B.Cu")
		(net 73)
	)
	(arc
		(start 121.165878 95.030738)
		(mid 120.996173 94.960443)
		(end 120.826467 95.030738)
		(width 0.2)
		(layer "B.Cu")
		(net 73)
	)
	(segment
		(start 130.3 38.115)
		(end 130.3 37.432499)
		(width 0.2)
		(layer "F.Cu")
		(net 74)
	)
	(segment
		(start 122.403672 101.013483)
		(end 125.3 98.117156)
		(width 0.2)
		(layer "F.Cu")
		(net 74)
	)
	(segment
		(start 139.129 47.861501)
		(end 139.079 47.811501)
		(width 0.2)
		(layer "F.Cu")
		(net 74)
	)
	(segment
		(start 139.129 46.164499)
		(end 139.129 45.539)
		(width 0.2)
		(layer "F.Cu")
		(net 74)
	)
	(segment
		(start 121.859201 101.557958)
		(end 122.403672 101.013483)
		(width 0.2)
		(layer "F.Cu")
		(net 74)
	)
	(segment
		(start 114.774 105.1)
		(end 115.509 105.1)
		(width 0.2)
		(layer "F.Cu")
		(net 74)
	)
	(segment
		(start 121.054958 101.602246)
		(end 121.139813 101.517392)
		(width 0.2)
		(layer "F.Cu")
		(net 74)
	)
	(segment
		(start 139.079 47.811501)
		(end 139.079 47.399)
		(width 0.2)
		(layer "F.Cu")
		(net 74)
	)
	(segment
		(start 130.35 37.025)
		(end 130.225 36.9)
		(width 0.2)
		(layer "F.Cu")
		(net 74)
	)
	(segment
		(start 130.3 37.432499)
		(end 130.35 37.382499)
		(width 0.2)
		(layer "F.Cu")
		(net 74)
	)
	(segment
		(start 121.479223 101.517393)
		(end 121.519789 101.557959)
		(width 0.2)
		(layer "F.Cu")
		(net 74)
	)
	(segment
		(start 115.809 105.4)
		(end 118.017156 105.4)
		(width 0.2)
		(layer "F.Cu")
		(net 74)
	)
	(segment
		(start 139.079 46.627)
		(end 139.079 46.214499)
		(width 0.2)
		(layer "F.Cu")
		(net 74)
	)
	(segment
		(start 115.509 105.1)
		(end 115.809 105.4)
		(width 0.2)
		(layer "F.Cu")
		(net 74)
	)
	(segment
		(start 139.129 54.388156)
		(end 139.129 47.861501)
		(width 0.2)
		(layer "F.Cu")
		(net 74)
	)
	(segment
		(start 125.3 68.217156)
		(end 139.129 54.388156)
		(width 0.2)
		(layer "F.Cu")
		(net 74)
	)
	(segment
		(start 118.017156 105.4)
		(end 121.095523 102.321633)
		(width 0.2)
		(layer "F.Cu")
		(net 74)
	)
	(segment
		(start 139.079 47.399)
		(end 139.079 46.627)
		(width 0.2)
		(layer "F.Cu")
		(net 74)
	)
	(segment
		(start 139.079 46.214499)
		(end 139.129 46.164499)
		(width 0.2)
		(layer "F.Cu")
		(net 74)
	)
	(segment
		(start 125.3 98.117156)
		(end 125.3 68.217156)
		(width 0.2)
		(layer "F.Cu")
		(net 74)
	)
	(segment
		(start 121.095524 101.982221)
		(end 121.054959 101.941656)
		(width 0.2)
		(layer "F.Cu")
		(net 74)
	)
	(segment
		(start 139.129 45.539)
		(end 139.004 45.414)
		(width 0.2)
		(layer "F.Cu")
		(net 74)
	)
	(segment
		(start 130.35 37.382499)
		(end 130.35 37.025)
		(width 0.2)
		(layer "F.Cu")
		(net 74)
	)
	(via
		(at 130.225 36.9)
		(size 0.45)
		(drill 0.1)
		(layers "F.Cu" "B.Cu")
		(net 74)
	)
	(via
		(at 139.004 45.414)
		(size 0.45)
		(drill 0.1)
		(layers "F.Cu" "B.Cu")
		(net 74)
	)
	(arc
		(start 121.095523 102.321633)
		(mid 121.165818 102.151927)
		(end 121.095524 101.982221)
		(width 0.2)
		(layer "F.Cu")
		(net 74)
	)
	(arc
		(start 121.519789 101.557959)
		(mid 121.689494 101.628254)
		(end 121.859201 101.557958)
		(width 0.2)
		(layer "F.Cu")
		(net 74)
	)
	(arc
		(start 121.054959 101.941656)
		(mid 120.984665 101.77195)
		(end 121.054958 101.602246)
		(width 0.2)
		(layer "F.Cu")
		(net 74)
	)
	(arc
		(start 121.139813 101.517392)
		(mid 121.309518 101.447098)
		(end 121.479223 101.517393)
		(width 0.2)
		(layer "F.Cu")
		(net 74)
	)
	(segment
		(start 130.35 38.032844)
		(end 131.317156 39)
		(width 0.2)
		(layer "B.Cu")
		(net 74)
	)
	(segment
		(start 136.5 40.382844)
		(end 136.5 41.182844)
		(width 0.2)
		(layer "B.Cu")
		(net 74)
	)
	(segment
		(start 130.35 37.025)
		(end 130.35 38.032844)
		(width 0.2)
		(layer "B.Cu")
		(net 74)
	)
	(segment
		(start 139.129 43.811844)
		(end 139.129 45.289)
		(width 0.2)
		(layer "B.Cu")
		(net 74)
	)
	(segment
		(start 131.317156 39)
		(end 135.117156 39)
		(width 0.2)
		(layer "B.Cu")
		(net 74)
	)
	(segment
		(start 130.225 36.9)
		(end 130.35 37.025)
		(width 0.2)
		(layer "B.Cu")
		(net 74)
	)
	(segment
		(start 136.5 41.182844)
		(end 139.129 43.811844)
		(width 0.2)
		(layer "B.Cu")
		(net 74)
	)
	(segment
		(start 135.117156 39)
		(end 136.5 40.382844)
		(width 0.2)
		(layer "B.Cu")
		(net 74)
	)
	(segment
		(start 139.129 45.289)
		(end 139.004 45.414)
		(width 0.2)
		(layer "B.Cu")
		(net 74)
	)
	(segment
		(start 129.8 43)
		(end 129.8 42.587499)
		(width 0.2)
		(layer "F.Cu")
		(net 75)
	)
	(segment
		(start 129.75 41.037501)
		(end 129.8 40.987501)
		(width 0.2)
		(layer "F.Cu")
		(net 75)
	)
	(segment
		(start 129.75 42.537499)
		(end 129.75 41.037501)
		(width 0.2)
		(layer "F.Cu")
		(net 75)
	)
	(segment
		(start 129.75 44.234501)
		(end 129.75 47.032843)
		(width 0.2)
		(layer "F.Cu")
		(net 75)
	)
	(segment
		(start 106.839 99.1)
		(end 106.539 98.8)
		(width 0.2)
		(layer "F.Cu")
		(net 75)
	)
	(segment
		(start 127.72981 49.053033)
		(end 127.72981 49.22981)
		(width 0.2)
		(layer "F.Cu")
		(net 75)
	)
	(segment
		(start 129.8 43.772)
		(end 129.8 44.184501)
		(width 0.2)
		(layer "F.Cu")
		(net 75)
	)
	(segment
		(start 129.75 47.032843)
		(end 127.72981 49.053033)
		(width 0.2)
		(layer "F.Cu")
		(net 75)
	)
	(segment
		(start 107.574 99.1)
		(end 106.839 99.1)
		(width 0.2)
		(layer "F.Cu")
		(net 75)
	)
	(segment
		(start 129.8 43)
		(end 129.8 43.772)
		(width 0.2)
		(layer "F.Cu")
		(net 75)
	)
	(segment
		(start 106.539 98.8)
		(end 105.525 98.8)
		(width 0.2)
		(layer "F.Cu")
		(net 75)
	)
	(segment
		(start 129.8 40.987501)
		(end 129.8 40.305)
		(width 0.2)
		(layer "F.Cu")
		(net 75)
	)
	(segment
		(start 105.525 98.8)
		(end 105.4 98.925)
		(width 0.2)
		(layer "F.Cu")
		(net 75)
	)
	(segment
		(start 129.8 44.184501)
		(end 129.75 44.234501)
		(width 0.2)
		(layer "F.Cu")
		(net 75)
	)
	(segment
		(start 129.8 42.587499)
		(end 129.75 42.537499)
		(width 0.2)
		(layer "F.Cu")
		(net 75)
	)
	(via
		(at 127.72981 49.22981)
		(size 0.45)
		(drill 0.1)
		(layers "F.Cu" "B.Cu")
		(net 75)
	)
	(via
		(at 105.4 98.925)
		(size 0.45)
		(drill 0.1)
		(layers "F.Cu" "B.Cu")
		(net 75)
	)
	(segment
		(start 121 91.582844)
		(end 113.782844 98.8)
		(width 0.2)
		(layer "B.Cu")
		(net 75)
	)
	(segment
		(start 105.525 98.8)
		(end 105.4 98.925)
		(width 0.2)
		(layer "B.Cu")
		(net 75)
	)
	(segment
		(start 127.72981 49.22981)
		(end 127.553033 49.22981)
		(width 0.2)
		(layer "B.Cu")
		(net 75)
	)
	(segment
		(start 113.782844 98.8)
		(end 105.525 98.8)
		(width 0.2)
		(layer "B.Cu")
		(net 75)
	)
	(segment
		(start 127.553033 49.22981)
		(end 121 55.782843)
		(width 0.2)
		(layer "B.Cu")
		(net 75)
	)
	(segment
		(start 121 55.782843)
		(end 121 91.582844)
		(width 0.2)
		(layer "B.Cu")
		(net 75)
	)
	(segment
		(start 118.315853 94.341269)
		(end 118.400708 94.256415)
		(width 0.2)
		(layer "F.Cu")
		(net 76)
	)
	(segment
		(start 119.399967 94.017189)
		(end 120.7 92.717156)
		(width 0.2)
		(layer "F.Cu")
		(net 76)
	)
	(segment
		(start 118.740118 94.256416)
		(end 118.780725 94.297023)
		(width 0.2)
		(layer "F.Cu")
		(net 76)
	)
	(segment
		(start 124.3 38.115)
		(end 124.3 37.432499)
		(width 0.2)
		(layer "F.Cu")
		(net 76)
	)
	(segment
		(start 117.017156 96.4)
		(end 118.356459 95.060697)
		(width 0.2)
		(layer "F.Cu")
		(net 76)
	)
	(segment
		(start 124.35 37.382499)
		(end 124.35 37.025)
		(width 0.2)
		(layer "F.Cu")
		(net 76)
	)
	(segment
		(start 124.35 37.025)
		(end 124.225 36.9)
		(width 0.2)
		(layer "F.Cu")
		(net 76)
	)
	(segment
		(start 135.15 47.848501)
		(end 135.1 47.798501)
		(width 0.2)
		(layer "F.Cu")
		(net 76)
	)
	(segment
		(start 135.15 46.151499)
		(end 135.15 45.489)
		(width 0.2)
		(layer "F.Cu")
		(net 76)
	)
	(segment
		(start 114.774 96.1)
		(end 115.509 96.1)
		(width 0.2)
		(layer "F.Cu")
		(net 76)
	)
	(segment
		(start 135.1 46.614)
		(end 135.1 46.201499)
		(width 0.2)
		(layer "F.Cu")
		(net 76)
	)
	(segment
		(start 124.3 37.432499)
		(end 124.35 37.382499)
		(width 0.2)
		(layer "F.Cu")
		(net 76)
	)
	(segment
		(start 135.15 45.489)
		(end 135.025 45.364)
		(width 0.2)
		(layer "F.Cu")
		(net 76)
	)
	(segment
		(start 135.1 46.201499)
		(end 135.15 46.151499)
		(width 0.2)
		(layer "F.Cu")
		(net 76)
	)
	(segment
		(start 135.15 51.767156)
		(end 135.15 47.848501)
		(width 0.2)
		(layer "F.Cu")
		(net 76)
	)
	(segment
		(start 119.120137 94.297022)
		(end 119.399967 94.017189)
		(width 0.2)
		(layer "F.Cu")
		(net 76)
	)
	(segment
		(start 120.7 66.217156)
		(end 135.15 51.767156)
		(width 0.2)
		(layer "F.Cu")
		(net 76)
	)
	(segment
		(start 118.35646 94.721285)
		(end 118.315854 94.680679)
		(width 0.2)
		(layer "F.Cu")
		(net 76)
	)
	(segment
		(start 135.1 47.798501)
		(end 135.1 47.386)
		(width 0.2)
		(layer "F.Cu")
		(net 76)
	)
	(segment
		(start 135.1 47.386)
		(end 135.1 46.614)
		(width 0.2)
		(layer "F.Cu")
		(net 76)
	)
	(segment
		(start 115.809 96.4)
		(end 117.017156 96.4)
		(width 0.2)
		(layer "F.Cu")
		(net 76)
	)
	(segment
		(start 120.7 92.717156)
		(end 120.7 66.217156)
		(width 0.2)
		(layer "F.Cu")
		(net 76)
	)
	(segment
		(start 115.509 96.1)
		(end 115.809 96.4)
		(width 0.2)
		(layer "F.Cu")
		(net 76)
	)
	(via
		(at 135.025 45.364)
		(size 0.45)
		(drill 0.1)
		(layers "F.Cu" "B.Cu")
		(net 76)
	)
	(via
		(at 124.225 36.9)
		(size 0.45)
		(drill 0.1)
		(layers "F.Cu" "B.Cu")
		(net 76)
	)
	(arc
		(start 118.315854 94.680679)
		(mid 118.24556 94.510973)
		(end 118.315853 94.341269)
		(width 0.2)
		(layer "F.Cu")
		(net 76)
	)
	(arc
		(start 118.356459 95.060697)
		(mid 118.426754 94.890991)
		(end 118.35646 94.721285)
		(width 0.2)
		(layer "F.Cu")
		(net 76)
	)
	(arc
		(start 118.780725 94.297023)
		(mid 118.95043 94.367318)
		(end 119.120137 94.297022)
		(width 0.2)
		(layer "F.Cu")
		(net 76)
	)
	(arc
		(start 118.400708 94.256415)
		(mid 118.570413 94.186121)
		(end 118.740118 94.256416)
		(width 0.2)
		(layer "F.Cu")
		(net 76)
	)
	(segment
		(start 124.8 42.082844)
		(end 125.917156 43.2)
		(width 0.2)
		(layer "B.Cu")
		(net 76)
	)
	(segment
		(start 124.8 39.582844)
		(end 124.8 42.082844)
		(width 0.2)
		(layer "B.Cu")
		(net 76)
	)
	(segment
		(start 134.117156 43.2)
		(end 135.15 44.232844)
		(width 0.2)
		(layer "B.Cu")
		(net 76)
	)
	(segment
		(start 124.225 36.9)
		(end 124.35 37.025)
		(width 0.2)
		(layer "B.Cu")
		(net 76)
	)
	(segment
		(start 135.15 45.239)
		(end 135.025 45.364)
		(width 0.2)
		(layer "B.Cu")
		(net 76)
	)
	(segment
		(start 124.35 39.132844)
		(end 124.8 39.582844)
		(width 0.2)
		(layer "B.Cu")
		(net 76)
	)
	(segment
		(start 125.917156 43.2)
		(end 134.117156 43.2)
		(width 0.2)
		(layer "B.Cu")
		(net 76)
	)
	(segment
		(start 124.35 37.025)
		(end 124.35 39.132844)
		(width 0.2)
		(layer "B.Cu")
		(net 76)
	)
	(segment
		(start 135.15 44.232844)
		(end 135.15 45.239)
		(width 0.2)
		(layer "B.Cu")
		(net 76)
	)
	(segment
		(start 129.25 37.382499)
		(end 129.25 37.025)
		(width 0.2)
		(layer "F.Cu")
		(net 77)
	)
	(segment
		(start 115.809 100.8)
		(end 117.382844 100.8)
		(width 0.2)
		(layer "F.Cu")
		(net 77)
	)
	(segment
		(start 115.509 101.1)
		(end 115.809 100.8)
		(width 0.2)
		(layer "F.Cu")
		(net 77)
	)
	(segment
		(start 123.5 67.582844)
		(end 138.031 53.051844)
		(width 0.2)
		(layer "F.Cu")
		(net 77)
	)
	(segment
		(start 138.031 53.051844)
		(end 138.031 47.861501)
		(width 0.2)
		(layer "F.Cu")
		(net 77)
	)
	(segment
		(start 138.031 45.539)
		(end 138.156 45.414)
		(width 0.2)
		(layer "F.Cu")
		(net 77)
	)
	(segment
		(start 138.081 46.214499)
		(end 138.031 46.164499)
		(width 0.2)
		(layer "F.Cu")
		(net 77)
	)
	(segment
		(start 138.081 47.811501)
		(end 138.081 47.399)
		(width 0.2)
		(layer "F.Cu")
		(net 77)
	)
	(segment
		(start 129.25 37.025)
		(end 129.375 36.9)
		(width 0.2)
		(layer "F.Cu")
		(net 77)
	)
	(segment
		(start 117.382844 100.8)
		(end 123.5 94.682844)
		(width 0.2)
		(layer "F.Cu")
		(net 77)
	)
	(segment
		(start 129.3 38.115)
		(end 129.3 37.432499)
		(width 0.2)
		(layer "F.Cu")
		(net 77)
	)
	(segment
		(start 138.031 47.861501)
		(end 138.081 47.811501)
		(width 0.2)
		(layer "F.Cu")
		(net 77)
	)
	(segment
		(start 114.774 101.1)
		(end 115.509 101.1)
		(width 0.2)
		(layer "F.Cu")
		(net 77)
	)
	(segment
		(start 138.031 46.164499)
		(end 138.031 45.539)
		(width 0.2)
		(layer "F.Cu")
		(net 77)
	)
	(segment
		(start 123.5 94.682844)
		(end 123.5 67.582844)
		(width 0.2)
		(layer "F.Cu")
		(net 77)
	)
	(segment
		(start 138.081 46.627)
		(end 138.081 46.214499)
		(width 0.2)
		(layer "F.Cu")
		(net 77)
	)
	(segment
		(start 138.081 47.399)
		(end 138.081 46.627)
		(width 0.2)
		(layer "F.Cu")
		(net 77)
	)
	(segment
		(start 129.3 37.432499)
		(end 129.25 37.382499)
		(width 0.2)
		(layer "F.Cu")
		(net 77)
	)
	(via
		(at 129.375 36.9)
		(size 0.45)
		(drill 0.1)
		(layers "F.Cu" "B.Cu")
		(net 77)
	)
	(via
		(at 138.156 45.414)
		(size 0.45)
		(drill 0.1)
		(layers "F.Cu" "B.Cu")
		(net 77)
	)
	(segment
		(start 129.25 37.025)
		(end 129.25 39.567156)
		(width 0.2)
		(layer "B.Cu")
		(net 77)
	)
	(segment
		(start 138.031 45.289)
		(end 138.156 45.414)
		(width 0.2)
		(layer "B.Cu")
		(net 77)
	)
	(segment
		(start 138.031 44.148156)
		(end 138.031 45.289)
		(width 0.2)
		(layer "B.Cu")
		(net 77)
	)
	(segment
		(start 129.682844 40)
		(end 133.882844 40)
		(width 0.2)
		(layer "B.Cu")
		(net 77)
	)
	(segment
		(start 133.882844 40)
		(end 138.031 44.148156)
		(width 0.2)
		(layer "B.Cu")
		(net 77)
	)
	(segment
		(start 129.25 39.567156)
		(end 129.682844 40)
		(width 0.2)
		(layer "B.Cu")
		(net 77)
	)
	(segment
		(start 129.375 36.9)
		(end 129.25 37.025)
		(width 0.2)
		(layer "B.Cu")
		(net 77)
	)
	(segment
		(start 131.298 43.772)
		(end 131.298 44.184501)
		(width 0.2)
		(layer "F.Cu")
		(net 78)
	)
	(segment
		(start 131.248 47.834843)
		(end 129.62981 49.453033)
		(width 0.2)
		(layer "F.Cu")
		(net 78)
	)
	(segment
		(start 131.25 41.037501)
		(end 131.25 42.198)
		(width 0.2)
		(layer "F.Cu")
		(net 78)
	)
	(segment
		(start 129.62981 49.453033)
		(end 129.62981 49.62981)
		(width 0.2)
		(layer "F.Cu")
		(net 78)
	)
	(segment
		(start 131.298 43)
		(end 131.298 43.772)
		(width 0.2)
		(layer "F.Cu")
		(net 78)
	)
	(segment
		(start 106.539 103.8)
		(end 105.525 103.8)
		(width 0.2)
		(layer "F.Cu")
		(net 78)
	)
	(segment
		(start 107.574 104.1)
		(end 106.839 104.1)
		(width 0.2)
		(layer "F.Cu")
		(net 78)
	)
	(segment
		(start 131.3 40.987501)
		(end 131.25 41.037501)
		(width 0.2)
		(layer "F.Cu")
		(net 78)
	)
	(segment
		(start 131.248 44.234501)
		(end 131.248 47.834843)
		(width 0.2)
		(layer "F.Cu")
		(net 78)
	)
	(segment
		(start 106.839 104.1)
		(end 106.539 103.8)
		(width 0.2)
		(layer "F.Cu")
		(net 78)
	)
	(segment
		(start 131.248 42.537499)
		(end 131.298 42.587499)
		(width 0.2)
		(layer "F.Cu")
		(net 78)
	)
	(segment
		(start 131.3 40.305)
		(end 131.3 40.987501)
		(width 0.2)
		(layer "F.Cu")
		(net 78)
	)
	(segment
		(start 105.525 103.8)
		(end 105.4 103.925)
		(width 0.2)
		(layer "F.Cu")
		(net 78)
	)
	(segment
		(start 131.248 42.2)
		(end 131.248 42.537499)
		(width 0.2)
		(layer "F.Cu")
		(net 78)
	)
	(segment
		(start 131.25 42.198)
		(end 131.248 42.2)
		(width 0.2)
		(layer "F.Cu")
		(net 78)
	)
	(segment
		(start 131.298 42.587499)
		(end 131.298 43)
		(width 0.2)
		(layer "F.Cu")
		(net 78)
	)
	(segment
		(start 131.298 44.184501)
		(end 131.248 44.234501)
		(width 0.2)
		(layer "F.Cu")
		(net 78)
	)
	(via
		(at 105.4 103.925)
		(size 0.45)
		(drill 0.1)
		(layers "F.Cu" "B.Cu")
		(net 78)
	)
	(via
		(at 129.62981 49.62981)
		(size 0.45)
		(drill 0.1)
		(layers "F.Cu" "B.Cu")
		(net 78)
	)
	(segment
		(start 113.382844 103.8)
		(end 105.525 103.8)
		(width 0.2)
		(layer "B.Cu")
		(net 78)
	)
	(segment
		(start 128.1 52.082844)
		(end 123.5 56.682844)
		(width 0.2)
		(layer "B.Cu")
		(net 78)
	)
	(segment
		(start 129.62981 49.62981)
		(end 129.453033 49.62981)
		(width 0.2)
		(layer "B.Cu")
		(net 78)
	)
	(segment
		(start 123.5 93.682844)
		(end 113.382844 103.8)
		(width 0.2)
		(layer "B.Cu")
		(net 78)
	)
	(segment
		(start 128.1 50.982843)
		(end 128.1 52.082844)
		(width 0.2)
		(layer "B.Cu")
		(net 78)
	)
	(segment
		(start 105.525 103.8)
		(end 105.4 103.925)
		(width 0.2)
		(layer "B.Cu")
		(net 78)
	)
	(segment
		(start 129.453033 49.62981)
		(end 128.1 50.982843)
		(width 0.2)
		(layer "B.Cu")
		(net 78)
	)
	(segment
		(start 123.5 56.682844)
		(end 123.5 93.682844)
		(width 0.2)
		(layer "B.Cu")
		(net 78)
	)
	(segment
		(start 124.8 40.987501)
		(end 124.8 40.305)
		(width 0.2)
		(layer "F.Cu")
		(net 79)
	)
	(segment
		(start 106.539 94.401)
		(end 105.525 94.401)
		(width 0.2)
		(layer "F.Cu")
		(net 79)
	)
	(segment
		(start 124.85 41.3)
		(end 124.85 41.037501)
		(width 0.2)
		(layer "F.Cu")
		(net 79)
	)
	(segment
		(start 107.574 94.101)
		(end 106.839 94.101)
		(width 0.2)
		(layer "F.Cu")
		(net 79)
	)
	(segment
		(start 124.798 43)
		(end 124.798 42.587499)
		(width 0.2)
		(layer "F.Cu")
		(net 79)
	)
	(segment
		(start 106.839 94.101)
		(end 106.539 94.401)
		(width 0.2)
		(layer "F.Cu")
		(net 79)
	)
	(segment
		(start 124.546967 47.07019)
		(end 124.848 46.769157)
		(width 0.2)
		(layer "F.Cu")
		(net 79)
	)
	(segment
		(start 124.798 43.772)
		(end 124.798 43)
		(width 0.2)
		(layer "F.Cu")
		(net 79)
	)
	(segment
		(start 124.798 44.184501)
		(end 124.798 43.772)
		(width 0.2)
		(layer "F.Cu")
		(net 79)
	)
	(segment
		(start 124.848 44.234501)
		(end 124.798 44.184501)
		(width 0.2)
		(layer "F.Cu")
		(net 79)
	)
	(segment
		(start 124.848 46.769157)
		(end 124.848 44.234501)
		(width 0.2)
		(layer "F.Cu")
		(net 79)
	)
	(segment
		(start 124.37019 47.07019)
		(end 124.546967 47.07019)
		(width 0.2)
		(layer "F.Cu")
		(net 79)
	)
	(segment
		(start 105.525 94.401)
		(end 105.4 94.276)
		(width 0.2)
		(layer "F.Cu")
		(net 79)
	)
	(segment
		(start 124.798 42.587499)
		(end 124.848 42.537499)
		(width 0.2)
		(layer "F.Cu")
		(net 79)
	)
	(segment
		(start 124.848 42.537499)
		(end 124.848 41.302)
		(width 0.2)
		(layer "F.Cu")
		(net 79)
	)
	(segment
		(start 124.848 41.302)
		(end 124.85 41.3)
		(width 0.2)
		(layer "F.Cu")
		(net 79)
	)
	(segment
		(start 124.85 41.037501)
		(end 124.8 40.987501)
		(width 0.2)
		(layer "F.Cu")
		(net 79)
	)
	(via
		(at 105.4 94.276)
		(size 0.45)
		(drill 0.1)
		(layers "F.Cu" "B.Cu")
		(net 79)
	)
	(via
		(at 124.37019 47.07019)
		(size 0.45)
		(drill 0.1)
		(layers "F.Cu" "B.Cu")
		(net 79)
	)
	(segment
		(start 121 50.617157)
		(end 124.37019 47.246967)
		(width 0.2)
		(layer "B.Cu")
		(net 79)
	)
	(segment
		(start 114.659185 90.657974)
		(end 114.744037 90.57312)
		(width 0.2)
		(layer "B.Cu")
		(net 79)
	)
	(segment
		(start 113.85494 90.70226)
		(end 113.939795 90.617406)
		(width 0.2)
		(layer "B.Cu")
		(net 79)
	)
	(segment
		(start 124.37019 47.246967)
		(end 124.37019 47.07019)
		(width 0.2)
		(layer "B.Cu")
		(net 79)
	)
	(segment
		(start 114.279205 90.617407)
		(end 114.319773 90.657975)
		(width 0.2)
		(layer "B.Cu")
		(net 79)
	)
	(segment
		(start 117.9 87.417156)
		(end 117.9 55.017156)
		(width 0.2)
		(layer "B.Cu")
		(net 79)
	)
	(segment
		(start 117.9 55.017156)
		(end 121 51.917156)
		(width 0.2)
		(layer "B.Cu")
		(net 79)
	)
	(segment
		(start 113.895508 91.082237)
		(end 113.854941 91.04167)
		(width 0.2)
		(layer "B.Cu")
		(net 79)
	)
	(segment
		(start 105.525 94.401)
		(end 110.916156 94.401)
		(width 0.2)
		(layer "B.Cu")
		(net 79)
	)
	(segment
		(start 105.4 94.276)
		(end 105.525 94.401)
		(width 0.2)
		(layer "B.Cu")
		(net 79)
	)
	(segment
		(start 121 51.917156)
		(end 121 50.617157)
		(width 0.2)
		(layer "B.Cu")
		(net 79)
	)
	(segment
		(start 114.744037 90.57312)
		(end 117.9 87.417156)
		(width 0.2)
		(layer "B.Cu")
		(net 79)
	)
	(segment
		(start 110.916156 94.401)
		(end 113.895507 91.421649)
		(width 0.2)
		(layer "B.Cu")
		(net 79)
	)
	(arc
		(start 113.854941 91.04167)
		(mid 113.784647 90.871964)
		(end 113.85494 90.70226)
		(width 0.2)
		(layer "B.Cu")
		(net 79)
	)
	(arc
		(start 113.895507 91.421649)
		(mid 113.965802 91.251943)
		(end 113.895508 91.082237)
		(width 0.2)
		(layer "B.Cu")
		(net 79)
	)
	(arc
		(start 113.939795 90.617406)
		(mid 114.1095 90.547112)
		(end 114.279205 90.617407)
		(width 0.2)
		(layer "B.Cu")
		(net 79)
	)
	(arc
		(start 114.319773 90.657975)
		(mid 114.489478 90.72827)
		(end 114.659185 90.657974)
		(width 0.2)
		(layer "B.Cu")
		(net 79)
	)
	(segment
		(start 122.8 38.115)
		(end 122.8 37.432499)
		(width 0.2)
		(layer "F.Cu")
		(net 80)
	)
	(segment
		(start 117.594145 91.162969)
		(end 117.679 91.078115)
		(width 0.2)
		(layer "F.Cu")
		(net 80)
	)
	(segment
		(start 118.01841 91.078116)
		(end 118.059021 91.118727)
		(width 0.2)
		(layer "F.Cu")
		(net 80)
	)
	(segment
		(start 133.652 50.265156)
		(end 133.652 47.848501)
		(width 0.2)
		(layer "F.Cu")
		(net 80)
	)
	(segment
		(start 133.652 45.489)
		(end 133.527 45.364)
		(width 0.2)
		(layer "F.Cu")
		(net 80)
	)
	(segment
		(start 133.602 46.614)
		(end 133.602 46.201499)
		(width 0.2)
		(layer "F.Cu")
		(net 80)
	)
	(segment
		(start 133.652 46.151499)
		(end 133.652 45.489)
		(width 0.2)
		(layer "F.Cu")
		(net 80)
	)
	(segment
		(start 115.509 92.101)
		(end 115.809 92.401)
		(width 0.2)
		(layer "F.Cu")
		(net 80)
	)
	(segment
		(start 117.116156 92.401)
		(end 117.634755 91.882401)
		(width 0.2)
		(layer "F.Cu")
		(net 80)
	)
	(segment
		(start 122.85 37.025)
		(end 122.725 36.9)
		(width 0.2)
		(layer "F.Cu")
		(net 80)
	)
	(segment
		(start 117.634756 91.542989)
		(end 117.594146 91.502379)
		(width 0.2)
		(layer "F.Cu")
		(net 80)
	)
	(segment
		(start 133.602 46.614)
		(end 133.602 47.386)
		(width 0.2)
		(layer "F.Cu")
		(net 80)
	)
	(segment
		(start 118.7 90.817156)
		(end 118.7 65.217156)
		(width 0.2)
		(layer "F.Cu")
		(net 80)
	)
	(segment
		(start 122.85 37.382499)
		(end 122.85 37.025)
		(width 0.2)
		(layer "F.Cu")
		(net 80)
	)
	(segment
		(start 133.602 46.201499)
		(end 133.652 46.151499)
		(width 0.2)
		(layer "F.Cu")
		(net 80)
	)
	(segment
		(start 122.8 37.432499)
		(end 122.85 37.382499)
		(width 0.2)
		(layer "F.Cu")
		(net 80)
	)
	(segment
		(start 118.7 65.217156)
		(end 133.652 50.265156)
		(width 0.2)
		(layer "F.Cu")
		(net 80)
	)
	(segment
		(start 114.774 92.101)
		(end 115.509 92.101)
		(width 0.2)
		(layer "F.Cu")
		(net 80)
	)
	(segment
		(start 133.652 47.848501)
		(end 133.602 47.798501)
		(width 0.2)
		(layer "F.Cu")
		(net 80)
	)
	(segment
		(start 133.602 47.798501)
		(end 133.602 47.386)
		(width 0.2)
		(layer "F.Cu")
		(net 80)
	)
	(segment
		(start 118.398433 91.118726)
		(end 118.7 90.817156)
		(width 0.2)
		(layer "F.Cu")
		(net 80)
	)
	(segment
		(start 115.809 92.401)
		(end 117.116156 92.401)
		(width 0.2)
		(layer "F.Cu")
		(net 80)
	)
	(via
		(at 133.527 45.364)
		(size 0.45)
		(drill 0.1)
		(layers "F.Cu" "B.Cu")
		(net 80)
	)
	(via
		(at 122.725 36.9)
		(size 0.45)
		(drill 0.1)
		(layers "F.Cu" "B.Cu")
		(net 80)
	)
	(arc
		(start 118.059021 91.118727)
		(mid 118.228726 91.189022)
		(end 118.398433 91.118726)
		(width 0.2)
		(layer "F.Cu")
		(net 80)
	)
	(arc
		(start 117.679 91.078115)
		(mid 117.848705 91.007821)
		(end 118.01841 91.078116)
		(width 0.2)
		(layer "F.Cu")
		(net 80)
	)
	(arc
		(start 117.594146 91.502379)
		(mid 117.523852 91.332673)
		(end 117.594145 91.162969)
		(width 0.2)
		(layer "F.Cu")
		(net 80)
	)
	(arc
		(start 117.634755 91.882401)
		(mid 117.70505 91.712695)
		(end 117.634756 91.542989)
		(width 0.2)
		(layer "F.Cu")
		(net 80)
	)
	(segment
		(start 121.8 40.217156)
		(end 122.85 39.167156)
		(width 0.2)
		(layer "B.Cu")
		(net 80)
	)
	(segment
		(start 122.85 37.025)
		(end 122.725 36.9)
		(width 0.2)
		(layer "B.Cu")
		(net 80)
	)
	(segment
		(start 121.8 42.382844)
		(end 121.8 40.217156)
		(width 0.2)
		(layer "B.Cu")
		(net 80)
	)
	(segment
		(start 133.652 44.834844)
		(end 133.317156 44.5)
		(width 0.2)
		(layer "B.Cu")
		(net 80)
	)
	(segment
		(start 133.652 45.239)
		(end 133.652 44.834844)
		(width 0.2)
		(layer "B.Cu")
		(net 80)
	)
	(segment
		(start 133.527 45.364)
		(end 133.652 45.239)
		(width 0.2)
		(layer "B.Cu")
		(net 80)
	)
	(segment
		(start 130.582844 45.2)
		(end 124.617156 45.2)
		(width 0.2)
		(layer "B.Cu")
		(net 80)
	)
	(segment
		(start 122.85 39.167156)
		(end 122.85 37.025)
		(width 0.2)
		(layer "B.Cu")
		(net 80)
	)
	(segment
		(start 124.617156 45.2)
		(end 121.8 42.382844)
		(width 0.2)
		(layer "B.Cu")
		(net 80)
	)
	(segment
		(start 131.282844 44.5)
		(end 130.582844 45.2)
		(width 0.2)
		(layer "B.Cu")
		(net 80)
	)
	(segment
		(start 133.317156 44.5)
		(end 131.282844 44.5)
		(width 0.2)
		(layer "B.Cu")
		(net 80)
	)
	(segment
		(start 107.574 95.101)
		(end 106.839 95.101)
		(width 0.2)
		(layer "F.Cu")
		(net 81)
	)
	(segment
		(start 105.525 94.801)
		(end 105.4 94.926)
		(width 0.2)
		(layer "F.Cu")
		(net 81)
	)
	(segment
		(start 125.248 44.234501)
		(end 125.298 44.184501)
		(width 0.2)
		(layer "F.Cu")
		(net 81)
	)
	(segment
		(start 125.248 46.934843)
		(end 125.248 44.234501)
		(width 0.2)
		(layer "F.Cu")
		(net 81)
	)
	(segment
		(start 125.248 42.537499)
		(end 125.248 41.455072)
		(width 0.2)
		(layer "F.Cu")
		(net 81)
	)
	(segment
		(start 125.298 43.772)
		(end 125.298 43)
		(width 0.2)
		(layer "F.Cu")
		(net 81)
	)
	(segment
		(start 124.82981 47.353033)
		(end 125.248 46.934843)
		(width 0.2)
		(layer "F.Cu")
		(net 81)
	)
	(segment
		(start 106.839 95.101)
		(end 106.539 94.801)
		(width 0.2)
		(layer "F.Cu")
		(net 81)
	)
	(segment
		(start 106.539 94.801)
		(end 105.525 94.801)
		(width 0.2)
		(layer "F.Cu")
		(net 81)
	)
	(segment
		(start 125.298 42.587499)
		(end 125.248 42.537499)
		(width 0.2)
		(layer "F.Cu")
		(net 81)
	)
	(segment
		(start 125.248 41.455072)
		(end 125.25 41.453072)
		(width 0.2)
		(layer "F.Cu")
		(net 81)
	)
	(segment
		(start 125.25 41.037501)
		(end 125.3 40.987501)
		(width 0.2)
		(layer "F.Cu")
		(net 81)
	)
	(segment
		(start 124.82981 47.52981)
		(end 124.82981 47.353033)
		(width 0.2)
		(layer "F.Cu")
		(net 81)
	)
	(segment
		(start 125.298 43)
		(end 125.298 42.587499)
		(width 0.2)
		(layer "F.Cu")
		(net 81)
	)
	(segment
		(start 125.298 44.184501)
		(end 125.298 43.772)
		(width 0.2)
		(layer "F.Cu")
		(net 81)
	)
	(segment
		(start 125.3 40.987501)
		(end 125.3 40.305)
		(width 0.2)
		(layer "F.Cu")
		(net 81)
	)
	(segment
		(start 125.25 41.453072)
		(end 125.25 41.037501)
		(width 0.2)
		(layer "F.Cu")
		(net 81)
	)
	(via
		(at 105.4 94.926)
		(size 0.45)
		(drill 0.1)
		(layers "F.Cu" "B.Cu")
		(net 81)
	)
	(via
		(at 124.82981 47.52981)
		(size 0.45)
		(drill 0.1)
		(layers "F.Cu" "B.Cu")
		(net 81)
	)
	(segment
		(start 124.653033 47.52981)
		(end 121.4 50.782843)
		(width 0.2)
		(layer "B.Cu")
		(net 81)
	)
	(segment
		(start 121.4 50.782843)
		(end 121.4 52.082844)
		(width 0.2)
		(layer "B.Cu")
		(net 81)
	)
	(segment
		(start 121.4 52.082844)
		(end 118.3 55.182844)
		(width 0.2)
		(layer "B.Cu")
		(net 81)
	)
	(segment
		(start 124.82981 47.52981)
		(end 124.653033 47.52981)
		(width 0.2)
		(layer "B.Cu")
		(net 81)
	)
	(segment
		(start 105.525 94.801)
		(end 105.4 94.926)
		(width 0.2)
		(layer "B.Cu")
		(net 81)
	)
	(segment
		(start 118.3 55.182844)
		(end 118.3 87.582844)
		(width 0.2)
		(layer "B.Cu")
		(net 81)
	)
	(segment
		(start 118.3 87.582844)
		(end 111.081844 94.801)
		(width 0.2)
		(layer "B.Cu")
		(net 81)
	)
	(segment
		(start 111.081844 94.801)
		(end 105.525 94.801)
		(width 0.2)
		(layer "B.Cu")
		(net 81)
	)
	(segment
		(start 117.281844 92.801)
		(end 119.1 90.982844)
		(width 0.2)
		(layer "F.Cu")
		(net 82)
	)
	(segment
		(start 134.052 45.489)
		(end 134.177 45.364)
		(width 0.2)
		(layer "F.Cu")
		(net 82)
	)
	(segment
		(start 134.102 47.386)
		(end 134.102 46.614)
		(width 0.2)
		(layer "F.Cu")
		(net 82)
	)
	(segment
		(start 134.102 46.614)
		(end 134.102 46.201499)
		(width 0.2)
		(layer "F.Cu")
		(net 82)
	)
	(segment
		(start 123.25 37.382499)
		(end 123.25 37.025)
		(width 0.2)
		(layer "F.Cu")
		(net 82)
	)
	(segment
		(start 134.052 47.848501)
		(end 134.102 47.798501)
		(width 0.2)
		(layer "F.Cu")
		(net 82)
	)
	(segment
		(start 119.1 65.382844)
		(end 134.052 50.430844)
		(width 0.2)
		(layer "F.Cu")
		(net 82)
	)
	(segment
		(start 134.052 50.430844)
		(end 134.052 47.848501)
		(width 0.2)
		(layer "F.Cu")
		(net 82)
	)
	(segment
		(start 115.809 92.801)
		(end 117.281844 92.801)
		(width 0.2)
		(layer "F.Cu")
		(net 82)
	)
	(segment
		(start 134.102 47.798501)
		(end 134.102 47.386)
		(width 0.2)
		(layer "F.Cu")
		(net 82)
	)
	(segment
		(start 134.052 46.151499)
		(end 134.052 45.489)
		(width 0.2)
		(layer "F.Cu")
		(net 82)
	)
	(segment
		(start 119.1 90.982844)
		(end 119.1 65.382844)
		(width 0.2)
		(layer "F.Cu")
		(net 82)
	)
	(segment
		(start 123.3 37.432499)
		(end 123.25 37.382499)
		(width 0.2)
		(layer "F.Cu")
		(net 82)
	)
	(segment
		(start 123.25 37.025)
		(end 123.375 36.9)
		(width 0.2)
		(layer "F.Cu")
		(net 82)
	)
	(segment
		(start 134.102 46.201499)
		(end 134.052 46.151499)
		(width 0.2)
		(layer "F.Cu")
		(net 82)
	)
	(segment
		(start 115.509 93.101)
		(end 115.809 92.801)
		(width 0.2)
		(layer "F.Cu")
		(net 82)
	)
	(segment
		(start 123.3 38.115)
		(end 123.3 37.432499)
		(width 0.2)
		(layer "F.Cu")
		(net 82)
	)
	(segment
		(start 114.774 93.101)
		(end 115.509 93.101)
		(width 0.2)
		(layer "F.Cu")
		(net 82)
	)
	(via
		(at 134.177 45.364)
		(size 0.45)
		(drill 0.1)
		(layers "F.Cu" "B.Cu")
		(net 82)
	)
	(via
		(at 123.375 36.9)
		(size 0.45)
		(drill 0.1)
		(layers "F.Cu" "B.Cu")
		(net 82)
	)
	(segment
		(start 130.417156 44.8)
		(end 124.782844 44.8)
		(width 0.2)
		(layer "B.Cu")
		(net 82)
	)
	(segment
		(start 122.2 42.217156)
		(end 122.2 40.382844)
		(width 0.2)
		(layer "B.Cu")
		(net 82)
	)
	(segment
		(start 133.482844 44.1)
		(end 131.117156 44.1)
		(width 0.2)
		(layer "B.Cu")
		(net 82)
	)
	(segment
		(start 124.782844 44.8)
		(end 122.2 42.217156)
		(width 0.2)
		(layer "B.Cu")
		(net 82)
	)
	(segment
		(start 134.052 44.669156)
		(end 133.482844 44.1)
		(width 0.2)
		(layer "B.Cu")
		(net 82)
	)
	(segment
		(start 122.2 40.382844)
		(end 123.25 39.332844)
		(width 0.2)
		(layer "B.Cu")
		(net 82)
	)
	(segment
		(start 123.25 37.025)
		(end 123.375 36.9)
		(width 0.2)
		(layer "B.Cu")
		(net 82)
	)
	(segment
		(start 134.052 45.239)
		(end 134.052 44.669156)
		(width 0.2)
		(layer "B.Cu")
		(net 82)
	)
	(segment
		(start 123.25 39.332844)
		(end 123.25 37.025)
		(width 0.2)
		(layer "B.Cu")
		(net 82)
	)
	(segment
		(start 134.177 45.364)
		(end 134.052 45.239)
		(width 0.2)
		(layer "B.Cu")
		(net 82)
	)
	(segment
		(start 131.117156 44.1)
		(end 130.417156 44.8)
		(width 0.2)
		(layer "B.Cu")
		(net 82)
	)
	(segment
		(start 114.774001 112.1)
		(end 114.774 112.099999)
		(width 0.5)
		(layer "F.Cu")
		(net 83)
	)
	(segment
		(start 117.72 112.1)
		(end 114.774001 112.1)
		(width 0.5)
		(layer "F.Cu")
		(net 83)
	)
	(segment
		(start 151.964 45.788)
		(end 151.964 46.364)
		(width 0.2)
		(layer "F.Cu")
		(net 84)
	)
	(segment
		(start 151.964 46.364)
		(end 152 46.4)
		(width 0.2)
		(layer "F.Cu")
		(net 84)
	)
	(segment
		(start 152.900001 48.100001)
		(end 152.94 48.100001)
		(width 0.2)
		(layer "F.Cu")
		(net 84)
	)
	(segment
		(start 152.94 48.100001)
		(end 153.9 47.14)
		(width 0.2)
		(layer "F.Cu")
		(net 84)
	)
	(segment
		(start 154.9 48.1)
		(end 154.86 48.1)
		(width 0.2)
		(layer "F.Cu")
		(net 84)
	)
	(segment
		(start 153.160001 46.4)
		(end 153.900001 47.14)
		(width 0.2)
		(layer "F.Cu")
		(net 84)
	)
	(segment
		(start 151.900001 48.100001)
		(end 152.900001 48.100001)
		(width 0.2)
		(layer "F.Cu")
		(net 84)
	)
	(segment
		(start 154.86 48.1)
		(end 153.9 47.14)
		(width 0.2)
		(layer "F.Cu")
		(net 84)
	)
	(segment
		(start 152 46.4)
		(end 153.160001 46.4)
		(width 0.2)
		(layer "F.Cu")
		(net 84)
	)
	(segment
		(start 126.148001 133.928001)
		(end 126.62 134.4)
		(width 0.2)
		(layer "F.Cu")
		(net 85)
	)
	(segment
		(start 125.151 133.928001)
		(end 126.148001 133.928001)
		(width 0.2)
		(layer "F.Cu")
		(net 85)
	)
	(segment
		(start 124.653 131.147)
		(end 124.653 131.627001)
		(width 0.25)
		(layer "F.Cu")
		(net 86)
	)
	(segment
		(start 124.203 134.997)
		(end 124.2 135)
		(width 0.25)
		(layer "F.Cu")
		(net 86)
	)
	(segment
		(start 125 130.8)
		(end 124.653 131.147)
		(width 0.25)
		(layer "F.Cu")
		(net 86)
	)
	(segment
		(start 124.653 134.947)
		(end 124.6 135)
		(width 0.25)
		(layer "F.Cu")
		(net 86)
	)
	(segment
		(start 124.6 135)
		(end 124.597 134.997)
		(width 0.25)
		(layer "F.Cu")
		(net 86)
	)
	(segment
		(start 124.653 134.426001)
		(end 124.653 134.947)
		(width 0.25)
		(layer "F.Cu")
		(net 86)
	)
	(segment
		(start 124.203 134.426001)
		(end 124.203 134.997)
		(width 0.25)
		(layer "F.Cu")
		(net 86)
	)
	(segment
		(start 124.597 134.997)
		(end 124.203 134.997)
		(width 0.25)
		(layer "F.Cu")
		(net 86)
	)
	(via
		(at 124.65 135.425)
		(size 0.45)
		(drill 0.1)
		(layers "F.Cu" "B.Cu")
		(net 86)
	)
	(via
		(at 125 130.8)
		(size 0.45)
		(drill 0.1)
		(layers "F.Cu" "B.Cu")
		(net 86)
	)
	(segment
		(start 125 130.8)
		(end 125 135.075)
		(width 0.25)
		(layer "B.Cu")
		(net 86)
	)
	(segment
		(start 125 135.075)
		(end 124.65 135.425)
		(width 0.25)
		(layer "B.Cu")
		(net 86)
	)
	(segment
		(start 154.25 152.35)
		(end 154.6 152)
		(width 0.2)
		(layer "F.Cu")
		(net 87)
	)
	(segment
		(start 130.15 111.35)
		(end 130.15 111.182676)
		(width 0.2)
		(layer "F.Cu")
		(net 87)
	)
	(segment
		(start 138 142)
		(end 138 144.75)
		(width 0.2)
		(layer "F.Cu")
		(net 87)
	)
	(segment
		(start 112.5 121.75)
		(end 112.75 122)
		(width 0.5)
		(layer "F.Cu")
		(net 87)
	)
	(segment
		(start 125.8 132.2)
		(end 125.8 132.4)
		(width 0.2)
		(layer "F.Cu")
		(net 87)
	)
	(segment
		(start 139.785999 120.856999)
		(end 139.785999 121.518997)
		(width 0.2)
		(layer "F.Cu")
		(net 87)
	)
	(segment
		(start 109 120.1)
		(end 109 119.1)
		(width 0.5)
		(layer "F.Cu")
		(net 87)
	)
	(segment
		(start 125.721999 133.478001)
		(end 125.8 133.4)
		(width 0.2)
		(layer "F.Cu")
		(net 87)
	)
	(segment
		(start 139.785999 146.015999)
		(end 140.52 146.75)
		(width 0.2)
		(layer "F.Cu")
		(net 87)
	)
	(segment
		(start 137.354 111.246)
		(end 136.4 112.2)
		(width 0.2)
		(layer "F.Cu")
		(net 87)
	)
	(segment
		(start 118.700001 119.292)
		(end 119.141 119.732999)
		(width 1)
		(layer "F.Cu")
		(net 87)
	)
	(segment
		(start 125.151 132.125)
		(end 125.725 132.125)
		(width 0.2)
		(layer "F.Cu")
		(net 87)
	)
	(segment
		(start 125.8 132.4)
		(end 125.8 132.6)
		(width 0.2)
		(layer "F.Cu")
		(net 87)
	)
	(segment
		(start 137.815998 110.014001)
		(end 138.499999 109.33)
		(width 0.2)
		(layer "F.Cu")
		(net 87)
	)
	(segment
		(start 119.4 128.8)
		(end 119.2 128.6)
		(width 0.2)
		(layer "F.Cu")
		(net 87)
	)
	(segment
		(start 125.8 133.4)
		(end 125.8 133)
		(width 0.2)
		(layer "F.Cu")
		(net 87)
	)
	(segment
		(start 112.8 121.1)
		(end 112.5 121.1)
		(width 0.5)
		(layer "F.Cu")
		(net 87)
	)
	(segment
		(start 106.1 120.1)
		(end 105.5 120.1)
		(width 0.5)
		(layer "F.Cu")
		(net 87)
	)
	(segment
		(start 139.785999 120.856999)
		(end 134.9 120.856999)
		(width 0.2)
		(layer "F.Cu")
		(net 87)
	)
	(segment
		(start 107.574 119.1)
		(end 106.2 119.1)
		(width 0.5)
		(layer "F.Cu")
		(net 87)
	)
	(segment
		(start 119.2 127.2)
		(end 119.7 126.7)
		(width 0.2)
		(layer "F.Cu")
		(net 87)
	)
	(segment
		(start 107.574 120.1)
		(end 109 120.1)
		(width 0.5)
		(layer "F.Cu")
		(net 87)
	)
	(segment
		(start 134.9 124.6)
		(end 134.9 120.856999)
		(width 0.2)
		(layer "F.Cu")
		(net 87)
	)
	(segment
		(start 112.5 121.1)
		(end 112.5 121.75)
		(width 0.5)
		(layer "F.Cu")
		(net 87)
	)
	(segment
		(start 131.856999 120.856999)
		(end 131.36414 120.36414)
		(width 0.2)
		(layer "F.Cu")
		(net 87)
	)
	(segment
		(start 118.891 122)
		(end 119.141 121.75)
		(width 0.5)
		(layer "F.Cu")
		(net 87)
	)
	(segment
		(start 125.151 133.478001)
		(end 125.721999 133.478001)
		(width 0.2)
		(layer "F.Cu")
		(net 87)
	)
	(segment
		(start 152.2 161.4)
		(end 152.2 162.25)
		(width 0.2)
		(layer "F.Cu")
		(net 87)
	)
	(segment
		(start 139.785999 121.518997)
		(end 140.420001 122.152999)
		(width 0.2)
		(layer "F.Cu")
		(net 87)
	)
	(segment
		(start 107.574 120.1)
		(end 106.1 120.1)
		(width 0.5)
		(layer "F.Cu")
		(net 87)
	)
	(segment
		(start 131.36414 120.36414)
		(end 131.36414 116.318535)
		(width 0.2)
		(layer "F.Cu")
		(net 87)
	)
	(segment
		(start 154.6 152)
		(end 155.75 152)
		(width 0.2)
		(layer "F.Cu")
		(net 87)
	)
	(segment
		(start 112.75 122)
		(end 118.891 122)
		(width 0.5)
		(layer "F.Cu")
		(net 87)
	)
	(segment
		(start 114.774 119.1)
		(end 112.5 119.1)
		(width 0.5)
		(layer "F.Cu")
		(net 87)
	)
	(segment
		(start 119.141 123.6)
		(end 119.141 121.75)
		(width 1)
		(layer "F.Cu")
		(net 87)
	)
	(segment
		(start 116.4 120.1)
		(end 114.774001 120.1)
		(width 0.5)
		(layer "F.Cu")
		(net 87)
	)
	(segment
		(start 154.25 153.5)
		(end 154.25 159.35)
		(width 0.2)
		(layer "F.Cu")
		(net 87)
	)
	(segment
		(start 154.25 159.35)
		(end 152.2 161.4)
		(width 0.2)
		(layer "F.Cu")
		(net 87)
	)
	(segment
		(start 116.399999 121.099999)
		(end 116.4 121.1)
		(width 0.5)
		(layer "F.Cu")
		(net 87)
	)
	(segment
		(start 138.704 145.454)
		(end 139.785999 145.454)
		(width 0.2)
		(layer "F.Cu")
		(net 87)
	)
	(segment
		(start 125.8 132.6)
		(end 125.176 132.6)
		(width 0.2)
		(layer "F.Cu")
		(net 87)
	)
	(segment
		(start 119.7 126.7)
		(end 132.8 126.7)
		(width 0.2)
		(layer "F.Cu")
		(net 87)
	)
	(segment
		(start 134.9 120.856999)
		(end 131.856999 120.856999)
		(width 0.2)
		(layer "F.Cu")
		(net 87)
	)
	(segment
		(start 114.774 119.1)
		(end 116.4 119.1)
		(width 0.5)
		(layer "F.Cu")
		(net 87)
	)
	(segment
		(start 138 144.75)
		(end 138.704 145.454)
		(width 0.2)
		(layer "F.Cu")
		(net 87)
	)
	(segment
		(start 131 112.2)
		(end 130.15 111.35)
		(width 0.2)
		(layer "F.Cu")
		(net 87)
	)
	(segment
		(start 116.4 119.1)
		(end 116.4 120.1)
		(width 0.5)
		(layer "F.Cu")
		(net 87)
	)
	(segment
		(start 137.354 110.014001)
		(end 137.815998 110.014001)
		(width 0.2)
		(layer "F.Cu")
		(net 87)
	)
	(segment
		(start 125.176 132.6)
		(end 125.151001 132.575001)
		(width 0.2)
		(layer "F.Cu")
		(net 87)
	)
	(segment
		(start 139.785999 145.454)
		(end 139.785999 146.015999)
		(width 0.2)
		(layer "F.Cu")
		(net 87)
	)
	(segment
		(start 114.773999 120.1)
		(end 114.774 120.100001)
		(width 0.5)
		(layer "F.Cu")
		(net 87)
	)
	(segment
		(start 106.2 119.1)
		(end 106.1 119.2)
		(width 0.5)
		(layer "F.Cu")
		(net 87)
	)
	(segment
		(start 112.5 120.1)
		(end 114.773999 120.1)
		(width 0.5)
		(layer "F.Cu")
		(net 87)
	)
	(segment
		(start 125.151001 133.025001)
		(end 125.774999 133.025001)
		(width 0.2)
		(layer "F.Cu")
		(net 87)
	)
	(segment
		(start 109 119.1)
		(end 107.574 119.1)
		(width 0.5)
		(layer "F.Cu")
		(net 87)
	)
	(segment
		(start 114.774 121.099999)
		(end 116.399999 121.099999)
		(width 0.5)
		(layer "F.Cu")
		(net 87)
	)
	(segment
		(start 120.02 128.8)
		(end 119.4 128.8)
		(width 0.2)
		(layer "F.Cu")
		(net 87)
	)
	(segment
		(start 130.15 111.182676)
		(end 131.36414 109.968536)
		(width 0.2)
		(layer "F.Cu")
		(net 87)
	)
	(segment
		(start 112.5 119.1)
		(end 112.5 120.1)
		(width 0.5)
		(layer "F.Cu")
		(net 87)
	)
	(segment
		(start 125.725 132.125)
		(end 125.8 132.2)
		(width 0.2)
		(layer "F.Cu")
		(net 87)
	)
	(segment
		(start 125.774999 133.025001)
		(end 125.8 133)
		(width 0.2)
		(layer "F.Cu")
		(net 87)
	)
	(segment
		(start 137.354 110.014001)
		(end 137.354 111.246)
		(width 0.2)
		(layer "F.Cu")
		(net 87)
	)
	(segment
		(start 106.1 119.2)
		(end 106.1 120.1)
		(width 0.5)
		(layer "F.Cu")
		(net 87)
	)
	(segment
		(start 112.5 121.1)
		(end 112.5 120.1)
		(width 0.5)
		(layer "F.Cu")
		(net 87)
	)
	(segment
		(start 138.67 141.33)
		(end 138 142)
		(width 0.2)
		(layer "F.Cu")
		(net 87)
	)
	(segment
		(start 114.774001 120.1)
		(end 114.774 120.100001)
		(width 0.5)
		(layer "F.Cu")
		(net 87)
	)
	(segment
		(start 119.141 121.75)
		(end 119.141 119.732999)
		(width 1)
		(layer "F.Cu")
		(net 87)
	)
	(segment
		(start 116.4 121.1)
		(end 116.4 120.1)
		(width 0.5)
		(layer "F.Cu")
		(net 87)
	)
	(segment
		(start 139.564 141.33)
		(end 138.67 141.33)
		(width 0.2)
		(layer "F.Cu")
		(net 87)
	)
	(segment
		(start 125.8 133)
		(end 125.8 132.4)
		(width 0.2)
		(layer "F.Cu")
		(net 87)
	)
	(segment
		(start 105.5 120.1)
		(end 105.100001 120.499999)
		(width 0.5)
		(layer "F.Cu")
		(net 87)
	)
	(segment
		(start 114.774 121.099999)
		(end 112.800001 121.099999)
		(width 0.5)
		(layer "F.Cu")
		(net 87)
	)
	(segment
		(start 118.700001 117.4)
		(end 118.700001 119.292)
		(width 1)
		(layer "F.Cu")
		(net 87)
	)
	(segment
		(start 136.4 112.2)
		(end 131 112.2)
		(width 0.2)
		(layer "F.Cu")
		(net 87)
	)
	(segment
		(start 154.25 153.5)
		(end 154.25 152.35)
		(width 0.2)
		(layer "F.Cu")
		(net 87)
	)
	(segment
		(start 132.8 126.7)
		(end 134.9 124.6)
		(width 0.2)
		(layer "F.Cu")
		(net 87)
	)
	(segment
		(start 105.100001 120.499999)
		(end 103.8 120.499999)
		(width 0.5)
		(layer "F.Cu")
		(net 87)
	)
	(segment
		(start 119.2 128.6)
		(end 119.2 127.2)
		(width 0.2)
		(layer "F.Cu")
		(net 87)
	)
	(segment
		(start 112.800001 121.099999)
		(end 112.8 121.1)
		(width 0.5)
		(layer "F.Cu")
		(net 87)
	)
	(via
		(at 135.8 141.6)
		(size 0.45)
		(drill 0.1)
		(layers "F.Cu" "B.Cu")
		(net 87)
	)
	(via
		(at 154.25 153.5)
		(size 0.45)
		(drill 0.1)
		(layers "F.Cu" "B.Cu")
		(net 87)
	)
	(segment
		(start 140.85 150.75)
		(end 135.8 145.7)
		(width 0.2)
		(layer "B.Cu")
		(net 87)
	)
	(segment
		(start 151.5 150.75)
		(end 140.85 150.75)
		(width 0.2)
		(layer "B.Cu")
		(net 87)
	)
	(segment
		(start 135.8 145.7)
		(end 135.8 141.6)
		(width 0.2)
		(layer "B.Cu")
		(net 87)
	)
	(segment
		(start 154.25 153.5)
		(end 151.5 150.75)
		(width 0.2)
		(layer "B.Cu")
		(net 87)
	)
	(segment
		(start 123 135)
		(end 121.6 135)
		(width 0.2)
		(layer "F.Cu")
		(net 88)
	)
	(segment
		(start 120 127.78)
		(end 120.02 127.8)
		(width 0.2)
		(layer "F.Cu")
		(net 88)
	)
	(segment
		(start 121.18 135)
		(end 120.98 134.8)
		(width 0.2)
		(layer "F.Cu")
		(net 88)
	)
	(segment
		(start 123.3 134.7)
		(end 123 135)
		(width 0.2)
		(layer "F.Cu")
		(net 88)
	)
	(segment
		(start 121.6 135)
		(end 121.18 135)
		(width 0.2)
		(layer "F.Cu")
		(net 88)
	)
	(segment
		(start 123.3 134.426002)
		(end 123.3 134.7)
		(width 0.2)
		(layer "F.Cu")
		(net 88)
	)
	(segment
		(start 120 127.2)
		(end 120 127.78)
		(width 0.2)
		(layer "F.Cu")
		(net 88)
	)
	(segment
		(start 120.02 132.8)
		(end 119.4 132.8)
		(width 0.2)
		(layer "F.Cu")
		(net 88)
	)
	(segment
		(start 121.6 135)
		(end 121.6 134.4)
		(width 0.2)
		(layer "F.Cu")
		(net 88)
	)
	(via
		(at 121.6 134.4)
		(size 0.45)
		(drill 0.1)
		(layers "F.Cu" "B.Cu")
		(net 88)
	)
	(via
		(at 119.4 132.8)
		(size 0.45)
		(drill 0.1)
		(layers "F.Cu" "B.Cu")
		(net 88)
	)
	(via
		(at 120 127.2)
		(size 0.45)
		(drill 0.1)
		(layers "F.Cu" "B.Cu")
		(net 88)
	)
	(segment
		(start 121.6 133.2)
		(end 121.2 132.8)
		(width 0.2)
		(layer "B.Cu")
		(net 88)
	)
	(segment
		(start 119.4 132.8)
		(end 118.8 132.2)
		(width 0.2)
		(layer "B.Cu")
		(net 88)
	)
	(segment
		(start 121.2 132.8)
		(end 119.4 132.8)
		(width 0.2)
		(layer "B.Cu")
		(net 88)
	)
	(segment
		(start 121.6 134.4)
		(end 121.6 133.2)
		(width 0.2)
		(layer "B.Cu")
		(net 88)
	)
	(segment
		(start 118.8 132.2)
		(end 118.8 128.4)
		(width 0.2)
		(layer "B.Cu")
		(net 88)
	)
	(segment
		(start 118.8 128.4)
		(end 120 127.2)
		(width 0.2)
		(layer "B.Cu")
		(net 88)
	)
	(segment
		(start 143.11 162.25)
		(end 150.8 162.25)
		(width 0.125)
		(layer "F.Cu")
		(net 89)
	)
	(segment
		(start 134.859999 153.999999)
		(end 143.11 162.25)
		(width 0.125)
		(layer "F.Cu")
		(net 89)
	)
	(segment
		(start 132.199999 153.999999)
		(end 134.859999 153.999999)
		(width 0.125)
		(layer "F.Cu")
		(net 89)
	)
	(segment
		(start 137.699999 151.999999)
		(end 142.87 157.17)
		(width 0.125)
		(layer "F.Cu")
		(net 90)
	)
	(segment
		(start 132.2 151.999999)
		(end 137.699999 151.999999)
		(width 0.125)
		(layer "F.Cu")
		(net 90)
	)
	(segment
		(start 142.87 157.17)
		(end 150.8 157.17)
		(width 0.125)
		(layer "F.Cu")
		(net 90)
	)
	(segment
		(start 136.409999 152.999999)
		(end 132.2 152.999999)
		(width 0.125)
		(layer "F.Cu")
		(net 91)
	)
	(segment
		(start 143.12 159.71)
		(end 136.409999 152.999999)
		(width 0.125)
		(layer "F.Cu")
		(net 91)
	)
	(segment
		(start 150.8 159.71)
		(end 143.12 159.71)
		(width 0.125)
		(layer "F.Cu")
		(net 91)
	)
	(segment
		(start 129.14 52.46)
		(end 125.5 52.46)
		(width 0.125)
		(layer "F.Cu")
		(net 93)
	)
	(segment
		(start 129.8 51.8)
		(end 129.14 52.46)
		(width 0.125)
		(layer "F.Cu")
		(net 93)
	)
	(segment
		(start 127 102.3)
		(end 118.2 111.1)
		(width 0.125)
		(layer "F.Cu")
		(net 93)
	)
	(segment
		(start 118.2 111.1)
		(end 114.774 111.1)
		(width 0.125)
		(layer "F.Cu")
		(net 93)
	)
	(segment
		(start 127 92.8)
		(end 127 102.3)
		(width 0.125)
		(layer "F.Cu")
		(net 93)
	)
	(via
		(at 127 92.8)
		(size 0.55)
		(drill 0.15)
		(layers "F.Cu" "B.Cu")
		(net 93)
	)
	(via
		(at 129.8 51.8)
		(size 0.55)
		(drill 0.15)
		(layers "F.Cu" "B.Cu")
		(net 93)
	)
	(segment
		(start 127 71)
		(end 131.1 66.9)
		(width 0.125)
		(layer "B.Cu")
		(net 93)
	)
	(segment
		(start 131.1 66.9)
		(end 131.1 53.1)
		(width 0.125)
		(layer "B.Cu")
		(net 93)
	)
	(segment
		(start 131.1 53.1)
		(end 129.8 51.8)
		(width 0.125)
		(layer "B.Cu")
		(net 93)
	)
	(segment
		(start 127 92.8)
		(end 127 71)
		(width 0.125)
		(layer "B.Cu")
		(net 93)
	)
	(segment
		(start 142.081 46.527999)
		(end 142.081 47.299999)
		(width 0.125)
		(layer "F.Cu")
		(net 95)
	)
	(segment
		(start 142.081 44.919)
		(end 142.1 44.9)
		(width 0.125)
		(layer "F.Cu")
		(net 95)
	)
	(segment
		(start 142.081 46.527999)
		(end 142.081 44.919)
		(width 0.125)
		(layer "F.Cu")
		(net 95)
	)
	(segment
		(start 142.081 49.319)
		(end 141.660661 49.739339)
		(width 0.125)
		(layer "F.Cu")
		(net 95)
	)
	(segment
		(start 141.660661 49.739339)
		(end 141.660661 50.32)
		(width 0.125)
		(layer "F.Cu")
		(net 95)
	)
	(segment
		(start 127.3 38.115)
		(end 127.3 36.8)
		(width 0.125)
		(layer "F.Cu")
		(net 95)
	)
	(segment
		(start 142.081 47.299999)
		(end 142.081 49.319)
		(width 0.125)
		(layer "F.Cu")
		(net 95)
	)
	(via
		(at 142.1 44.9)
		(size 0.45)
		(drill 0.1)
		(layers "F.Cu" "B.Cu")
		(net 95)
	)
	(via
		(at 127.3 36.8)
		(size 0.45)
		(drill 0.1)
		(layers "F.Cu" "B.Cu")
		(net 95)
	)
	(segment
		(start 129.2 34.9)
		(end 127.3 36.8)
		(width 0.125)
		(layer "B.Cu")
		(net 95)
	)
	(segment
		(start 135.3 35.8)
		(end 134.4 34.9)
		(width 0.125)
		(layer "B.Cu")
		(net 95)
	)
	(segment
		(start 140.6 35.8)
		(end 135.3 35.8)
		(width 0.125)
		(layer "B.Cu")
		(net 95)
	)
	(segment
		(start 142.1 37.3)
		(end 140.6 35.8)
		(width 0.125)
		(layer "B.Cu")
		(net 95)
	)
	(segment
		(start 142.1 44.9)
		(end 142.1 37.3)
		(width 0.125)
		(layer "B.Cu")
		(net 95)
	)
	(segment
		(start 134.4 34.9)
		(end 129.2 34.9)
		(width 0.125)
		(layer "B.Cu")
		(net 95)
	)
	(segment
		(start 111.6 83.525)
		(end 111.725 83.4)
		(width 0.2)
		(layer "F.Cu")
		(net 96)
	)
	(segment
		(start 107.574 107.1)
		(end 108.309 107.1)
		(width 0.2)
		(layer "F.Cu")
		(net 96)
	)
	(segment
		(start 108.609 106.8)
		(end 109.882844 106.8)
		(width 0.2)
		(layer "F.Cu")
		(net 96)
	)
	(segment
		(start 109.882844 106.8)
		(end 111.6 105.082844)
		(width 0.2)
		(layer "F.Cu")
		(net 96)
	)
	(segment
		(start 119.55 47.67)
		(end 119.55 46.95)
		(width 0.2)
		(layer "F.Cu")
		(net 96)
	)
	(segment
		(start 108.309 107.1)
		(end 108.609 106.8)
		(width 0.2)
		(layer "F.Cu")
		(net 96)
	)
	(segment
		(start 119.55 46.229999)
		(end 119.55 46.95)
		(width 0.2)
		(layer "F.Cu")
		(net 96)
	)
	(segment
		(start 111.6 105.082844)
		(end 111.6 83.525)
		(width 0.2)
		(layer "F.Cu")
		(net 96)
	)
	(via
		(at 111.725 83.4)
		(size 0.45)
		(drill 0.1)
		(layers "F.Cu" "B.Cu")
		(net 96)
	)
	(via
		(at 119.55 46.95)
		(size 0.45)
		(drill 0.1)
		(layers "F.Cu" "B.Cu")
		(net 96)
	)
	(segment
		(start 111.6 83.275)
		(end 111.725 83.4)
		(width 0.2)
		(layer "B.Cu")
		(net 96)
	)
	(segment
		(start 119.55 46.95)
		(end 119.25 47.25)
		(width 0.2)
		(layer "B.Cu")
		(net 96)
	)
	(segment
		(start 111.6 51.882844)
		(end 111.6 83.275)
		(width 0.2)
		(layer "B.Cu")
		(net 96)
	)
	(segment
		(start 119.25 47.832844)
		(end 117.282844 49.8)
		(width 0.2)
		(layer "B.Cu")
		(net 96)
	)
	(segment
		(start 117.282844 49.8)
		(end 113.682844 49.8)
		(width 0.2)
		(layer "B.Cu")
		(net 96)
	)
	(segment
		(start 113.682844 49.8)
		(end 111.6 51.882844)
		(width 0.2)
		(layer "B.Cu")
		(net 96)
	)
	(segment
		(start 119.25 47.25)
		(end 119.25 47.832844)
		(width 0.2)
		(layer "B.Cu")
		(net 96)
	)
	(segment
		(start 110.189949 105.167244)
		(end 110.274802 105.082392)
		(width 0.2)
		(layer "F.Cu")
		(net 97)
	)
	(segment
		(start 111.2 104.917156)
		(end 111.2 83.525)
		(width 0.2)
		(layer "F.Cu")
		(net 97)
	)
	(segment
		(start 111.2 83.525)
		(end 111.075 83.4)
		(width 0.2)
		(layer "F.Cu")
		(net 97)
	)
	(segment
		(start 108.609 106.4)
		(end 109.717156 106.4)
		(width 0.2)
		(layer "F.Cu")
		(net 97)
	)
	(segment
		(start 110.614214 105.082391)
		(end 110.654785 105.122962)
		(width 0.2)
		(layer "F.Cu")
		(net 97)
	)
	(segment
		(start 118.55 47.67)
		(end 118.55 46.95)
		(width 0.2)
		(layer "F.Cu")
		(net 97)
	)
	(segment
		(start 109.717156 106.4)
		(end 110.230518 105.886638)
		(width 0.2)
		(layer "F.Cu")
		(net 97)
	)
	(segment
		(start 118.55 46.23)
		(end 118.55 46.95)
		(width 0.2)
		(layer "F.Cu")
		(net 97)
	)
	(segment
		(start 110.994197 105.122962)
		(end 111.2 104.917156)
		(width 0.2)
		(layer "F.Cu")
		(net 97)
	)
	(segment
		(start 108.309 106.1)
		(end 108.609 106.4)
		(width 0.2)
		(layer "F.Cu")
		(net 97)
	)
	(segment
		(start 110.230519 105.547226)
		(end 110.189949 105.506656)
		(width 0.2)
		(layer "F.Cu")
		(net 97)
	)
	(segment
		(start 107.574 106.1)
		(end 108.309 106.1)
		(width 0.2)
		(layer "F.Cu")
		(net 97)
	)
	(via
		(at 118.55 46.95)
		(size 0.45)
		(drill 0.1)
		(layers "F.Cu" "B.Cu")
		(net 97)
	)
	(via
		(at 111.075 83.4)
		(size 0.45)
		(drill 0.1)
		(layers "F.Cu" "B.Cu")
		(net 97)
	)
	(arc
		(start 110.274802 105.082392)
		(mid 110.444509 105.012096)
		(end 110.614214 105.082391)
		(width 0.2)
		(layer "F.Cu")
		(net 97)
	)
	(arc
		(start 110.654785 105.122962)
		(mid 110.82449 105.193258)
		(end 110.994197 105.122962)
		(width 0.2)
		(layer "F.Cu")
		(net 97)
	)
	(arc
		(start 110.189949 105.506656)
		(mid 110.119653 105.336951)
		(end 110.189949 105.167244)
		(width 0.2)
		(layer "F.Cu")
		(net 97)
	)
	(arc
		(start 110.230518 105.886638)
		(mid 110.300813 105.716932)
		(end 110.230519 105.547226)
		(width 0.2)
		(layer "F.Cu")
		(net 97)
	)
	(segment
		(start 111.2 51.717156)
		(end 111.2 83.275)
		(width 0.2)
		(layer "B.Cu")
		(net 97)
	)
	(segment
		(start 118.85 47.25)
		(end 118.85 47.667156)
		(width 0.2)
		(layer "B.Cu")
		(net 97)
	)
	(segment
		(start 117.117156 49.4)
		(end 113.517156 49.4)
		(width 0.2)
		(layer "B.Cu")
		(net 97)
	)
	(segment
		(start 118.55 46.95)
		(end 118.85 47.25)
		(width 0.2)
		(layer "B.Cu")
		(net 97)
	)
	(segment
		(start 113.517156 49.4)
		(end 111.2 51.717156)
		(width 0.2)
		(layer "B.Cu")
		(net 97)
	)
	(segment
		(start 118.85 47.667156)
		(end 117.117156 49.4)
		(width 0.2)
		(layer "B.Cu")
		(net 97)
	)
	(segment
		(start 111.2 83.275)
		(end 111.075 83.4)
		(width 0.2)
		(layer "B.Cu")
		(net 97)
	)
	(segment
		(start 121.2 143.95)
		(end 121.2 146.429499)
		(width 0.125)
		(layer "F.Cu")
		(net 99)
	)
	(segment
		(start 143.781981 54.381981)
		(end 143.8 54.4)
		(width 0.125)
		(layer "F.Cu")
		(net 99)
	)
	(segment
		(start 143.781981 51.28)
		(end 143.781981 54.381981)
		(width 0.125)
		(layer "F.Cu")
		(net 99)
	)
	(segment
		(start 121.2 146.429499)
		(end 121.1245 146.504999)
		(width 0.125)
		(layer "F.Cu")
		(net 99)
	)
	(via
		(at 121.2 143.95)
		(size 0.45)
		(drill 0.1)
		(layers "F.Cu" "B.Cu")
		(net 99)
	)
	(via
		(at 143.8 54.4)
		(size 0.45)
		(drill 0.1)
		(layers "F.Cu" "B.Cu")
		(net 99)
	)
	(segment
		(start 118.05 137.05)
		(end 118.05 127.75)
		(width 0.125)
		(layer "B.Cu")
		(net 99)
	)
	(segment
		(start 125.375 124.825)
		(end 143 107.2)
		(width 0.125)
		(layer "B.Cu")
		(net 99)
	)
	(segment
		(start 121.2 143.95)
		(end 121.2 140.2)
		(width 0.125)
		(layer "B.Cu")
		(net 99)
	)
	(segment
		(start 121.2 140.2)
		(end 118.05 137.05)
		(width 0.125)
		(layer "B.Cu")
		(net 99)
	)
	(segment
		(start 143.4 106)
		(end 150.4 99)
		(width 0.125)
		(layer "B.Cu")
		(net 99)
	)
	(segment
		(start 146.35 56.95)
		(end 143.8 54.4)
		(width 0.125)
		(layer "B.Cu")
		(net 99)
	)
	(segment
		(start 120.975 124.825)
		(end 125.375 124.825)
		(width 0.125)
		(layer "B.Cu")
		(net 99)
	)
	(segment
		(start 118.05 127.75)
		(end 120.975 124.825)
		(width 0.125)
		(layer "B.Cu")
		(net 99)
	)
	(segment
		(start 149.2 77.6)
		(end 149.2 58.5)
		(width 0.125)
		(layer "B.Cu")
		(net 99)
	)
	(segment
		(start 143 106)
		(end 143.4 106)
		(width 0.125)
		(layer "B.Cu")
		(net 99)
	)
	(segment
		(start 150.4 99)
		(end 150.4 78.8)
		(width 0.125)
		(layer "B.Cu")
		(net 99)
	)
	(segment
		(start 143 107.2)
		(end 143 106)
		(width 0.125)
		(layer "B.Cu")
		(net 99)
	)
	(segment
		(start 147.65 56.95)
		(end 146.35 56.95)
		(width 0.125)
		(layer "B.Cu")
		(net 99)
	)
	(segment
		(start 150.4 78.8)
		(end 149.2 77.6)
		(width 0.125)
		(layer "B.Cu")
		(net 99)
	)
	(segment
		(start 149.2 58.5)
		(end 147.65 56.95)
		(width 0.125)
		(layer "B.Cu")
		(net 99)
	)
	(segment
		(start 141.581 48.619)
		(end 141.581 47.3)
		(width 0.125)
		(layer "F.Cu")
		(net 101)
	)
	(segment
		(start 141.581 46.527999)
		(end 141.581 45.419)
		(width 0.125)
		(layer "F.Cu")
		(net 101)
	)
	(segment
		(start 127.8 36.9)
		(end 127.9 36.8)
		(width 0.125)
		(layer "F.Cu")
		(net 101)
	)
	(segment
		(start 140.6 50.32)
		(end 140.6 49.6)
		(width 0.125)
		(layer "F.Cu")
		(net 101)
	)
	(segment
		(start 141.581 46.527999)
		(end 141.581 47.3)
		(width 0.125)
		(layer "F.Cu")
		(net 101)
	)
	(segment
		(start 141.581 45.419)
		(end 141.6 45.4)
		(width 0.125)
		(layer "F.Cu")
		(net 101)
	)
	(segment
		(start 127.8 38.115)
		(end 127.8 36.9)
		(width 0.125)
		(layer "F.Cu")
		(net 101)
	)
	(segment
		(start 140.6 49.6)
		(end 141.581 48.619)
		(width 0.125)
		(layer "F.Cu")
		(net 101)
	)
	(via
		(at 127.9 36.8)
		(size 0.45)
		(drill 0.1)
		(layers "F.Cu" "B.Cu")
		(net 101)
	)
	(via
		(at 141.6 45.4)
		(size 0.45)
		(drill 0.1)
		(layers "F.Cu" "B.Cu")
		(net 101)
	)
	(segment
		(start 141.6 40)
		(end 141 39.4)
		(width 0.125)
		(layer "B.Cu")
		(net 101)
	)
	(segment
		(start 129.3 35.4)
		(end 134.4 35.4)
		(width 0.125)
		(layer "B.Cu")
		(net 101)
	)
	(segment
		(start 141.6 45.4)
		(end 141.6 40)
		(width 0.125)
		(layer "B.Cu")
		(net 101)
	)
	(segment
		(start 127.9 36.8)
		(end 129.3 35.4)
		(width 0.125)
		(layer "B.Cu")
		(net 101)
	)
	(segment
		(start 141 39.4)
		(end 138.4 39.4)
		(width 0.125)
		(layer "B.Cu")
		(net 101)
	)
	(segment
		(start 138.4 39.4)
		(end 134.4 35.4)
		(width 0.125)
		(layer "B.Cu")
		(net 101)
	)
	(segment
		(start 140.6 51.28)
		(end 140.6 55.5)
		(width 0.125)
		(layer "F.Cu")
		(net 102)
	)
	(segment
		(start 140.6 55.5)
		(end 141.2 56.1)
		(width 0.125)
		(layer "F.Cu")
		(net 102)
	)
	(segment
		(start 114.774 117.1)
		(end 116.5 117.1)
		(width 0.125)
		(layer "F.Cu")
		(net 102)
	)
	(via
		(at 141.2 56.1)
		(size 0.45)
		(drill 0.1)
		(layers "F.Cu" "B.Cu")
		(net 102)
	)
	(via
		(at 116.5 117.1)
		(size 0.45)
		(drill 0.1)
		(layers "F.Cu" "B.Cu")
		(net 102)
	)
	(segment
		(start 138.9 69.5)
		(end 140.1 68.3)
		(width 0.125)
		(layer "B.Cu")
		(net 102)
	)
	(segment
		(start 127.8 74.7)
		(end 133 69.5)
		(width 0.125)
		(layer "B.Cu")
		(net 102)
	)
	(segment
		(start 140.1 68.3)
		(end 140.1 62.2)
		(width 0.125)
		(layer "B.Cu")
		(net 102)
	)
	(segment
		(start 117.5 108.8)
		(end 127.8 98.5)
		(width 0.125)
		(layer "B.Cu")
		(net 102)
	)
	(segment
		(start 127.8 98.5)
		(end 127.8 74.7)
		(width 0.125)
		(layer "B.Cu")
		(net 102)
	)
	(segment
		(start 117.5 113.3)
		(end 117.5 108.8)
		(width 0.125)
		(layer "B.Cu")
		(net 102)
	)
	(segment
		(start 140.1 62.2)
		(end 141.2 61.1)
		(width 0.125)
		(layer "B.Cu")
		(net 102)
	)
	(segment
		(start 115.7 115.1)
		(end 117.5 113.3)
		(width 0.125)
		(layer "B.Cu")
		(net 102)
	)
	(segment
		(start 116.5 117.1)
		(end 115.7 116.3)
		(width 0.125)
		(layer "B.Cu")
		(net 102)
	)
	(segment
		(start 115.7 116.3)
		(end 115.7 115.1)
		(width 0.125)
		(layer "B.Cu")
		(net 102)
	)
	(segment
		(start 141.2 61.1)
		(end 141.2 56.1)
		(width 0.125)
		(layer "B.Cu")
		(net 102)
	)
	(segment
		(start 133 69.5)
		(end 138.9 69.5)
		(width 0.125)
		(layer "B.Cu")
		(net 102)
	)
	(segment
		(start 141.660661 51.28)
		(end 141.660661 55.960661)
		(width 0.125)
		(layer "F.Cu")
		(net 103)
	)
	(segment
		(start 141.660661 55.960661)
		(end 141.9 56.2)
		(width 0.125)
		(layer "F.Cu")
		(net 103)
	)
	(segment
		(start 114.774001 116.1)
		(end 116.5 116.1)
		(width 0.125)
		(layer "F.Cu")
		(net 103)
	)
	(segment
		(start 141.9 56.2)
		(end 141.9 57.2)
		(width 0.125)
		(layer "F.Cu")
		(net 103)
	)
	(via
		(at 141.9 57.2)
		(size 0.45)
		(drill 0.1)
		(layers "F.Cu" "B.Cu")
		(net 103)
	)
	(via
		(at 116.5 116.1)
		(size 0.45)
		(drill 0.1)
		(layers "F.Cu" "B.Cu")
		(net 103)
	)
	(segment
		(start 141.6 66.2)
		(end 141.6 57.5)
		(width 0.125)
		(layer "B.Cu")
		(net 103)
	)
	(segment
		(start 141.6 57.5)
		(end 141.9 57.2)
		(width 0.125)
		(layer "B.Cu")
		(net 103)
	)
	(segment
		(start 118.4 114.2)
		(end 118.4 109.5)
		(width 0.125)
		(layer "B.Cu")
		(net 103)
	)
	(segment
		(start 142.6 67.2)
		(end 141.6 66.2)
		(width 0.125)
		(layer "B.Cu")
		(net 103)
	)
	(segment
		(start 142.6 70.2)
		(end 142.6 67.2)
		(width 0.125)
		(layer "B.Cu")
		(net 103)
	)
	(segment
		(start 132.45 73.15)
		(end 139.65 73.15)
		(width 0.125)
		(layer "B.Cu")
		(net 103)
	)
	(segment
		(start 118.4 109.5)
		(end 128.4 99.5)
		(width 0.125)
		(layer "B.Cu")
		(net 103)
	)
	(segment
		(start 128.4 99.5)
		(end 128.4 77.2)
		(width 0.125)
		(layer "B.Cu")
		(net 103)
	)
	(segment
		(start 116.5 116.1)
		(end 118.4 114.2)
		(width 0.125)
		(layer "B.Cu")
		(net 103)
	)
	(segment
		(start 139.65 73.15)
		(end 142.6 70.2)
		(width 0.125)
		(layer "B.Cu")
		(net 103)
	)
	(segment
		(start 128.4 77.2)
		(end 132.45 73.15)
		(width 0.125)
		(layer "B.Cu")
		(net 103)
	)
	(segment
		(start 138.762 117.390999)
		(end 138.5 117.652999)
		(width 0.2)
		(layer "F.Cu")
		(net 104)
	)
	(segment
		(start 138.753 119.905999)
		(end 139.786 119.905999)
		(width 0.2)
		(layer "F.Cu")
		(net 104)
	)
	(segment
		(start 139.564 117.390999)
		(end 138.762 117.390999)
		(width 0.2)
		(layer "F.Cu")
		(net 104)
	)
	(segment
		(start 138.5 119.652999)
		(end 138.753 119.905999)
		(width 0.2)
		(layer "F.Cu")
		(net 104)
	)
	(segment
		(start 138.5 117.652999)
		(end 138.5 119.652999)
		(width 0.2)
		(layer "F.Cu")
		(net 104)
	)
	(segment
		(start 128.424999 146.854999)
		(end 127.724998 146.154999)
		(width 0.125)
		(layer "F.Cu")
		(net 105)
	)
	(segment
		(start 122.874999 142.725001)
		(end 122.9 142.7)
		(width 0.125)
		(layer "F.Cu")
		(net 105)
	)
	(segment
		(start 121.425 147.604999)
		(end 121.095001 147.604999)
		(width 0.125)
		(layer "F.Cu")
		(net 105)
	)
	(segment
		(start 122.6 130.95)
		(end 123.1 130.95)
		(width 0.125)
		(layer "F.Cu")
		(net 105)
	)
	(segment
		(start 122.874999 146.155)
		(end 121.425 147.604999)
		(width 0.125)
		(layer "F.Cu")
		(net 105)
	)
	(segment
		(start 122.3 130.65)
		(end 122.6 130.95)
		(width 0.125)
		(layer "F.Cu")
		(net 105)
	)
	(segment
		(start 126.580998 149.299)
		(end 126.824999 149.054999)
		(width 0.125)
		(layer "F.Cu")
		(net 105)
	)
	(segment
		(start 121.095001 147.604999)
		(end 120.173999 148.526001)
		(width 0.125)
		(layer "F.Cu")
		(net 105)
	)
	(segment
		(start 120.173999 148.526001)
		(end 120.173999 148.853999)
		(width 0.125)
		(layer "F.Cu")
		(net 105)
	)
	(segment
		(start 127.724998 146.154999)
		(end 122.874999 146.155)
		(width 0.125)
		(layer "F.Cu")
		(net 105)
	)
	(segment
		(start 126.824999 149.054999)
		(end 127.9 149.054999)
		(width 0.125)
		(layer "F.Cu")
		(net 105)
	)
	(segment
		(start 128.424999 148.53)
		(end 128.424999 146.854999)
		(width 0.125)
		(layer "F.Cu")
		(net 105)
	)
	(segment
		(start 123.3 131.15)
		(end 123.3 131.627001)
		(width 0.125)
		(layer "F.Cu")
		(net 105)
	)
	(segment
		(start 122.3 129.1)
		(end 121 127.8)
		(width 0.125)
		(layer "F.Cu")
		(net 105)
	)
	(segment
		(start 126.580998 150.426999)
		(end 126.580998 149.299)
		(width 0.125)
		(layer "F.Cu")
		(net 105)
	)
	(segment
		(start 122.3 129.1)
		(end 122.3 130.65)
		(width 0.125)
		(layer "F.Cu")
		(net 105)
	)
	(segment
		(start 123.1 130.95)
		(end 123.3 131.15)
		(width 0.125)
		(layer "F.Cu")
		(net 105)
	)
	(segment
		(start 122.874999 146.155)
		(end 122.874999 142.725001)
		(width 0.125)
		(layer "F.Cu")
		(net 105)
	)
	(segment
		(start 120.7445 149.4245)
		(end 120.7445 150.154999)
		(width 0.125)
		(layer "F.Cu")
		(net 105)
	)
	(segment
		(start 120.173999 148.853999)
		(end 120.7445 149.4245)
		(width 0.125)
		(layer "F.Cu")
		(net 105)
	)
	(segment
		(start 127.9 149.054999)
		(end 128.424999 148.53)
		(width 0.125)
		(layer "F.Cu")
		(net 105)
	)
	(segment
		(start 121 127.8)
		(end 120.98 127.8)
		(width 0.125)
		(layer "F.Cu")
		(net 105)
	)
	(via
		(at 122.3 129.1)
		(size 0.45)
		(drill 0.1)
		(layers "F.Cu" "B.Cu")
		(net 105)
	)
	(via
		(at 122.9 142.7)
		(size 0.45)
		(drill 0.1)
		(layers "F.Cu" "B.Cu")
		(net 105)
	)
	(segment
		(start 127.1 137.2)
		(end 127.1 133.4)
		(width 0.125)
		(layer "B.Cu")
		(net 105)
	)
	(segment
		(start 122.3 126.7)
		(end 122.3 129.1)
		(width 0.125)
		(layer "B.Cu")
		(net 105)
	)
	(segment
		(start 123.9 140.4)
		(end 127.1 137.2)
		(width 0.125)
		(layer "B.Cu")
		(net 105)
	)
	(segment
		(start 132.2 127.4)
		(end 130.6 125.8)
		(width 0.125)
		(layer "B.Cu")
		(net 105)
	)
	(segment
		(start 130.6 125.8)
		(end 123.2 125.8)
		(width 0.125)
		(layer "B.Cu")
		(net 105)
	)
	(segment
		(start 128.4 133.4)
		(end 132.2 129.6)
		(width 0.125)
		(layer "B.Cu")
		(net 105)
	)
	(segment
		(start 123.9 141.7)
		(end 123.9 140.4)
		(width 0.125)
		(layer "B.Cu")
		(net 105)
	)
	(segment
		(start 122.9 142.7)
		(end 123.9 141.7)
		(width 0.125)
		(layer "B.Cu")
		(net 105)
	)
	(segment
		(start 132.2 129.6)
		(end 132.2 127.4)
		(width 0.125)
		(layer "B.Cu")
		(net 105)
	)
	(segment
		(start 127.1 133.4)
		(end 128.4 133.4)
		(width 0.125)
		(layer "B.Cu")
		(net 105)
	)
	(segment
		(start 123.2 125.8)
		(end 122.3 126.7)
		(width 0.125)
		(layer "B.Cu")
		(net 105)
	)
	(segment
		(start 122.352 132.575001)
		(end 122.025001 132.575001)
		(width 0.125)
		(layer "F.Cu")
		(net 106)
	)
	(segment
		(start 120.979999 129.799999)
		(end 120.979999 128.800001)
		(width 0.125)
		(layer "F.Cu")
		(net 106)
	)
	(segment
		(start 121.85 132.4)
		(end 121.85 130.67)
		(width 0.125)
		(layer "F.Cu")
		(net 106)
	)
	(segment
		(start 120.979999 128.800001)
		(end 120.98 128.8)
		(width 0.125)
		(layer "F.Cu")
		(net 106)
	)
	(segment
		(start 122.025001 132.575001)
		(end 121.85 132.4)
		(width 0.125)
		(layer "F.Cu")
		(net 106)
	)
	(segment
		(start 121.85 130.67)
		(end 120.979999 129.799999)
		(width 0.125)
		(layer "F.Cu")
		(net 106)
	)
	(segment
		(start 122.352 133.928001)
		(end 121.108001 133.928001)
		(width 0.125)
		(layer "F.Cu")
		(net 107)
	)
	(segment
		(start 121.108001 133.928001)
		(end 120.98 133.8)
		(width 0.125)
		(layer "F.Cu")
		(net 107)
	)
	(segment
		(start 120.98 132.8)
		(end 120.98 133.8)
		(width 0.125)
		(layer "F.Cu")
		(net 107)
	)
	(segment
		(start 120.98 130.8)
		(end 120.98 131.799999)
		(width 0.125)
		(layer "F.Cu")
		(net 108)
	)
	(segment
		(start 120.979999 131.8)
		(end 121.4 131.8)
		(width 0.125)
		(layer "F.Cu")
		(net 108)
	)
	(segment
		(start 121.6 133.2)
		(end 121.878001 133.478001)
		(width 0.125)
		(layer "F.Cu")
		(net 108)
	)
	(segment
		(start 120.98 131.799999)
		(end 120.979999 131.8)
		(width 0.125)
		(layer "F.Cu")
		(net 108)
	)
	(segment
		(start 121.878001 133.478001)
		(end 122.352 133.478001)
		(width 0.125)
		(layer "F.Cu")
		(net 108)
	)
	(segment
		(start 121.4 131.8)
		(end 121.6 132)
		(width 0.125)
		(layer "F.Cu")
		(net 108)
	)
	(segment
		(start 121.6 132)
		(end 121.6 133.2)
		(width 0.125)
		(layer "F.Cu")
		(net 108)
	)
	(segment
		(start 138.16 37.055)
		(end 137.96 37.255)
		(width 0.2)
		(layer "F.Cu")
		(net 113)
	)
	(segment
		(start 149.7 50)
		(end 151.1 48.6)
		(width 0.2)
		(layer "F.Cu")
		(net 113)
	)
	(segment
		(start 149.3 50)
		(end 149.7 50)
		(width 0.2)
		(layer "F.Cu")
		(net 113)
	)
	(segment
		(start 151.1 45.4)
		(end 151.37 45.13)
		(width 0.2)
		(layer "F.Cu")
		(net 113)
	)
	(segment
		(start 139.82 43.9)
		(end 139.3 43.38)
		(width 0.2)
		(layer "F.Cu")
		(net 113)
	)
	(segment
		(start 151.140001 47.140001)
		(end 151.1 47.1)
		(width 0.2)
		(layer "F.Cu")
		(net 113)
	)
	(segment
		(start 141.802 37.998)
		(end 141.9 37.9)
		(width 0.2)
		(layer "F.Cu")
		(net 113)
	)
	(segment
		(start 140.5 43.9)
		(end 139.82 43.9)
		(width 0.2)
		(layer "F.Cu")
		(net 113)
	)
	(segment
		(start 141.802 38.5)
		(end 141.802 37.998)
		(width 0.2)
		(layer "F.Cu")
		(net 113)
	)
	(segment
		(start 151.1 47.1)
		(end 151.1 45.4)
		(width 0.2)
		(layer "F.Cu")
		(net 113)
	)
	(segment
		(start 141.9 36.5)
		(end 141.6 36.2)
		(width 0.2)
		(layer "F.Cu")
		(net 113)
	)
	(segment
		(start 141.6 43.9)
		(end 141.802 43.698)
		(width 0.2)
		(layer "F.Cu")
		(net 113)
	)
	(segment
		(start 151.37 45.13)
		(end 151.964 45.13)
		(width 0.2)
		(layer "F.Cu")
		(net 113)
	)
	(segment
		(start 138.16 36.89)
		(end 138.16 37.055)
		(width 0.2)
		(layer "F.Cu")
		(net 113)
	)
	(segment
		(start 141.802 43.698)
		(end 141.802 38.5)
		(width 0.2)
		(layer "F.Cu")
		(net 113)
	)
	(segment
		(start 138.85 36.2)
		(end 138.16 36.89)
		(width 0.2)
		(layer "F.Cu")
		(net 113)
	)
	(segment
		(start 141.9 37.9)
		(end 141.9 36.5)
		(width 0.2)
		(layer "F.Cu")
		(net 113)
	)
	(segment
		(start 149.000001 50.299999)
		(end 149.3 50)
		(width 0.2)
		(layer "F.Cu")
		(net 113)
	)
	(segment
		(start 151.1 48.6)
		(end 151.1 47.1)
		(width 0.2)
		(layer "F.Cu")
		(net 113)
	)
	(segment
		(start 141.6 36.2)
		(end 138.85 36.2)
		(width 0.2)
		(layer "F.Cu")
		(net 113)
	)
	(segment
		(start 151.900001 47.140001)
		(end 151.140001 47.140001)
		(width 0.2)
		(layer "F.Cu")
		(net 113)
	)
	(segment
		(start 149.000001 51.313)
		(end 149.000001 50.299999)
		(width 0.2)
		(layer "F.Cu")
		(net 113)
	)
	(segment
		(start 140.5 43.9)
		(end 141.6 43.9)
		(width 0.2)
		(layer "F.Cu")
		(net 113)
	)
	(segment
		(start 152.900001 47.140001)
		(end 151.900001 47.140001)
		(width 0.2)
		(layer "F.Cu")
		(net 113)
	)
	(segment
		(start 147.543 54.5)
		(end 147.042 55.001)
		(width 0.25)
		(layer "F.Cu")
		(net 114)
	)
	(segment
		(start 148.312 54.5)
		(end 147.543 54.5)
		(width 0.25)
		(layer "F.Cu")
		(net 114)
	)
	(segment
		(start 156.75 48.75)
		(end 156.8 48.7)
		(width 0.2)
		(layer "F.Cu")
		(net 115)
	)
	(segment
		(start 143.4 85.6)
		(end 148.2 85.6)
		(width 0.3)
		(layer "F.Cu")
		(net 115)
	)
	(segment
		(start 141.9 84.1)
		(end 141.9 83.499998)
		(width 0.3)
		(layer "F.Cu")
		(net 115)
	)
	(segment
		(start 156.66 47.14)
		(end 156.8 47)
		(width 0.25)
		(layer "F.Cu")
		(net 115)
	)
	(segment
		(start 153.062 52.502001)
		(end 152.187 52.502)
		(width 0.15)
		(layer "F.Cu")
		(net 115)
	)
	(segment
		(start 148.2 85.6)
		(end 148.632 86.032)
		(width 0.3)
		(layer "F.Cu")
		(net 115)
	)
	(segment
		(start 154.9 47.14)
		(end 156.66 47.14)
		(width 0.25)
		(layer "F.Cu")
		(net 115)
	)
	(segment
		(start 154.256999 45.1)
		(end 153.956999 44.8)
		(width 0.25)
		(layer "F.Cu")
		(net 115)
	)
	(segment
		(start 156.75 50)
		(end 156.75 48.75)
		(width 0.2)
		(layer "F.Cu")
		(net 115)
	)
	(segment
		(start 153.25 50)
		(end 156.75 50)
		(width 0.2)
		(layer "F.Cu")
		(net 115)
	)
	(segment
		(start 153 50.25)
		(end 153.25 50)
		(width 0.2)
		(layer "F.Cu")
		(net 115)
	)
	(segment
		(start 145.2 89.224999)
		(end 145.2 87.4)
		(width 0.3)
		(layer "F.Cu")
		(net 115)
	)
	(segment
		(start 156.3 45.1)
		(end 154.256999 45.1)
		(width 0.25)
		(layer "F.Cu")
		(net 115)
	)
	(segment
		(start 148.632 86.032)
		(end 148.632 87)
		(width 0.3)
		(layer "F.Cu")
		(net 115)
	)
	(segment
		(start 156.8 45.6)
		(end 156.3 45.1)
		(width 0.25)
		(layer "F.Cu")
		(net 115)
	)
	(segment
		(start 143.4 85.6)
		(end 141.9 84.1)
		(width 0.3)
		(layer "F.Cu")
		(net 115)
	)
	(segment
		(start 145.2 87.4)
		(end 143.4 85.6)
		(width 0.3)
		(layer "F.Cu")
		(net 115)
	)
	(segment
		(start 156.8 47)
		(end 156.8 45.6)
		(width 0.25)
		(layer "F.Cu")
		(net 115)
	)
	(via
		(at 153.062 52.502001)
		(size 0.55)
		(drill 0.15)
		(layers "F.Cu" "B.Cu")
		(net 115)
	)
	(via
		(at 153 50.25)
		(size 0.45)
		(drill 0.1)
		(layers "F.Cu" "B.Cu")
		(net 115)
	)
	(segment
		(start 153.062 52.502001)
		(end 153.062 50.312)
		(width 0.2)
		(layer "B.Cu")
		(net 115)
	)
	(segment
		(start 153.062 50.312)
		(end 153 50.25)
		(width 0.2)
		(layer "B.Cu")
		(net 115)
	)
	(segment
		(start 144 142)
		(end 142.556999 142)
		(width 0.2)
		(layer "F.Cu")
		(net 116)
	)
	(segment
		(start 144.25 142.25)
		(end 144 142)
		(width 0.2)
		(layer "F.Cu")
		(net 116)
	)
	(segment
		(start 142.556999 142)
		(end 141.556999 141)
		(width 0.2)
		(layer "F.Cu")
		(net 116)
	)
	(segment
		(start 142.1 145.453999)
		(end 143.473999 145.453999)
		(width 0.2)
		(layer "F.Cu")
		(net 116)
	)
	(segment
		(start 143.5 145.48)
		(end 144.02 145.48)
		(width 0.2)
		(layer "F.Cu")
		(net 116)
	)
	(segment
		(start 144.02 145.48)
		(end 144.25 145.25)
		(width 0.2)
		(layer "F.Cu")
		(net 116)
	)
	(segment
		(start 144.25 145.25)
		(end 144.25 142.25)
		(width 0.2)
		(layer "F.Cu")
		(net 116)
	)
	(segment
		(start 143.473999 145.453999)
		(end 143.5 145.48)
		(width 0.2)
		(layer "F.Cu")
		(net 116)
	)
	(segment
		(start 154.792 58.434001)
		(end 154.792 53.000999)
		(width 0.3)
		(layer "F.Cu")
		(net 117)
	)
	(segment
		(start 150.726001 59.2)
		(end 152.676001 59.2)
		(width 0.3)
		(layer "F.Cu")
		(net 117)
	)
	(segment
		(start 152.737001 57.856)
		(end 152.737001 59.139)
		(width 0.2)
		(layer "F.Cu")
		(net 117)
	)
	(segment
		(start 148.4 59.25)
		(end 148.35 59.2)
		(width 0.2)
		(layer "F.Cu")
		(net 117)
	)
	(segment
		(start 150.737 57.856)
		(end 150.737 59.189001)
		(width 0.2)
		(layer "F.Cu")
		(net 117)
	)
	(segment
		(start 154.792 51.000999)
		(end 154.792 52.001)
		(width 0.15)
		(layer "F.Cu")
		(net 117)
	)
	(segment
		(start 144.826001 51.55)
		(end 144.826001 58.25)
		(width 0.3)
		(layer "F.Cu")
		(net 117)
	)
	(segment
		(start 147.042 54.001)
		(end 147.042 51.415999)
		(width 0.3)
		(layer "F.Cu")
		(net 117)
	)
	(segment
		(start 147.043 54)
		(end 147.042 54.001)
		(width 0.3)
		(layer "F.Cu")
		(net 117)
	)
	(segment
		(start 146.737 57.856)
		(end 146.737 59.139001)
		(width 0.2)
		(layer "F.Cu")
		(net 117)
	)
	(segment
		(start 147.042 51.415999)
		(end 146.676001 51.05)
		(width 0.3)
		(layer "F.Cu")
		(net 117)
	)
	(segment
		(start 154.026001 59.2)
		(end 154.792 58.434001)
		(width 0.3)
		(layer "F.Cu")
		(net 117)
	)
	(segment
		(start 146.676001 59.2)
		(end 148.35 59.2)
		(width 0.3)
		(layer "F.Cu")
		(net 117)
	)
	(segment
		(start 150.737 59.189001)
		(end 150.726001 59.2)
		(width 0.2)
		(layer "F.Cu")
		(net 117)
	)
	(segment
		(start 148.312001 54)
		(end 147.043 54)
		(width 0.3)
		(layer "F.Cu")
		(net 117)
	)
	(segment
		(start 139.5 66.7)
		(end 147.25 66.7)
		(width 0.2)
		(layer "F.Cu")
		(net 117)
	)
	(segment
		(start 136.75 67.57)
		(end 136.75 66.85)
		(width 0.2)
		(layer "F.Cu")
		(net 117)
	)
	(segment
		(start 145.326001 51.05)
		(end 144.826001 51.55)
		(width 0.3)
		(layer "F.Cu")
		(net 117)
	)
	(segment
		(start 145.229001 58.652999)
		(end 145.776001 59.2)
		(width 0.3)
		(layer "F.Cu")
		(net 117)
	)
	(segment
		(start 146.676001 51.05)
		(end 145.326001 51.05)
		(width 0.3)
		(layer "F.Cu")
		(net 117)
	)
	(segment
		(start 145.776001 59.2)
		(end 146.676001 59.2)
		(width 0.3)
		(layer "F.Cu")
		(net 117)
	)
	(segment
		(start 148.736999 59.139002)
		(end 148.676001 59.2)
		(width 0.2)
		(layer "F.Cu")
		(net 117)
	)
	(segment
		(start 148.676001 59.2)
		(end 150.726001 59.2)
		(width 0.3)
		(layer "F.Cu")
		(net 117)
	)
	(segment
		(start 154.792 51.001)
		(end 154.792 53.000999)
		(width 0.3)
		(layer "F.Cu")
		(net 117)
	)
	(segment
		(start 144.826001 58.25)
		(end 145.229001 58.652999)
		(width 0.3)
		(layer "F.Cu")
		(net 117)
	)
	(segment
		(start 148.736999 57.856001)
		(end 148.736999 59.139002)
		(width 0.2)
		(layer "F.Cu")
		(net 117)
	)
	(segment
		(start 148.35 59.2)
		(end 148.676001 59.2)
		(width 0.3)
		(layer "F.Cu")
		(net 117)
	)
	(segment
		(start 152.676001 59.2)
		(end 154.026001 59.2)
		(width 0.3)
		(layer "F.Cu")
		(net 117)
	)
	(segment
		(start 148.4 65.55)
		(end 148.4 59.25)
		(width 0.2)
		(layer "F.Cu")
		(net 117)
	)
	(segment
		(start 154.792 53.001)
		(end 154.792 52.001)
		(width 0.15)
		(layer "F.Cu")
		(net 117)
	)
	(segment
		(start 147.25 66.7)
		(end 148.4 65.55)
		(width 0.2)
		(layer "F.Cu")
		(net 117)
	)
	(segment
		(start 146.737 59.139001)
		(end 146.676001 59.2)
		(width 0.2)
		(layer "F.Cu")
		(net 117)
	)
	(segment
		(start 152.737001 59.139)
		(end 152.676001 59.2)
		(width 0.2)
		(layer "F.Cu")
		(net 117)
	)
	(via
		(at 136.75 66.85)
		(size 0.45)
		(drill 0.1)
		(layers "F.Cu" "B.Cu")
		(net 117)
	)
	(via
		(at 139.5 66.7)
		(size 0.45)
		(drill 0.1)
		(layers "F.Cu" "B.Cu")
		(net 117)
	)
	(segment
		(start 137.6 66)
		(end 138.8 66)
		(width 0.2)
		(layer "B.Cu")
		(net 117)
	)
	(segment
		(start 136.75 66.85)
		(end 137.6 66)
		(width 0.2)
		(layer "B.Cu")
		(net 117)
	)
	(segment
		(start 138.8 66)
		(end 139.5 66.7)
		(width 0.2)
		(layer "B.Cu")
		(net 117)
	)
	(segment
		(start 144.25 117.652999)
		(end 144 117.402999)
		(width 0.2)
		(layer "F.Cu")
		(net 118)
	)
	(segment
		(start 144 117.402999)
		(end 142.556999 117.402999)
		(width 0.2)
		(layer "F.Cu")
		(net 118)
	)
	(segment
		(start 142.1 120.856998)
		(end 143.473999 120.856998)
		(width 0.2)
		(layer "F.Cu")
		(net 118)
	)
	(segment
		(start 144.02 120.882999)
		(end 144.25 120.652999)
		(width 0.2)
		(layer "F.Cu")
		(net 118)
	)
	(segment
		(start 143.5 120.882999)
		(end 144.02 120.882999)
		(width 0.2)
		(layer "F.Cu")
		(net 118)
	)
	(segment
		(start 144.25 120.652999)
		(end 144.25 117.652999)
		(width 0.2)
		(layer "F.Cu")
		(net 118)
	)
	(segment
		(start 143.473999 120.856998)
		(end 143.5 120.882999)
		(width 0.2)
		(layer "F.Cu")
		(net 118)
	)
	(segment
		(start 132.25 103.443001)
		(end 134.156999 103.443001)
		(width 0.2)
		(layer "F.Cu")
		(net 119)
	)
	(segment
		(start 134.75 105.15)
		(end 135 105.4)
		(width 0.2)
		(layer "F.Cu")
		(net 119)
	)
	(segment
		(start 137 105.4)
		(end 137.399998 105.799998)
		(width 0.2)
		(layer "F.Cu")
		(net 119)
	)
	(segment
		(start 134.156999 103.443001)
		(end 134.75 104.036002)
		(width 0.2)
		(layer "F.Cu")
		(net 119)
	)
	(segment
		(start 135 105.4)
		(end 137 105.4)
		(width 0.2)
		(layer "F.Cu")
		(net 119)
	)
	(segment
		(start 134.75 104.036002)
		(end 134.75 105.15)
		(width 0.2)
		(layer "F.Cu")
		(net 119)
	)
	(segment
		(start 137.353999 107.7)
		(end 137.353999 106.395999)
		(width 0.2)
		(layer "F.Cu")
		(net 119)
	)
	(segment
		(start 137.353999 106.395999)
		(end 137.399998 106.35)
		(width 0.2)
		(layer "F.Cu")
		(net 119)
	)
	(segment
		(start 137.399998 105.799998)
		(end 137.399998 106.35)
		(width 0.2)
		(layer "F.Cu")
		(net 119)
	)
	(segment
		(start 141.751 88.221)
		(end 141.751 89.225)
		(width 0.2)
		(layer "F.Cu")
		(net 120)
	)
	(segment
		(start 142.251 88.179001)
		(end 142.251 89.225)
		(width 0.2)
		(layer "F.Cu")
		(net 120)
	)
	(segment
		(start 142.022 87.950001)
		(end 141.751 88.221)
		(width 0.2)
		(layer "F.Cu")
		(net 120)
	)
	(segment
		(start 142.022 87.950001)
		(end 142.251 88.179001)
		(width 0.2)
		(layer "F.Cu")
		(net 120)
	)
	(segment
		(start 148.632 91)
		(end 148.631998 90.96)
		(width 0.15)
		(layer "F.Cu")
		(net 121)
	)
	(segment
		(start 147.671998 90)
		(end 147.172 90.500002)
		(width 0.2)
		(layer "F.Cu")
		(net 121)
	)
	(segment
		(start 149.951998 90.65)
		(end 149.952001 88.4)
		(width 0.15)
		(layer "F.Cu")
		(net 121)
	)
	(segment
		(start 148.632 91)
		(end 149.602001 91)
		(width 0.15)
		(layer "F.Cu")
		(net 121)
	)
	(segment
		(start 149.602001 91)
		(end 149.951998 90.65)
		(width 0.15)
		(layer "F.Cu")
		(net 121)
	)
	(segment
		(start 147.172 90.500002)
		(end 146.025 90.499999)
		(width 0.2)
		(layer "F.Cu")
		(net 121)
	)
	(segment
		(start 149.551999 88)
		(end 148.632 88.000001)
		(width 0.15)
		(layer "F.Cu")
		(net 121)
	)
	(segment
		(start 149.952001 88.4)
		(end 149.551999 88)
		(width 0.15)
		(layer "F.Cu")
		(net 121)
	)
	(segment
		(start 148.631998 90.96)
		(end 147.671998 90)
		(width 0.15)
		(layer "F.Cu")
		(net 121)
	)
	(segment
		(start 143.253 88.221001)
		(end 143.253 89.225)
		(width 0.2)
		(layer "F.Cu")
		(net 122)
	)
	(segment
		(start 142.982 87.95)
		(end 143.253 88.221001)
		(width 0.2)
		(layer "F.Cu")
		(net 122)
	)
	(segment
		(start 143.749998 95.322)
		(end 143.749998 94.273)
		(width 0.2)
		(layer "F.Cu")
		(net 123)
	)
	(segment
		(start 143.521999 95.549999)
		(end 143.749998 95.322)
		(width 0.2)
		(layer "F.Cu")
		(net 123)
	)
	(segment
		(start 149 68.25)
		(end 143.85 73.4)
		(width 0.125)
		(layer "F.Cu")
		(net 124)
	)
	(segment
		(start 135.400499 71.4)
		(end 135.7995 71.799001)
		(width 0.15)
		(layer "F.Cu")
		(net 124)
	)
	(segment
		(start 152.187001 53.5)
		(end 152.876001 53.5)
		(width 0.125)
		(layer "F.Cu")
		(net 124)
	)
	(segment
		(start 135.400499 71.4)
		(end 132.449 71.4)
		(width 0.15)
		(layer "F.Cu")
		(net 124)
	)
	(segment
		(start 135.7995 72.5995)
		(end 135.7995 72.45)
		(width 0.125)
		(layer "F.Cu")
		(net 124)
	)
	(segment
		(start 132.449 71.4)
		(end 132.449 72.45)
		(width 0.15)
		(layer "F.Cu")
		(net 124)
	)
	(segment
		(start 136.6 73.4)
		(end 135.7995 72.5995)
		(width 0.125)
		(layer "F.Cu")
		(net 124)
	)
	(segment
		(start 135.7995 72.45)
		(end 135.7995 71.799001)
		(width 0.15)
		(layer "F.Cu")
		(net 124)
	)
	(segment
		(start 133.4205 68.530001)
		(end 132.448999 69.501501)
		(width 0.15)
		(layer "F.Cu")
		(net 124)
	)
	(segment
		(start 132.448999 69.501501)
		(end 132.449 71.4)
		(width 0.15)
		(layer "F.Cu")
		(net 124)
	)
	(segment
		(start 143.85 73.4)
		(end 136.6 73.4)
		(width 0.125)
		(layer "F.Cu")
		(net 124)
	)
	(segment
		(start 149 64.75)
		(end 149 68.25)
		(width 0.125)
		(layer "F.Cu")
		(net 124)
	)
	(segment
		(start 134.650999 68.53)
		(end 133.4205 68.530001)
		(width 0.15)
		(layer "F.Cu")
		(net 124)
	)
	(segment
		(start 152.9 60.2)
		(end 152.9 60.85)
		(width 0.125)
		(layer "F.Cu")
		(net 124)
	)
	(segment
		(start 152.876001 53.5)
		(end 152.926001 53.55)
		(width 0.125)
		(layer "F.Cu")
		(net 124)
	)
	(segment
		(start 152.9 60.85)
		(end 149 64.75)
		(width 0.125)
		(layer "F.Cu")
		(net 124)
	)
	(via
		(at 152.926001 53.55)
		(size 0.45)
		(drill 0.1)
		(layers "F.Cu" "B.Cu")
		(net 124)
	)
	(via
		(at 152.9 60.2)
		(size 0.55)
		(drill 0.15)
		(layers "F.Cu" "B.Cu")
		(net 124)
	)
	(segment
		(start 152.9 60.2)
		(end 152.9 53.576001)
		(width 0.125)
		(layer "B.Cu")
		(net 124)
	)
	(segment
		(start 152.9 53.576001)
		(end 152.926001 53.55)
		(width 0.125)
		(layer "B.Cu")
		(net 124)
	)
	(segment
		(start 145.249999 95.698)
		(end 146.552 97.000001)
		(width 0.15)
		(layer "F.Cu")
		(net 125)
	)
	(segment
		(start 146.552 97.000001)
		(end 147.671999 97)
		(width 0.15)
		(layer "F.Cu")
		(net 125)
	)
	(segment
		(start 145.250001 94.273)
		(end 145.249999 95.698)
		(width 0.15)
		(layer "F.Cu")
		(net 125)
	)
	(segment
		(start 148.637 56.076)
		(end 147.862 56.076001)
		(width 0.15)
		(layer "F.Cu")
		(net 133)
	)
	(segment
		(start 149 55.713)
		(end 148.637 56.076)
		(width 0.15)
		(layer "F.Cu")
		(net 133)
	)
	(segment
		(start 147.737 56.896001)
		(end 146.737 56.896)
		(width 0.15)
		(layer "F.Cu")
		(net 133)
	)
	(segment
		(start 149 55.188)
		(end 149 55.713)
		(width 0.15)
		(layer "F.Cu")
		(net 133)
	)
	(segment
		(start 147.862 56.076001)
		(end 147.737001 56.201)
		(width 0.15)
		(layer "F.Cu")
		(net 133)
	)
	(segment
		(start 147.737001 56.201)
		(end 147.737 56.896001)
		(width 0.15)
		(layer "F.Cu")
		(net 133)
	)
	(segment
		(start 138.438 62.238)
		(end 138.2 62)
		(width 0.125)
		(layer "F.Cu")
		(net 134)
	)
	(segment
		(start 114.774 114.1)
		(end 113.3 114.1)
		(width 0.5)
		(layer "F.Cu")
		(net 134)
	)
	(segment
		(start 107.574 113.1)
		(end 109 113.1)
		(width 0.5)
		(layer "F.Cu")
		(net 134)
	)
	(segment
		(start 138.2 62)
		(end 138.2 61)
		(width 0.125)
		(layer "F.Cu")
		(net 134)
	)
	(segment
		(start 140.8 60.22)
		(end 140.58 60)
		(width 0.2)
		(layer "F.Cu")
		(net 134)
	)
	(segment
		(start 126.079999 148.069999)
		(end 126.079999 147.677999)
		(width 0.3)
		(layer "F.Cu")
		(net 134)
	)
	(segment
		(start 107.574 113.1)
		(end 106.1 113.1)
		(width 0.5)
		(layer "F.Cu")
		(net 134)
	)
	(segment
		(start 106.1 112.4)
		(end 106.1 112.1)
		(width 0.5)
		(layer "F.Cu")
		(net 134)
	)
	(segment
		(start 151.15 152.4)
		(end 153.4 154.65)
		(width 0.2)
		(layer "F.Cu")
		(net 134)
	)
	(segment
		(start 118.700001 114.2)
		(end 118.700001 112.120001)
		(width 0.5)
		(layer "F.Cu")
		(net 134)
	)
	(segment
		(start 140.3 60.28)
		(end 140.3 60.6)
		(width 0.2)
		(layer "F.Cu")
		(net 134)
	)
	(segment
		(start 142.199999 59.400001)
		(end 143.229999 59.400001)
		(width 0.2)
		(layer "F.Cu")
		(net 134)
	)
	(segment
		(start 106.1 112.4)
		(end 104.2 112.4)
		(width 0.5)
		(layer "F.Cu")
		(net 134)
	)
	(segment
		(start 140.8 61.35)
		(end 140.8 60.22)
		(width 0.2)
		(layer "F.Cu")
		(net 134)
	)
	(segment
		(start 114.774 114.1)
		(end 118.600001 114.1)
		(width 0.5)
		(layer "F.Cu")
		(net 134)
	)
	(segment
		(start 106.1 113.1)
		(end 106.1 112.5)
		(width 0.5)
		(layer "F.Cu")
		(net 134)
	)
	(segment
		(start 106.1 112.5)
		(end 106.1 112.4)
		(width 0.5)
		(layer "F.Cu")
		(net 134)
	)
	(segment
		(start 152.2 159.71)
		(end 152.2 157.17)
		(width 0.2)
		(layer "F.Cu")
		(net 134)
	)
	(segment
		(start 151.15 152.4)
		(end 153.55 150)
		(width 0.2)
		(layer "F.Cu")
		(net 134)
	)
	(segment
		(start 139 62.238)
		(end 138.438 62.238)
		(width 0.125)
		(layer "F.Cu")
		(net 134)
	)
	(segment
		(start 138.2 61)
		(end 138.6 60.6)
		(width 0.125)
		(layer "F.Cu")
		(net 134)
	)
	(segment
		(start 153.4 156.85)
		(end 153.08 157.17)
		(width 0.2)
		(layer "F.Cu")
		(net 134)
	)
	(segment
		(start 109 113.1)
		(end 109 112.1)
		(width 0.5)
		(layer "F.Cu")
		(net 134)
	)
	(segment
		(start 124.882998 148.574999)
		(end 125.574999 148.574999)
		(width 0.3)
		(layer "F.Cu")
		(net 134)
	)
	(segment
		(start 117.5 137.9)
		(end 117.5 135.5)
		(width 0.3)
		(layer "F.Cu")
		(net 134)
	)
	(segment
		(start 140.3 60.6)
		(end 140.3 61.35)
		(width 0.2)
		(layer "F.Cu")
		(net 134)
	)
	(segment
		(start 153.4 154.65)
		(end 153.4 156.85)
		(width 0.2)
		(layer "F.Cu")
		(net 134)
	)
	(segment
		(start 106.1 112.1)
		(end 107.574 112.1)
		(width 0.5)
		(layer "F.Cu")
		(net 134)
	)
	(segment
		(start 153.08 157.17)
		(end 152.2 157.17)
		(width 0.2)
		(layer "F.Cu")
		(net 134)
	)
	(segment
		(start 104.2 112.4)
		(end 103.8 112.8)
		(width 0.5)
		(layer "F.Cu")
		(net 134)
	)
	(segment
		(start 124.882999 148.574999)
		(end 123.825001 148.574999)
		(width 0.3)
		(layer "F.Cu")
		(net 134)
	)
	(segment
		(start 138.6 60.6)
		(end 140.3 60.6)
		(width 0.125)
		(layer "F.Cu")
		(net 134)
	)
	(segment
		(start 141.6 60)
		(end 142.199999 59.400001)
		(width 0.2)
		(layer "F.Cu")
		(net 134)
	)
	(segment
		(start 125.574999 148.574999)
		(end 126.079999 148.069999)
		(width 0.3)
		(layer "F.Cu")
		(net 134)
	)
	(segment
		(start 140.58 60)
		(end 141.6 60)
		(width 0.2)
		(layer "F.Cu")
		(net 134)
	)
	(segment
		(start 103.8 114.100001)
		(end 103.8 112.8)
		(width 0.5)
		(layer "F.Cu")
		(net 134)
	)
	(segment
		(start 123.825001 148.574999)
		(end 123.8 148.6)
		(width 0.3)
		(layer "F.Cu")
		(net 134)
	)
	(segment
		(start 118.600001 114.1)
		(end 118.700001 114.2)
		(width 0.5)
		(layer "F.Cu")
		(net 134)
	)
	(segment
		(start 109 112.1)
		(end 107.574 112.1)
		(width 0.5)
		(layer "F.Cu")
		(net 134)
	)
	(segment
		(start 140.58 60)
		(end 140.3 60.28)
		(width 0.2)
		(layer "F.Cu")
		(net 134)
	)
	(segment
		(start 153.55 150)
		(end 155.75 150)
		(width 0.2)
		(layer "F.Cu")
		(net 134)
	)
	(segment
		(start 118.700001 112.120001)
		(end 118.68 112.1)
		(width 0.5)
		(layer "F.Cu")
		(net 134)
	)
	(via
		(at 105.5 110)
		(size 0.55)
		(drill 0.15)
		(layers "F.Cu" "B.Cu")
		(free yes)
		(net 134)
	)
	(via
		(at 115 136)
		(size 0.55)
		(drill 0.15)
		(layers "F.Cu" "B.Cu")
		(free yes)
		(net 134)
	)
	(via
		(at 104.5 112)
		(size 0.55)
		(drill 0.15)
		(layers "F.Cu" "B.Cu")
		(free yes)
		(net 134)
	)
	(via
		(at 114 138)
		(size 0.55)
		(drill 0.15)
		(layers "F.Cu" "B.Cu")
		(free yes)
		(net 134)
	)
	(via
		(at 113 136)
		(size 0.55)
		(drill 0.15)
		(layers "F.Cu" "B.Cu")
		(free yes)
		(net 134)
	)
	(via
		(at 104.5 111)
		(size 0.55)
		(drill 0.15)
		(layers "F.Cu" "B.Cu")
		(free yes)
		(net 134)
	)
	(via
		(at 117.5 135.5)
		(size 0.45)
		(drill 0.1)
		(layers "F.Cu" "B.Cu")
		(net 134)
	)
	(via
		(at 113 137)
		(size 0.55)
		(drill 0.15)
		(layers "F.Cu" "B.Cu")
		(free yes)
		(net 134)
	)
	(via
		(at 105.5 109)
		(size 0.55)
		(drill 0.15)
		(layers "F.Cu" "B.Cu")
		(free yes)
		(net 134)
	)
	(via
		(at 103.5 109)
		(size 0.55)
		(drill 0.15)
		(layers "F.Cu" "B.Cu")
		(free yes)
		(net 134)
	)
	(via
		(at 113.999999 137)
		(size 0.55)
		(drill 0.15)
		(layers "F.Cu" "B.Cu")
		(free yes)
		(net 134)
	)
	(via
		(at 104.5 110)
		(size 0.55)
		(drill 0.15)
		(layers "F.Cu" "B.Cu")
		(free yes)
		(net 134)
	)
	(via
		(at 115 137)
		(size 0.55)
		(drill 0.15)
		(layers "F.Cu" "B.Cu")
		(free yes)
		(net 134)
	)
	(via
		(at 104.5 109)
		(size 0.55)
		(drill 0.15)
		(layers "F.Cu" "B.Cu")
		(free yes)
		(net 134)
	)
	(via
		(at 103.5 112)
		(size 0.55)
		(drill 0.15)
		(layers "F.Cu" "B.Cu")
		(free yes)
		(net 134)
	)
	(via
		(at 116 137)
		(size 0.55)
		(drill 0.15)
		(layers "F.Cu" "B.Cu")
		(free yes)
		(net 134)
	)
	(via
		(at 116 136)
		(size 0.55)
		(drill 0.15)
		(layers "F.Cu" "B.Cu")
		(free yes)
		(net 134)
	)
	(via
		(at 151.15 152.4)
		(size 0.45)
		(drill 0.1)
		(layers "F.Cu" "B.Cu")
		(net 134)
	)
	(via
		(at 123.8 148.6)
		(size 0.45)
		(drill 0.1)
		(layers "F.Cu" "B.Cu")
		(net 134)
	)
	(via
		(at 103.5 111)
		(size 0.55)
		(drill 0.15)
		(layers "F.Cu" "B.Cu")
		(free yes)
		(net 134)
	)
	(via
		(at 113 138)
		(size 0.55)
		(drill 0.15)
		(layers "F.Cu" "B.Cu")
		(free yes)
		(net 134)
	)
	(via
		(at 116 138)
		(size 0.55)
		(drill 0.15)
		(layers "F.Cu" "B.Cu")
		(free yes)
		(net 134)
	)
	(via
		(at 103.5 110)
		(size 0.55)
		(drill 0.15)
		(layers "F.Cu" "B.Cu")
		(free yes)
		(net 134)
	)
	(via
		(at 115 138)
		(size 0.55)
		(drill 0.15)
		(layers "F.Cu" "B.Cu")
		(free yes)
		(net 134)
	)
	(via
		(at 143.229999 59.400001)
		(size 0.55)
		(drill 0.15)
		(layers "F.Cu" "B.Cu")
		(net 134)
	)
	(via
		(at 114 136)
		(size 0.55)
		(drill 0.15)
		(layers "F.Cu" "B.Cu")
		(free yes)
		(net 134)
	)
	(segment
		(start 123.8 148.55)
		(end 120.6 145.35)
		(width 0.3)
		(layer "B.Cu")
		(net 134)
	)
	(segment
		(start 129.2 118.3)
		(end 129.2 83.8)
		(width 0.3)
		(layer "B.Cu")
		(net 134)
	)
	(segment
		(start 121 120.5)
		(end 127 120.5)
		(width 0.3)
		(layer "B.Cu")
		(net 134)
	)
	(segment
		(start 124.2 152.4)
		(end 123.8 152)
		(width 0.2)
		(layer "B.Cu")
		(net 134)
	)
	(segment
		(start 145 66.6)
		(end 143.229999 64.829999)
		(width 0.3)
		(layer "B.Cu")
		(net 134)
	)
	(segment
		(start 143.2 75.4)
		(end 145 73.6)
		(width 0.3)
		(layer "B.Cu")
		(net 134)
	)
	(segment
		(start 117.5 135.5)
		(end 117.5 124)
		(width 0.3)
		(layer "B.Cu")
		(net 134)
	)
	(segment
		(start 145 73.6)
		(end 145 66.6)
		(width 0.3)
		(layer "B.Cu")
		(net 134)
	)
	(segment
		(start 120.6 145.35)
		(end 120.6 140.6)
		(width 0.3)
		(layer "B.Cu")
		(net 134)
	)
	(segment
		(start 151.15 152.4)
		(end 124.2 152.4)
		(width 0.2)
		(layer "B.Cu")
		(net 134)
	)
	(segment
		(start 143.229999 64.829999)
		(end 143.229999 59.400001)
		(width 0.3)
		(layer "B.Cu")
		(net 134)
	)
	(segment
		(start 120.6 140.6)
		(end 117.5 137.5)
		(width 0.3)
		(layer "B.Cu")
		(net 134)
	)
	(segment
		(start 129.2 83.8)
		(end 137.6 75.4)
		(width 0.3)
		(layer "B.Cu")
		(net 134)
	)
	(segment
		(start 117.5 137.5)
		(end 117.5 135.5)
		(width 0.3)
		(layer "B.Cu")
		(net 134)
	)
	(segment
		(start 127 120.5)
		(end 129.2 118.3)
		(width 0.3)
		(layer "B.Cu")
		(net 134)
	)
	(segment
		(start 137.6 75.4)
		(end 143.2 75.4)
		(width 0.3)
		(layer "B.Cu")
		(net 134)
	)
	(segment
		(start 123.8 148.6)
		(end 123.8 148.55)
		(width 0.3)
		(layer "B.Cu")
		(net 134)
	)
	(segment
		(start 117.5 124)
		(end 121 120.5)
		(width 0.3)
		(layer "B.Cu")
		(net 134)
	)
	(segment
		(start 123.8 152)
		(end 123.8 148.6)
		(width 0.2)
		(layer "B.Cu")
		(net 134)
	)
	(segment
		(start 152.687998 53.002)
		(end 152.762 53.076)
		(width 0.15)
		(layer "F.Cu")
		(net 135)
	)
	(segment
		(start 153.757 53.075999)
		(end 153.832 53.000999)
		(width 0.15)
		(layer "F.Cu")
		(net 135)
	)
	(segment
		(start 152.762 53.076)
		(end 153.757 53.075999)
		(width 0.15)
		(layer "F.Cu")
		(net 135)
	)
	(segment
		(start 152.187 53.002)
		(end 152.687998 53.002)
		(width 0.15)
		(layer "F.Cu")
		(net 135)
	)
	(segment
		(start 149.499999 55.738)
		(end 149.5 55.187999)
		(width 0.15)
		(layer "F.Cu")
		(net 136)
	)
	(segment
		(start 148.736999 56.501)
		(end 149.499999 55.738)
		(width 0.15)
		(layer "F.Cu")
		(net 136)
	)
	(segment
		(start 149.737 56.896)
		(end 148.737 56.896001)
		(width 0.15)
		(layer "F.Cu")
		(net 136)
	)
	(segment
		(start 148.737 56.896001)
		(end 148.736999 56.501)
		(width 0.15)
		(layer "F.Cu")
		(net 136)
	)
	(segment
		(start 151.712 56.051001)
		(end 152.587001 56.050999)
		(width 0.15)
		(layer "F.Cu")
		(net 137)
	)
	(segment
		(start 153.736999 56.896)
		(end 152.737 56.896001)
		(width 0.15)
		(layer "F.Cu")
		(net 137)
	)
	(segment
		(start 151.499 55.837999)
		(end 151.712 56.051001)
		(width 0.15)
		(layer "F.Cu")
		(net 137)
	)
	(segment
		(start 151.499 55.188)
		(end 151.499 55.837999)
		(width 0.15)
		(layer "F.Cu")
		(net 137)
	)
	(segment
		(start 152.736999 56.200999)
		(end 152.737 56.896001)
		(width 0.15)
		(layer "F.Cu")
		(net 137)
	)
	(segment
		(start 152.587001 56.050999)
		(end 152.736999 56.200999)
		(width 0.15)
		(layer "F.Cu")
		(net 137)
	)
	(segment
		(start 150.737 56.101)
		(end 150.737 56.896)
		(width 0.15)
		(layer "F.Cu")
		(net 138)
	)
	(segment
		(start 150.998 55.84)
		(end 150.737 56.101)
		(width 0.15)
		(layer "F.Cu")
		(net 138)
	)
	(segment
		(start 151.737 56.896)
		(end 150.737 56.896)
		(width 0.15)
		(layer "F.Cu")
		(net 138)
	)
	(segment
		(start 150.997998 55.188)
		(end 150.998 55.84)
		(width 0.15)
		(layer "F.Cu")
		(net 138)
	)
	(segment
		(start 143.301 39.9)
		(end 143.35 39.949)
		(width 0.125)
		(layer "F.Cu")
		(net 139)
	)
	(segment
		(start 142.8 39.9)
		(end 143.301 39.9)
		(width 0.125)
		(layer "F.Cu")
		(net 139)
	)
	(segment
		(start 143.35 40.55)
		(end 143.4 40.6)
		(width 0.125)
		(layer "F.Cu")
		(net 139)
	)
	(segment
		(start 150.998001 50.483999)
		(end 151.032 50.45)
		(width 0.125)
		(layer "F.Cu")
		(net 139)
	)
	(segment
		(start 142.451 39.551)
		(end 142.8 39.9)
		(width 0.125)
		(layer "F.Cu")
		(net 139)
	)
	(segment
		(start 143.35 39.949)
		(end 143.35 40.55)
		(width 0.125)
		(layer "F.Cu")
		(net 139)
	)
	(segment
		(start 150.998001 51.313)
		(end 150.998001 50.483999)
		(width 0.125)
		(layer "F.Cu")
		(net 139)
	)
	(segment
		(start 142.451 38.5)
		(end 142.451 39.551)
		(width 0.125)
		(layer "F.Cu")
		(net 139)
	)
	(via
		(at 143.4 40.6)
		(size 0.45)
		(drill 0.1)
		(layers "F.Cu" "B.Cu")
		(net 139)
	)
	(via
		(at 151.032 50.45)
		(size 0.45)
		(drill 0.1)
		(layers "F.Cu" "B.Cu")
		(net 139)
	)
	(segment
		(start 151.4 50.082)
		(end 151.4 44.6)
		(width 0.125)
		(layer "B.Cu")
		(net 139)
	)
	(segment
		(start 149 42.2)
		(end 143.8 42.2)
		(width 0.125)
		(layer "B.Cu")
		(net 139)
	)
	(segment
		(start 143.4 41.8)
		(end 143.4 40.6)
		(width 0.125)
		(layer "B.Cu")
		(net 139)
	)
	(segment
		(start 151.4 44.6)
		(end 149 42.2)
		(width 0.125)
		(layer "B.Cu")
		(net 139)
	)
	(segment
		(start 143.8 42.2)
		(end 143.4 41.8)
		(width 0.125)
		(layer "B.Cu")
		(net 139)
	)
	(segment
		(start 151.032 50.45)
		(end 151.4 50.082)
		(width 0.125)
		(layer "B.Cu")
		(net 139)
	)
	(segment
		(start 144.65 40.55)
		(end 144.6 40.6)
		(width 0.125)
		(layer "F.Cu")
		(net 140)
	)
	(segment
		(start 144.65 39.949)
		(end 145.251 39.949)
		(width 0.125)
		(layer "F.Cu")
		(net 140)
	)
	(segment
		(start 150.498001 50.516001)
		(end 150.432 50.45)
		(width 0.125)
		(layer "F.Cu")
		(net 140)
	)
	(segment
		(start 145.5 39.7)
		(end 145.5 38.55)
		(width 0.125)
		(layer "F.Cu")
		(net 140)
	)
	(segment
		(start 144.65 39.949)
		(end 144.65 40.55)
		(width 0.125)
		(layer "F.Cu")
		(net 140)
	)
	(segment
		(start 150.498001 51.313)
		(end 150.498001 50.516001)
		(width 0.125)
		(layer "F.Cu")
		(net 140)
	)
	(segment
		(start 145.251 39.949)
		(end 145.5 39.7)
		(width 0.125)
		(layer "F.Cu")
		(net 140)
	)
	(segment
		(start 145.5 38.55)
		(end 145.45 38.5)
		(width 0.125)
		(layer "F.Cu")
		(net 140)
	)
	(via
		(at 144.6 40.6)
		(size 0.45)
		(drill 0.1)
		(layers "F.Cu" "B.Cu")
		(net 140)
	)
	(via
		(at 150.432 50.45)
		(size 0.45)
		(drill 0.1)
		(layers "F.Cu" "B.Cu")
		(net 140)
	)
	(segment
		(start 142.8 42.2)
		(end 144.1 43.5)
		(width 0.125)
		(layer "B.Cu")
		(net 140)
	)
	(segment
		(start 150.382 50.5)
		(end 150.432 50.45)
		(width 0.125)
		(layer "B.Cu")
		(net 140)
	)
	(segment
		(start 144.6 40.6)
		(end 144.4 40.6)
		(width 0.125)
		(layer "B.Cu")
		(net 140)
	)
	(segment
		(start 143.8 40)
		(end 143.2 40)
		(width 0.125)
		(layer "B.Cu")
		(net 140)
	)
	(segment
		(start 143.2 40)
		(end 142.8 40.4)
		(width 0.125)
		(layer "B.Cu")
		(net 140)
	)
	(segment
		(start 145.5 50.5)
		(end 150.382 50.5)
		(width 0.125)
		(layer "B.Cu")
		(net 140)
	)
	(segment
		(start 144.1 49.1)
		(end 145.5 50.5)
		(width 0.125)
		(layer "B.Cu")
		(net 140)
	)
	(segment
		(start 144.1 43.5)
		(end 144.1 49.1)
		(width 0.125)
		(layer "B.Cu")
		(net 140)
	)
	(segment
		(start 142.8 40.4)
		(end 142.8 42.2)
		(width 0.125)
		(layer "B.Cu")
		(net 140)
	)
	(segment
		(start 144.4 40.6)
		(end 143.8 40)
		(width 0.125)
		(layer "B.Cu")
		(net 140)
	)
	(segment
		(start 153.557 51.726)
		(end 152.912 51.726)
		(width 0.15)
		(layer "F.Cu")
		(net 141)
	)
	(segment
		(start 152.637 52.001)
		(end 152.187 52.001001)
		(width 0.15)
		(layer "F.Cu")
		(net 141)
	)
	(segment
		(start 152.912 51.726)
		(end 152.637 52.001)
		(width 0.15)
		(layer "F.Cu")
		(net 141)
	)
	(segment
		(start 153.832 52.001)
		(end 153.557 51.726)
		(width 0.15)
		(layer "F.Cu")
		(net 141)
	)
	(segment
		(start 151.499 51.312999)
		(end 151.498999 50.839001)
		(width 0.15)
		(layer "F.Cu")
		(net 142)
	)
	(segment
		(start 151.498999 50.839001)
		(end 151.562 50.776001)
		(width 0.15)
		(layer "F.Cu")
		(net 142)
	)
	(segment
		(start 152.612 50.776)
		(end 152.837001 51.001)
		(width 0.15)
		(layer "F.Cu")
		(net 142)
	)
	(segment
		(start 151.562 50.776001)
		(end 152.612 50.776)
		(width 0.15)
		(layer "F.Cu")
		(net 142)
	)
	(segment
		(start 152.837001 51.001)
		(end 153.832 51.001)
		(width 0.15)
		(layer "F.Cu")
		(net 142)
	)
	(segment
		(start 152.976001 54.65)
		(end 152.976001 55.45)
		(width 0.125)
		(layer "F.Cu")
		(net 144)
	)
	(segment
		(start 152.826001 54.5)
		(end 152.976001 54.65)
		(width 0.125)
		(layer "F.Cu")
		(net 144)
	)
	(segment
		(start 153.252001 55.726)
		(end 153.912 55.726)
		(width 0.125)
		(layer "F.Cu")
		(net 144)
	)
	(segment
		(start 152.976001 55.45)
		(end 153.252001 55.726)
		(width 0.125)
		(layer "F.Cu")
		(net 144)
	)
	(segment
		(start 152.187001 54.5)
		(end 152.826001 54.5)
		(width 0.125)
		(layer "F.Cu")
		(net 144)
	)
	(segment
		(start 152.187001 54)
		(end 153.436001 54)
		(width 0.125)
		(layer "F.Cu")
		(net 145)
	)
	(segment
		(start 153.436001 54)
		(end 153.912001 54.476)
		(width 0.125)
		(layer "F.Cu")
		(net 145)
	)
	(segment
		(start 136.403 110.797)
		(end 136.403 110.014)
		(width 0.2)
		(layer "F.Cu")
		(net 151)
	)
	(segment
		(start 133.238 106.238)
		(end 134.4 107.4)
		(width 0.2)
		(layer "F.Cu")
		(net 151)
	)
	(segment
		(start 134.4 107.4)
		(end 134.4 110.6)
		(width 0.2)
		(layer "F.Cu")
		(net 151)
	)
	(segment
		(start 134.4 110.6)
		(end 135 111.2)
		(width 0.2)
		(layer "F.Cu")
		(net 151)
	)
	(segment
		(start 136 111.2)
		(end 136.403 110.797)
		(width 0.2)
		(layer "F.Cu")
		(net 151)
	)
	(segment
		(start 135 111.2)
		(end 136 111.2)
		(width 0.2)
		(layer "F.Cu")
		(net 151)
	)
	(segment
		(start 133.238 105.436)
		(end 133.238 106.238)
		(width 0.2)
		(layer "F.Cu")
		(net 151)
	)
	(segment
		(start 147.202 89)
		(end 147.052 89.15)
		(width 0.125)
		(layer "F.Cu")
		(net 153)
	)
	(segment
		(start 147.052 89.799999)
		(end 146.851999 90)
		(width 0.125)
		(layer "F.Cu")
		(net 153)
	)
	(segment
		(start 147.672 89)
		(end 147.202 89)
		(width 0.125)
		(layer "F.Cu")
		(net 153)
	)
	(segment
		(start 146.851999 90)
		(end 146.025 90)
		(width 0.125)
		(layer "F.Cu")
		(net 153)
	)
	(segment
		(start 147.052 89.15)
		(end 147.052 89.799999)
		(width 0.125)
		(layer "F.Cu")
		(net 153)
	)
	(segment
		(start 153.8 48.200001)
		(end 153.900001 48.1)
		(width 0.15)
		(layer "F.Cu")
		(net 154)
	)
	(segment
		(start 153.8 48.8)
		(end 153.8 48.200001)
		(width 0.15)
		(layer "F.Cu")
		(net 154)
	)
	(segment
		(start 149.999998 56.026)
		(end 150.000001 55.188001)
		(width 0.15)
		(layer "F.Cu")
		(net 154)
	)
	(via
		(at 149.999998 56.026)
		(size 0.55)
		(drill 0.15)
		(layers "F.Cu" "B.Cu")
		(net 154)
	)
	(via
		(at 153.8 48.8)
		(size 0.45)
		(drill 0.1)
		(layers "F.Cu" "B.Cu")
		(net 154)
	)
	(segment
		(start 153.8 48.8)
		(end 153.2 48.8)
		(width 0.15)
		(layer "B.Cu")
		(net 154)
	)
	(segment
		(start 151.9 50.1)
		(end 151.9 54.125998)
		(width 0.15)
		(layer "B.Cu")
		(net 154)
	)
	(segment
		(start 153.2 48.8)
		(end 151.9 50.1)
		(width 0.15)
		(layer "B.Cu")
		(net 154)
	)
	(segment
		(start 151.9 54.125998)
		(end 149.999998 56.026)
		(width 0.15)
		(layer "B.Cu")
		(net 154)
	)
	(segment
		(start 147.671999 91)
		(end 147.671999 92)
		(width 0.15)
		(layer "F.Cu")
		(net 155)
	)
	(segment
		(start 147.671999 91)
		(end 146.025 91)
		(width 0.15)
		(layer "F.Cu")
		(net 155)
	)
	(segment
		(start 143.903 87.697)
		(end 144 87.6)
		(width 0.125)
		(layer "F.Cu")
		(net 156)
	)
	(segment
		(start 143.903 89.224998)
		(end 143.903 87.697)
		(width 0.125)
		(layer "F.Cu")
		(net 156)
	)
	(segment
		(start 146.8 87)
		(end 147.672 87)
		(width 0.125)
		(layer "F.Cu")
		(net 156)
	)
	(via
		(at 146.8 87)
		(size 0.45)
		(drill 0.1)
		(layers "F.Cu" "B.Cu")
		(net 156)
	)
	(via
		(at 144 87.6)
		(size 0.45)
		(drill 0.1)
		(layers "F.Cu" "B.Cu")
		(net 156)
	)
	(segment
		(start 144 87.6)
		(end 144.6 87)
		(width 0.125)
		(layer "B.Cu")
		(net 156)
	)
	(segment
		(start 144.6 87)
		(end 146.8 87)
		(width 0.125)
		(layer "B.Cu")
		(net 156)
	)
	(segment
		(start 146.905 91.5)
		(end 146.025 91.5)
		(width 0.125)
		(layer "F.Cu")
		(net 157)
	)
	(segment
		(start 147.672 92.999999)
		(end 147.672 92.958967)
		(width 0.125)
		(layer "F.Cu")
		(net 157)
	)
	(segment
		(start 147.048492 92.335457)
		(end 147.048491 91.643493)
		(width 0.125)
		(layer "F.Cu")
		(net 157)
	)
	(segment
		(start 147.048491 91.643493)
		(end 146.905 91.5)
		(width 0.125)
		(layer "F.Cu")
		(net 157)
	)
	(segment
		(start 147.672 92.958967)
		(end 147.048492 92.335457)
		(width 0.125)
		(layer "F.Cu")
		(net 157)
	)
	(segment
		(start 146.8 88)
		(end 147.672 88)
		(width 0.125)
		(layer "F.Cu")
		(net 158)
	)
	(segment
		(start 144.551 89.224999)
		(end 144.551 88.249)
		(width 0.125)
		(layer "F.Cu")
		(net 158)
	)
	(segment
		(start 144.551 88.249)
		(end 144.6 88.2)
		(width 0.125)
		(layer "F.Cu")
		(net 158)
	)
	(via
		(at 144.6 88.2)
		(size 0.45)
		(drill 0.1)
		(layers "F.Cu" "B.Cu")
		(net 158)
	)
	(via
		(at 146.8 88)
		(size 0.45)
		(drill 0.1)
		(layers "F.Cu" "B.Cu")
		(net 158)
	)
	(segment
		(start 144.8 88)
		(end 146.8 88)
		(width 0.125)
		(layer "B.Cu")
		(net 158)
	)
	(segment
		(start 144.6 88.2)
		(end 144.8 88)
		(width 0.125)
		(layer "B.Cu")
		(net 158)
	)
	(segment
		(start 148.632 94.999999)
		(end 148.632 94.96)
		(width 0.125)
		(layer "F.Cu")
		(net 159)
	)
	(segment
		(start 147.002 93.33)
		(end 147.002 92.75)
		(width 0.125)
		(layer "F.Cu")
		(net 159)
	)
	(segment
		(start 147.002 92.75)
		(end 146.749 92.497)
		(width 0.125)
		(layer "F.Cu")
		(net 159)
	)
	(segment
		(start 146.749 92.497)
		(end 146.025 92.497001)
		(width 0.125)
		(layer "F.Cu")
		(net 159)
	)
	(segment
		(start 148.632 94.96)
		(end 147.672 94)
		(width 0.125)
		(layer "F.Cu")
		(net 159)
	)
	(segment
		(start 147.672 94)
		(end 147.002 93.33)
		(width 0.125)
		(layer "F.Cu")
		(net 159)
	)
	(segment
		(start 132.82 156.499498)
		(end 132.82 155.599999)
		(width 0.125)
		(layer "F.Cu")
		(net 161)
	)
	(segment
		(start 129.72 152.499999)
		(end 130.22 151.999999)
		(width 0.125)
		(layer "F.Cu")
		(net 161)
	)
	(segment
		(start 132.82 155.599999)
		(end 131.97 154.749998)
		(width 0.125)
		(layer "F.Cu")
		(net 161)
	)
	(segment
		(start 130.22 151.999999)
		(end 131.24 151.999999)
		(width 0.125)
		(layer "F.Cu")
		(net 161)
	)
	(segment
		(start 131.97 154.749998)
		(end 130.22 154.749998)
		(width 0.125)
		(layer "F.Cu")
		(net 161)
	)
	(segment
		(start 130.22 154.749998)
		(end 129.72 154.249999)
		(width 0.125)
		(layer "F.Cu")
		(net 161)
	)
	(segment
		(start 129.72 154.249999)
		(end 129.72 152.499999)
		(width 0.125)
		(layer "F.Cu")
		(net 161)
	)
	(segment
		(start 138.4 66.35)
		(end 136.35 66.35)
		(width 0.125)
		(layer "F.Cu")
		(net 165)
	)
	(segment
		(start 135.8 38.9)
		(end 135.8 41.7)
		(width 0.125)
		(layer "F.Cu")
		(net 165)
	)
	(segment
		(start 135.3 38.4)
		(end 135.8 38.9)
		(width 0.125)
		(layer "F.Cu")
		(net 165)
	)
	(segment
		(start 136.7 59.7)
		(end 136 59.7)
		(width 0.125)
		(layer "F.Cu")
		(net 165)
	)
	(segment
		(start 136.46 34.755)
		(end 135.645 34.755)
		(width 0.125)
		(layer "F.Cu")
		(net 165)
	)
	(segment
		(start 136.35 66.35)
		(end 136.05 66.05)
		(width 0.125)
		(layer "F.Cu")
		(net 165)
	)
	(segment
		(start 137 61.2)
		(end 137 60)
		(width 0.125)
		(layer "F.Cu")
		(net 165)
	)
	(segment
		(start 135.645 34.755)
		(end 135.3 35.1)
		(width 0.125)
		(layer "F.Cu")
		(net 165)
	)
	(segment
		(start 135.3 35.1)
		(end 135.3 38.4)
		(width 0.125)
		(layer "F.Cu")
		(net 165)
	)
	(segment
		(start 136.05 66.05)
		(end 136.05 62.15)
		(width 0.125)
		(layer "F.Cu")
		(net 165)
	)
	(segment
		(start 136 59.7)
		(end 135.6 60.1)
		(width 0.125)
		(layer "F.Cu")
		(net 165)
	)
	(segment
		(start 132.1 45.4)
		(end 132.1 49.4)
		(width 0.125)
		(layer "F.Cu")
		(net 165)
	)
	(segment
		(start 138.899999 66.849999)
		(end 138.4 66.35)
		(width 0.125)
		(layer "F.Cu")
		(net 165)
	)
	(segment
		(start 135.6 60.1)
		(end 135.6 60.6)
		(width 0.125)
		(layer "F.Cu")
		(net 165)
	)
	(segment
		(start 136.05 62.15)
		(end 137 61.2)
		(width 0.125)
		(layer "F.Cu")
		(net 165)
	)
	(segment
		(start 138.899999 67.57)
		(end 138.899999 66.849999)
		(width 0.125)
		(layer "F.Cu")
		(net 165)
	)
	(segment
		(start 137 60)
		(end 136.7 59.7)
		(width 0.125)
		(layer "F.Cu")
		(net 165)
	)
	(segment
		(start 135.8 41.7)
		(end 132.1 45.4)
		(width 0.125)
		(layer "F.Cu")
		(net 165)
	)
	(via
		(at 132.1 49.4)
		(size 0.45)
		(drill 0.1)
		(layers "F.Cu" "B.Cu")
		(net 165)
	)
	(via
		(at 135.6 60.6)
		(size 0.45)
		(drill 0.1)
		(layers "F.Cu" "B.Cu")
		(net 165)
	)
	(segment
		(start 132.1 49.4)
		(end 132.1 57.1)
		(width 0.125)
		(layer "B.Cu")
		(net 165)
	)
	(segment
		(start 132.1 57.1)
		(end 135.6 60.6)
		(width 0.125)
		(layer "B.Cu")
		(net 165)
	)
	(segment
		(start 136.6455 52.5545)
		(end 135.1 54.1)
		(width 0.125)
		(layer "F.Cu")
		(net 167)
	)
	(segment
		(start 136.631 37.255)
		(end 136.6455 37.2695)
		(width 0.125)
		(layer "F.Cu")
		(net 167)
	)
	(segment
		(start 136.6455 37.2695)
		(end 136.6455 52.5545)
		(width 0.125)
		(layer "F.Cu")
		(net 167)
	)
	(segment
		(start 136.4 61.2)
		(end 136.4 60.3)
		(width 0.125)
		(layer "F.Cu")
		(net 167)
	)
	(segment
		(start 135.7005 61.8995)
		(end 136.4 61.2)
		(width 0.125)
		(layer "F.Cu")
		(net 167)
	)
	(segment
		(start 135.7005 67.570001)
		(end 135.7005 61.8995)
		(width 0.125)
		(layer "F.Cu")
		(net 167)
	)
	(segment
		(start 136.46 37.255)
		(end 136.631 37.255)
		(width 0.125)
		(layer "F.Cu")
		(net 167)
	)
	(via
		(at 135.1 54.1)
		(size 0.45)
		(drill 0.1)
		(layers "F.Cu" "B.Cu")
		(net 167)
	)
	(via
		(at 136.4 60.3)
		(size 0.45)
		(drill 0.1)
		(layers "F.Cu" "B.Cu")
		(net 167)
	)
	(segment
		(start 135.1 59)
		(end 136.4 60.3)
		(width 0.125)
		(layer "B.Cu")
		(net 167)
	)
	(segment
		(start 135.1 54.1)
		(end 135.1 59)
		(width 0.125)
		(layer "B.Cu")
		(net 167)
	)
	(segment
		(start 147.23 112.329999)
		(end 147.3 112.399999)
		(width 0.3)
		(layer "F.Cu")
		(net 168)
	)
	(segment
		(start 147.23 109.929999)
		(end 147.3 109.999999)
		(width 0.3)
		(layer "F.Cu")
		(net 168)
	)
	(segment
		(start 152.67 36.47)
		(end 152.6 36.4)
		(width 0.3)
		(layer "F.Cu")
		(net 168)
	)
	(segment
		(start 152.67 38.87)
		(end 152.6 38.8)
		(width 0.3)
		(layer "F.Cu")
		(net 168)
	)
	(via
		(at 147.3 112.399999)
		(size 0.45)
		(drill 0.1)
		(layers "F.Cu" "B.Cu")
		(free yes)
		(net 168)
	)
	(via
		(at 147.3 110.799999)
		(size 0.45)
		(drill 0.1)
		(layers "F.Cu" "B.Cu")
		(free yes)
		(net 168)
	)
	(via
		(at 153.4 36.4)
		(size 0.45)
		(drill 0.1)
		(layers "F.Cu" "B.Cu")
		(free yes)
		(net 168)
	)
	(via
		(at 152.6 38.8)
		(size 0.45)
		(drill 0.1)
		(layers "F.Cu" "B.Cu")
		(free yes)
		(net 168)
	)
	(via
		(at 146.5 114)
		(size 0.45)
		(drill 0.1)
		(layers "F.Cu" "B.Cu")
		(free yes)
		(net 168)
	)
	(via
		(at 153.4 38)
		(size 0.45)
		(drill 0.1)
		(layers "F.Cu" "B.Cu")
		(free yes)
		(net 168)
	)
	(via
		(at 154.2 37.2)
		(size 0.45)
		(drill 0.1)
		(layers "F.Cu" "B.Cu")
		(free yes)
		(net 168)
	)
	(via
		(at 145.7 113.199998)
		(size 0.45)
		(drill 0.1)
		(layers "F.Cu" "B.Cu")
		(free yes)
		(net 168)
	)
	(via
		(at 146.5 113.199999)
		(size 0.45)
		(drill 0.1)
		(layers "F.Cu" "B.Cu")
		(free yes)
		(net 168)
	)
	(via
		(at 154.2 35.6)
		(size 0.45)
		(drill 0.1)
		(layers "F.Cu" "B.Cu")
		(free yes)
		(net 168)
	)
	(via
		(at 145.7 111.6)
		(size 0.45)
		(drill 0.1)
		(layers "F.Cu" "B.Cu")
		(free yes)
		(net 168)
	)
	(via
		(at 153.4 34.8)
		(size 0.45)
		(drill 0.1)
		(layers "F.Cu" "B.Cu")
		(free yes)
		(net 168)
	)
	(via
		(at 154.2 36.4)
		(size 0.45)
		(drill 0.1)
		(layers "F.Cu" "B.Cu")
		(free yes)
		(net 168)
	)
	(via
		(at 152.6 38)
		(size 0.45)
		(drill 0.1)
		(layers "F.Cu" "B.Cu")
		(free yes)
		(net 168)
	)
	(via
		(at 145.7 110.799997)
		(size 0.45)
		(drill 0.1)
		(layers "F.Cu" "B.Cu")
		(free yes)
		(net 168)
	)
	(via
		(at 147.3 113.999999)
		(size 0.45)
		(drill 0.1)
		(layers "F.Cu" "B.Cu")
		(free yes)
		(net 168)
	)
	(via
		(at 146.5 111.599999)
		(size 0.45)
		(drill 0.1)
		(layers "F.Cu" "B.Cu")
		(free yes)
		(net 168)
	)
	(via
		(at 152.6 34.8)
		(size 0.45)
		(drill 0.1)
		(layers "F.Cu" "B.Cu")
		(free yes)
		(net 168)
	)
	(via
		(at 153.4 35.6)
		(size 0.45)
		(drill 0.1)
		(layers "F.Cu" "B.Cu")
		(free yes)
		(net 168)
	)
	(via
		(at 152.6 37.2)
		(size 0.45)
		(drill 0.1)
		(layers "F.Cu" "B.Cu")
		(free yes)
		(net 168)
	)
	(via
		(at 147.3 113.199999)
		(size 0.45)
		(drill 0.1)
		(layers "F.Cu" "B.Cu")
		(free yes)
		(net 168)
	)
	(via
		(at 154.2 38)
		(size 0.45)
		(drill 0.1)
		(layers "F.Cu" "B.Cu")
		(free yes)
		(net 168)
	)
	(via
		(at 146.5 110.799999)
		(size 0.45)
		(drill 0.1)
		(layers "F.Cu" "B.Cu")
		(free yes)
		(net 168)
	)
	(via
		(at 154.2 38.8)
		(size 0.45)
		(drill 0.1)
		(layers "F.Cu" "B.Cu")
		(free yes)
		(net 168)
	)
	(via
		(at 146.499999 109.999999)
		(size 0.45)
		(drill 0.1)
		(layers "F.Cu" "B.Cu")
		(free yes)
		(net 168)
	)
	(via
		(at 147.3 111.599999)
		(size 0.45)
		(drill 0.1)
		(layers "F.Cu" "B.Cu")
		(free yes)
		(net 168)
	)
	(via
		(at 153.4 38.8)
		(size 0.45)
		(drill 0.1)
		(layers "F.Cu" "B.Cu")
		(free yes)
		(net 168)
	)
	(via
		(at 145.7 109.999999)
		(size 0.45)
		(drill 0.1)
		(layers "F.Cu" "B.Cu")
		(free yes)
		(net 168)
	)
	(via
		(at 147.3 109.999999)
		(size 0.45)
		(drill 0.1)
		(layers "F.Cu" "B.Cu")
		(free yes)
		(net 168)
	)
	(via
		(at 146.499999 112.399999)
		(size 0.45)
		(drill 0.1)
		(layers "F.Cu" "B.Cu")
		(free yes)
		(net 168)
	)
	(via
		(at 145.7 113.999999)
		(size 0.45)
		(drill 0.1)
		(layers "F.Cu" "B.Cu")
		(free yes)
		(net 168)
	)
	(via
		(at 152.6 35.6)
		(size 0.45)
		(drill 0.1)
		(layers "F.Cu" "B.Cu")
		(free yes)
		(net 168)
	)
	(via
		(at 152.6 36.4)
		(size 0.45)
		(drill 0.1)
		(layers "F.Cu" "B.Cu")
		(free yes)
		(net 168)
	)
	(via
		(at 153.4 37.2)
		(size 0.45)
		(drill 0.1)
		(layers "F.Cu" "B.Cu")
		(free yes)
		(net 168)
	)
	(via
		(at 154.2 34.8)
		(size 0.45)
		(drill 0.1)
		(layers "F.Cu" "B.Cu")
		(free yes)
		(net 168)
	)
	(via
		(at 145.7 112.399999)
		(size 0.45)
		(drill 0.1)
		(layers "F.Cu" "B.Cu")
		(free yes)
		(net 168)
	)
	(segment
		(start 119.682844 43.7)
		(end 120.917156 43.7)
		(width 0.2)
		(layer "F.Cu")
		(net 170)
	)
	(segment
		(start 126.75 47.532844)
		(end 126.75 44.234501)
		(width 0.2)
		(layer "F.Cu")
		(net 170)
	)
	(segment
		(start 126.75 42.537499)
		(end 126.75 41.037501)
		(width 0.2)
		(layer "F.Cu")
		(net 170)
	)
	(segment
		(start 119.25 44.945)
		(end 119.25 44.132844)
		(width 0.2)
		(layer "F.Cu")
		(net 170)
	)
	(segment
		(start 121.3 44.082844)
		(end 121.3 47.582844)
		(width 0.2)
		(layer "F.Cu")
		(net 170)
	)
	(segment
		(start 126.75 41.037501)
		(end 126.8 40.987501)
		(width 0.2)
		(layer "F.Cu")
		(net 170)
	)
	(segment
		(start 119.25 44.132844)
		(end 119.682844 43.7)
		(width 0.2)
		(layer "F.Cu")
		(net 170)
	)
	(segment
		(start 126.8 44.184501)
		(end 126.8 43.772)
		(width 0.2)
		(layer "F.Cu")
		(net 170)
	)
	(segment
		(start 120.917156 43.7)
		(end 121.3 44.082844)
		(width 0.2)
		(layer "F.Cu")
		(net 170)
	)
	(segment
		(start 126.8 43.772)
		(end 126.8 43)
		(width 0.2)
		(layer "F.Cu")
		(net 170)
	)
	(segment
		(start 126.75 44.234501)
		(end 126.8 44.184501)
		(width 0.2)
		(layer "F.Cu")
		(net 170)
	)
	(segment
		(start 125.082844 49.2)
		(end 126.75 47.532844)
		(width 0.2)
		(layer "F.Cu")
		(net 170)
	)
	(segment
		(start 119.55 45.245)
		(end 119.25 44.945)
		(width 0.2)
		(layer "F.Cu")
		(net 170)
	)
	(segment
		(start 126.8 42.587499)
		(end 126.75 42.537499)
		(width 0.2)
		(layer "F.Cu")
		(net 170)
	)
	(segment
		(start 119.55 45.27)
		(end 119.55 45.245)
		(width 0.2)
		(layer "F.Cu")
		(net 170)
	)
	(segment
		(start 122.917156 49.2)
		(end 125.082844 49.2)
		(width 0.2)
		(layer "F.Cu")
		(net 170)
	)
	(segment
		(start 126.8 43)
		(end 126.8 42.587499)
		(width 0.2)
		(layer "F.Cu")
		(net 170)
	)
	(segment
		(start 121.3 47.582844)
		(end 122.917156 49.2)
		(width 0.2)
		(layer "F.Cu")
		(net 170)
	)
	(segment
		(start 126.8 40.987501)
		(end 126.8 40.305)
		(width 0.2)
		(layer "F.Cu")
		(net 170)
	)
	(segment
		(start 126.35 44.234501)
		(end 126.3 44.184501)
		(width 0.2)
		(layer "F.Cu")
		(net 171)
	)
	(segment
		(start 119.517156 43.3)
		(end 121.082844 43.3)
		(width 0.2)
		(layer "F.Cu")
		(net 171)
	)
	(segment
		(start 126.35 47.367156)
		(end 126.35 44.234501)
		(width 0.2)
		(layer "F.Cu")
		(net 171)
	)
	(segment
		(start 118.55 45.27)
		(end 118.55 45.245)
		(width 0.2)
		(layer "F.Cu")
		(net 171)
	)
	(segment
		(start 126.3 40.987501)
		(end 126.3 40.305)
		(width 0.2)
		(layer "F.Cu")
		(net 171)
	)
	(segment
		(start 121.082844 43.3)
		(end 121.7 43.917156)
		(width 0.2)
		(layer "F.Cu")
		(net 171)
	)
	(segment
		(start 126.3 43)
		(end 126.3 42.587499)
		(width 0.2)
		(layer "F.Cu")
		(net 171)
	)
	(segment
		(start 121.7 47.417156)
		(end 123.082844 48.8)
		(width 0.2)
		(layer "F.Cu")
		(net 171)
	)
	(segment
		(start 118.85 44.945)
		(end 118.85 43.967156)
		(width 0.2)
		(layer "F.Cu")
		(net 171)
	)
	(segment
		(start 126.3 44.184501)
		(end 126.3 43.772)
		(width 0.2)
		(layer "F.Cu")
		(net 171)
	)
	(segment
		(start 126.3 43.772)
		(end 126.3 43)
		(width 0.2)
		(layer "F.Cu")
		(net 171)
	)
	(segment
		(start 118.55 45.245)
		(end 118.85 44.945)
		(width 0.2)
		(layer "F.Cu")
		(net 171)
	)
	(segment
		(start 126.3 42.587499)
		(end 126.35 42.537499)
		(width 0.2)
		(layer "F.Cu")
		(net 171)
	)
	(segment
		(start 126.35 41.037501)
		(end 126.3 40.987501)
		(width 0.2)
		(layer "F.Cu")
		(net 171)
	)
	(segment
		(start 121.7 43.917156)
		(end 121.7 47.417156)
		(width 0.2)
		(layer "F.Cu")
		(net 171)
	)
	(segment
		(start 124.917156 48.8)
		(end 126.35 47.367156)
		(width 0.2)
		(layer "F.Cu")
		(net 171)
	)
	(segment
		(start 118.85 43.967156)
		(end 119.517156 43.3)
		(width 0.2)
		(layer "F.Cu")
		(net 171)
	)
	(segment
		(start 123.082844 48.8)
		(end 124.917156 48.8)
		(width 0.2)
		(layer "F.Cu")
		(net 171)
	)
	(segment
		(start 126.35 42.537499)
		(end 126.35 41.037501)
		(width 0.2)
		(layer "F.Cu")
		(net 171)
	)
	(segment
		(start 107.574 111.1)
		(end 105.95 111.1)
		(width 0.125)
		(layer "F.Cu")
		(net 172)
	)
	(segment
		(start 153.8 148)
		(end 155.75 148)
		(width 0.125)
		(layer "F.Cu")
		(net 172)
	)
	(segment
		(start 128.3 155.5)
		(end 128.332998 155.5)
		(width 0.125)
		(layer "F.Cu")
		(net 172)
	)
	(segment
		(start 128.332998 152.556999)
		(end 128.332998 155.5)
		(width 0.125)
		(layer "F.Cu")
		(net 172)
	)
	(segment
		(start 130.571002 155.5)
		(end 128.332998 155.5)
		(width 0.125)
		(layer "F.Cu")
		(net 172)
	)
	(segment
		(start 130.62 155.548998)
		(end 130.571002 155.5)
		(width 0.125)
		(layer "F.Cu")
		(net 172)
	)
	(segment
		(start 151.3 150.5)
		(end 153.8 148)
		(width 0.125)
		(layer "F.Cu")
		(net 172)
	)
	(segment
		(start 127.332999 152.556999)
		(end 128.332999 152.556999)
		(width 0.15)
		(layer "F.Cu")
		(net 172)
	)
	(segment
		(start 128.332998 152.556999)
		(end 128.943001 152.556999)
		(width 0.125)
		(layer "F.Cu")
		(net 172)
	)
	(segment
		(start 128.943001 152.556999)
		(end 131 150.5)
		(width 0.125)
		(layer "F.Cu")
		(net 172)
	)
	(segment
		(start 126.332999 152.556999)
		(end 127.332999 152.556999)
		(width 0.15)
		(layer "F.Cu")
		(net 172)
	)
	(segment
		(start 131 150.5)
		(end 151.3 150.5)
		(width 0.125)
		(layer "F.Cu")
		(net 172)
	)
	(segment
		(start 127.2 156.6)
		(end 128.3 155.5)
		(width 0.125)
		(layer "F.Cu")
		(net 172)
	)
	(via
		(at 105.95 111.1)
		(size 0.45)
		(drill 0.1)
		(layers "F.Cu" "B.Cu")
		(net 172)
	)
	(via
		(at 127.2 156.6)
		(size 0.45)
		(drill 0.1)
		(layers "F.Cu" "B.Cu")
		(net 172)
	)
	(segment
		(start 108.1 111.1)
		(end 105.95 111.1)
		(width 0.125)
		(layer "B.Cu")
		(net 172)
	)
	(segment
		(start 127.2 156.6)
		(end 121 156.6)
		(width 0.125)
		(layer "B.Cu")
		(net 172)
	)
	(segment
		(start 121 156.6)
		(end 116.9 152.5)
		(width 0.125)
		(layer "B.Cu")
		(net 172)
	)
	(segment
		(start 116.9 119.9)
		(end 108.1 111.1)
		(width 0.125)
		(layer "B.Cu")
		(net 172)
	)
	(segment
		(start 116.9 152.5)
		(end 116.9 119.9)
		(width 0.125)
		(layer "B.Cu")
		(net 172)
	)
	(segment
		(start 138.750499 71.300001)
		(end 139.1495 71.699)
		(width 0.15)
		(layer "F.Cu")
		(net 173)
	)
	(segment
		(start 137.0005 71.3)
		(end 138.750499 71.300001)
		(width 0.15)
		(layer "F.Cu")
		(net 173)
	)
	(segment
		(start 136.75 70.25)
		(end 136.750001 68.529999)
		(width 0.15)
		(layer "F.Cu")
		(net 173)
	)
	(segment
		(start 136.75 70.25)
		(end 136.75 71.0495)
		(width 0.15)
		(layer "F.Cu")
		(net 173)
	)
	(segment
		(start 139.1495 71.699)
		(end 139.1495 72.45)
		(width 0.15)
		(layer "F.Cu")
		(net 173)
	)
	(segment
		(start 137.85 68.53)
		(end 136.750001 68.529999)
		(width 0.15)
		(layer "F.Cu")
		(net 173)
	)
	(segment
		(start 136.75 71.0495)
		(end 137.0005 71.3)
		(width 0.15)
		(layer "F.Cu")
		(net 173)
	)
	(segment
		(start 140.1 69.2495)
		(end 140.1 70.249999)
		(width 0.15)
		(layer "F.Cu")
		(net 174)
	)
	(segment
		(start 139.3805 68.53)
		(end 140.1 69.2495)
		(width 0.15)
		(layer "F.Cu")
		(net 174)
	)
	(segment
		(start 138.9 68.53)
		(end 139.3805 68.53)
		(width 0.15)
		(layer "F.Cu")
		(net 174)
	)
	(segment
		(start 138.5 144.25)
		(end 138.753 144.503)
		(width 0.2)
		(layer "F.Cu")
		(net 175)
	)
	(segment
		(start 138.762 141.988)
		(end 138.5 142.25)
		(width 0.2)
		(layer "F.Cu")
		(net 175)
	)
	(segment
		(start 139.564 141.988)
		(end 138.762 141.988)
		(width 0.2)
		(layer "F.Cu")
		(net 175)
	)
	(segment
		(start 138.5 142.25)
		(end 138.5 144.25)
		(width 0.2)
		(layer "F.Cu")
		(net 175)
	)
	(segment
		(start 138.753 144.503)
		(end 139.786 144.503)
		(width 0.2)
		(layer "F.Cu")
		(net 175)
	)
	(segment
		(start 133.3995 69.700999)
		(end 133.3995 70.249999)
		(width 0.15)
		(layer "F.Cu")
		(net 176)
	)
	(segment
		(start 133.550499 69.55)
		(end 133.3995 69.700999)
		(width 0.15)
		(layer "F.Cu")
		(net 176)
	)
	(segment
		(start 135.7005 69.3)
		(end 135.4505 69.550001)
		(width 0.15)
		(layer "F.Cu")
		(net 176)
	)
	(segment
		(start 135.7005 68.53)
		(end 135.7005 69.3)
		(width 0.15)
		(layer "F.Cu")
		(net 176)
	)
	(segment
		(start 135.4505 69.550001)
		(end 133.550499 69.55)
		(width 0.15)
		(layer "F.Cu")
		(net 176)
	)
	(segment
		(start 127.080999 150.426999)
		(end 127.080999 151.344999)
		(width 0.15)
		(layer "F.Cu")
		(net 177)
	)
	(segment
		(start 127.080999 151.344999)
		(end 127.332999 151.596999)
		(width 0.15)
		(layer "F.Cu")
		(net 177)
	)
	(segment
		(start 119.55 48.705)
		(end 119.25 49.005)
		(width 0.2)
		(layer "F.Cu")
		(net 178)
	)
	(segment
		(start 119.55 48.68)
		(end 119.55 48.705)
		(width 0.2)
		(layer "F.Cu")
		(net 178)
	)
	(segment
		(start 145.52 64)
		(end 144.9 64)
		(width 0.2)
		(layer "F.Cu")
		(net 178)
	)
	(segment
		(start 122.875 50.5)
		(end 123 50.375)
		(width 0.2)
		(layer "F.Cu")
		(net 178)
	)
	(segment
		(start 144.28 64)
		(end 144.9 64)
		(width 0.2)
		(layer "F.Cu")
		(net 178)
	)
	(segment
		(start 119.25 49.005)
		(end 119.25 49.867156)
		(width 0.2)
		(layer "F.Cu")
		(net 178)
	)
	(segment
		(start 119.25 49.867156)
		(end 119.882844 50.5)
		(width 0.2)
		(layer "F.Cu")
		(net 178)
	)
	(segment
		(start 119.882844 50.5)
		(end 122.875 50.5)
		(width 0.2)
		(layer "F.Cu")
		(net 178)
	)
	(via
		(at 144.9 64)
		(size 0.45)
		(drill 0.1)
		(layers "F.Cu" "B.Cu")
		(net 178)
	)
	(via
		(at 123 50.375)
		(size 0.45)
		(drill 0.1)
		(layers "F.Cu" "B.Cu")
		(net 178)
	)
	(segment
		(start 123.317156 50.5)
		(end 123.125 50.5)
		(width 0.2)
		(layer "B.Cu")
		(net 178)
	)
	(segment
		(start 126.717156 47.1)
		(end 123.317156 50.5)
		(width 0.2)
		(layer "B.Cu")
		(net 178)
	)
	(segment
		(start 123.125 50.5)
		(end 123 50.375)
		(width 0.2)
		(layer "B.Cu")
		(net 178)
	)
	(segment
		(start 145.782844 63.7)
		(end 146.5 62.982844)
		(width 0.2)
		(layer "B.Cu")
		(net 178)
	)
	(segment
		(start 144.9 64)
		(end 145.2 63.7)
		(width 0.2)
		(layer "B.Cu")
		(net 178)
	)
	(segment
		(start 146.5 62.982844)
		(end 146.5 59.017156)
		(width 0.2)
		(layer "B.Cu")
		(net 178)
	)
	(segment
		(start 134.582844 47.1)
		(end 126.717156 47.1)
		(width 0.2)
		(layer "B.Cu")
		(net 178)
	)
	(segment
		(start 146.5 59.017156)
		(end 134.582844 47.1)
		(width 0.2)
		(layer "B.Cu")
		(net 178)
	)
	(segment
		(start 145.2 63.7)
		(end 145.782844 63.7)
		(width 0.2)
		(layer "B.Cu")
		(net 178)
	)
	(segment
		(start 119.717156 50.9)
		(end 122.875 50.9)
		(width 0.2)
		(layer "F.Cu")
		(net 179)
	)
	(segment
		(start 122.875 50.9)
		(end 123 51.025)
		(width 0.2)
		(layer "F.Cu")
		(net 179)
	)
	(segment
		(start 144.28 63)
		(end 144.9 63)
		(width 0.2)
		(layer "F.Cu")
		(net 179)
	)
	(segment
		(start 118.55 48.68)
		(end 118.55 48.705)
		(width 0.2)
		(layer "F.Cu")
		(net 179)
	)
	(segment
		(start 145.52 63)
		(end 144.9 63)
		(width 0.2)
		(layer "F.Cu")
		(net 179)
	)
	(segment
		(start 118.85 49.005)
		(end 118.85 50.032844)
		(width 0.2)
		(layer "F.Cu")
		(net 179)
	)
	(segment
		(start 118.85 50.032844)
		(end 119.717156 50.9)
		(width 0.2)
		(layer "F.Cu")
		(net 179)
	)
	(segment
		(start 118.55 48.705)
		(end 118.85 49.005)
		(width 0.2)
		(layer "F.Cu")
		(net 179)
	)
	(via
		(at 144.9 63)
		(size 0.45)
		(drill 0.1)
		(layers "F.Cu" "B.Cu")
		(net 179)
	)
	(via
		(at 123 51.025)
		(size 0.45)
		(drill 0.1)
		(layers "F.Cu" "B.Cu")
		(net 179)
	)
	(segment
		(start 145.2 63.3)
		(end 144.9 63)
		(width 0.2)
		(layer "B.Cu")
		(net 179)
	)
	(segment
		(start 139.297821 52.380665)
		(end 139.841593 52.924437)
		(width 0.2)
		(layer "B.Cu")
		(net 179)
	)
	(segment
		(start 138.408696 52.251555)
		(end 138.493548 52.336407)
		(width 0.2)
		(layer "B.Cu")
		(net 179)
	)
	(segment
		(start 126.882844 47.5)
		(end 134.417156 47.5)
		(width 0.2)
		(layer "B.Cu")
		(net 179)
	)
	(segment
		(start 138.83296 52.336407)
		(end 138.873556 52.29581)
		(width 0.2)
		(layer "B.Cu")
		(net 179)
	)
	(segment
		(start 138.449293 51.871548)
		(end 138.408696 51.912144)
		(width 0.2)
		(layer "B.Cu")
		(net 179)
	)
	(segment
		(start 134.417156 47.5)
		(end 138.449293 51.532137)
		(width 0.2)
		(layer "B.Cu")
		(net 179)
	)
	(segment
		(start 123.482844 50.9)
		(end 126.882844 47.5)
		(width 0.2)
		(layer "B.Cu")
		(net 179)
	)
	(segment
		(start 146.1 62.817156)
		(end 145.617156 63.3)
		(width 0.2)
		(layer "B.Cu")
		(net 179)
	)
	(segment
		(start 145.617156 63.3)
		(end 145.2 63.3)
		(width 0.2)
		(layer "B.Cu")
		(net 179)
	)
	(segment
		(start 146.1 59.182844)
		(end 146.1 62.817156)
		(width 0.2)
		(layer "B.Cu")
		(net 179)
	)
	(segment
		(start 139.841593 52.924437)
		(end 146.1 59.182844)
		(width 0.2)
		(layer "B.Cu")
		(net 179)
	)
	(segment
		(start 123 51.025)
		(end 123.125 50.9)
		(width 0.2)
		(layer "B.Cu")
		(net 179)
	)
	(segment
		(start 139.212967 52.29581)
		(end 139.297821 52.380665)
		(width 0.2)
		(layer "B.Cu")
		(net 179)
	)
	(segment
		(start 123.125 50.9)
		(end 123.482844 50.9)
		(width 0.2)
		(layer "B.Cu")
		(net 179)
	)
	(arc
		(start 138.493548 52.336407)
		(mid 138.663254 52.406702)
		(end 138.83296 52.336407)
		(width 0.2)
		(layer "B.Cu")
		(net 179)
	)
	(arc
		(start 138.873556 52.29581)
		(mid 139.043261 52.225516)
		(end 139.212967 52.29581)
		(width 0.2)
		(layer "B.Cu")
		(net 179)
	)
	(arc
		(start 138.449293 51.532137)
		(mid 138.519587 51.701843)
		(end 138.449293 51.871548)
		(width 0.2)
		(layer "B.Cu")
		(net 179)
	)
	(arc
		(start 138.408696 51.912144)
		(mid 138.338402 52.081849)
		(end 138.408696 52.251555)
		(width 0.2)
		(layer "B.Cu")
		(net 179)
	)
	(segment
		(start 127.080999 147.029999)
		(end 127.082999 147.027999)
		(width 0.15)
		(layer "F.Cu")
		(net 181)
	)
	(segment
		(start 127.581999 147.677999)
		(end 127.582 147.226999)
		(width 0.15)
		(layer "F.Cu")
		(net 181)
	)
	(segment
		(start 127.382999 147.027999)
		(end 127.082999 147.027999)
		(width 0.15)
		(layer "F.Cu")
		(net 181)
	)
	(segment
		(start 126.580999 147.229999)
		(end 126.580999 147.677999)
		(width 0.15)
		(layer "F.Cu")
		(net 181)
	)
	(segment
		(start 127.582 147.226999)
		(end 127.382999 147.027999)
		(width 0.15)
		(layer "F.Cu")
		(net 181)
	)
	(segment
		(start 126.782999 147.027999)
		(end 126.580999 147.229999)
		(width 0.15)
		(layer "F.Cu")
		(net 181)
	)
	(segment
		(start 127.082999 147.027999)
		(end 126.782999 147.027999)
		(width 0.15)
		(layer "F.Cu")
		(net 181)
	)
	(segment
		(start 127.080999 147.677999)
		(end 127.080999 147.029999)
		(width 0.15)
		(layer "F.Cu")
		(net 181)
	)
	(segment
		(start 143.579 44.921)
		(end 143.6 44.9)
		(width 0.125)
		(layer "F.Cu")
		(net 182)
	)
	(segment
		(start 143.579 50.117019)
		(end 143.781981 50.32)
		(width 0.125)
		(layer "F.Cu")
		(net 182)
	)
	(segment
		(start 125.8 38.115)
		(end 125.8 36.8)
		(width 0.125)
		(layer "F.Cu")
		(net 182)
	)
	(segment
		(start 143.579 47.299999)
		(end 143.579 50.117019)
		(width 0.125)
		(layer "F.Cu")
		(net 182)
	)
	(segment
		(start 143.579 46.527999)
		(end 143.579 44.921)
		(width 0.125)
		(layer "F.Cu")
		(net 182)
	)
	(segment
		(start 143.579 46.527999)
		(end 143.579 47.299999)
		(width 0.125)
		(layer "F.Cu")
		(net 182)
	)
	(via
		(at 143.6 44.9)
		(size 0.45)
		(drill 0.1)
		(layers "F.Cu" "B.Cu")
		(net 182)
	)
	(via
		(at 125.8 36.8)
		(size 0.45)
		(drill 0.1)
		(layers "F.Cu" "B.Cu")
		(net 182)
	)
	(segment
		(start 125.8 36)
		(end 127.4 34.4)
		(width 0.125)
		(layer "B.Cu")
		(net 182)
	)
	(segment
		(start 127.4 34.4)
		(end 135.3 34.4)
		(width 0.125)
		(layer "B.Cu")
		(net 182)
	)
	(segment
		(start 141 35.2)
		(end 142.4 36.6)
		(width 0.125)
		(layer "B.Cu")
		(net 182)
	)
	(segment
		(start 142.4 36.6)
		(end 142.4 43.7)
		(width 0.125)
		(layer "B.Cu")
		(net 182)
	)
	(segment
		(start 135.3 34.4)
		(end 136.1 35.2)
		(width 0.125)
		(layer "B.Cu")
		(net 182)
	)
	(segment
		(start 125.8 36.8)
		(end 125.8 36)
		(width 0.125)
		(layer "B.Cu")
		(net 182)
	)
	(segment
		(start 136.1 35.2)
		(end 141 35.2)
		(width 0.125)
		(layer "B.Cu")
		(net 182)
	)
	(segment
		(start 142.4 43.7)
		(end 143.6 44.9)
		(width 0.125)
		(layer "B.Cu")
		(net 182)
	)
	(segment
		(start 126.3 38.115)
		(end 126.3 36.5)
		(width 0.125)
		(layer "F.Cu")
		(net 183)
	)
	(segment
		(start 142.721321 49.478679)
		(end 142.721321 50.32)
		(width 0.125)
		(layer "F.Cu")
		(net 183)
	)
	(segment
		(start 129.6 35.9)
		(end 126.9 35.9)
		(width 0.125)
		(layer "F.Cu")
		(net 183)
	)
	(segment
		(start 142.5 44.4)
		(end 143.079 44.979)
		(width 0.125)
		(layer "F.Cu")
		(net 183)
	)
	(segment
		(start 143.079 46.527999)
		(end 143.079 44.979)
		(width 0.125)
		(layer "F.Cu")
		(net 183)
	)
	(segment
		(start 141.6 44.4)
		(end 141.1 44.9)
		(width 0.125)
		(layer "F.Cu")
		(net 183)
	)
	(segment
		(start 143.079 49.121)
		(end 142.721321 49.478679)
		(width 0.125)
		(layer "F.Cu")
		(net 183)
	)
	(segment
		(start 141.6 44.4)
		(end 142.5 44.4)
		(width 0.125)
		(layer "F.Cu")
		(net 183)
	)
	(segment
		(start 143.079 46.527999)
		(end 143.079 47.3)
		(width 0.125)
		(layer "F.Cu")
		(net 183)
	)
	(segment
		(start 126.9 35.9)
		(end 126.3 36.5)
		(width 0.125)
		(layer "F.Cu")
		(net 183)
	)
	(segment
		(start 143.079 47.3)
		(end 143.079 49.121)
		(width 0.125)
		(layer "F.Cu")
		(net 183)
	)
	(via
		(at 129.6 35.9)
		(size 0.45)
		(drill 0.1)
		(layers "F.Cu" "B.Cu")
		(net 183)
	)
	(via
		(at 141.1 44.9)
		(size 0.45)
		(drill 0.1)
		(layers "F.Cu" "B.Cu")
		(net 183)
	)
	(segment
		(start 141.1 43.25)
		(end 139.85 42)
		(width 0.125)
		(layer "B.Cu")
		(net 183)
	)
	(segment
		(start 139 42)
		(end 138.6 41.6)
		(width 0.125)
		(layer "B.Cu")
		(net 183)
	)
	(segment
		(start 134.1 35.9)
		(end 129.6 35.9)
		(width 0.125)
		(layer "B.Cu")
		(net 183)
	)
	(segment
		(start 139.85 42)
		(end 139 42)
		(width 0.125)
		(layer "B.Cu")
		(net 183)
	)
	(segment
		(start 138.6 40.4)
		(end 134.1 35.9)
		(width 0.125)
		(layer "B.Cu")
		(net 183)
	)
	(segment
		(start 138.6 41.6)
		(end 138.6 40.4)
		(width 0.125)
		(layer "B.Cu")
		(net 183)
	)
	(segment
		(start 141.1 44.9)
		(end 141.1 43.25)
		(width 0.125)
		(layer "B.Cu")
		(net 183)
	)
	(segment
		(start 127.798 43)
		(end 127.798 42.002)
		(width 0.125)
		(layer "F.Cu")
		(net 184)
	)
	(segment
		(start 127.798 47.102)
		(end 127.798 43.772)
		(width 0.125)
		(layer "F.Cu")
		(net 184)
	)
	(segment
		(start 125.5 51.5)
		(end 126.1 50.9)
		(width 0.125)
		(layer "F.Cu")
		(net 184)
	)
	(segment
		(start 127.8 42)
		(end 127.8 40.305)
		(width 0.125)
		(layer "F.Cu")
		(net 184)
	)
	(segment
		(start 126.1 50.9)
		(end 126.1 48.8)
		(width 0.125)
		(layer "F.Cu")
		(net 184)
	)
	(segment
		(start 127.798 43.772001)
		(end 127.798 43)
		(width 0.125)
		(layer "F.Cu")
		(net 184)
	)
	(segment
		(start 126.1 48.8)
		(end 127.798 47.102)
		(width 0.125)
		(layer "F.Cu")
		(net 184)
	)
	(segment
		(start 127.798 42.002)
		(end 127.8 42)
		(width 0.125)
		(layer "F.Cu")
		(net 184)
	)
	(segment
		(start 126.083 151.346999)
		(end 126.332999 151.596999)
		(width 0.15)
		(layer "F.Cu")
		(net 185)
	)
	(segment
		(start 142.8 51.358679)
		(end 142.721321 51.28)
		(width 0.125)
		(layer "F.Cu")
		(net 185)
	)
	(segment
		(start 125.332999 151.596999)
		(end 126.332999 151.596999)
		(width 0.15)
		(layer "F.Cu")
		(net 185)
	)
	(segment
		(start 142.8 52)
		(end 142.8 51.358679)
		(width 0.125)
		(layer "F.Cu")
		(net 185)
	)
	(segment
		(start 125.332999 151.596998)
		(end 124.603002 151.596998)
		(width 0.125)
		(layer "F.Cu")
		(net 185)
	)
	(segment
		(start 124.603002 151.596998)
		(end 124.6 151.6)
		(width 0.125)
		(layer "F.Cu")
		(net 185)
	)
	(segment
		(start 126.082999 150.426999)
		(end 126.083 151.346999)
		(width 0.15)
		(layer "F.Cu")
		(net 185)
	)
	(via
		(at 142.8 52)
		(size 0.45)
		(drill 0.1)
		(layers "F.Cu" "B.Cu")
		(net 185)
	)
	(via
		(at 124.6 151.6)
		(size 0.45)
		(drill 0.1)
		(layers "F.Cu" "B.Cu")
		(net 185)
	)
	(segment
		(start 146.55 54.85)
		(end 147.1 55.4)
		(width 0.125)
		(layer "B.Cu")
		(net 185)
	)
	(segment
		(start 150.9 58.3)
		(end 150.9 99.1)
		(width 0.125)
		(layer "B.Cu")
		(net 185)
	)
	(segment
		(start 124.6 142)
		(end 124.6 151.6)
		(width 0.125)
		(layer "B.Cu")
		(net 185)
	)
	(segment
		(start 144.2 52)
		(end 145 51.2)
		(width 0.125)
		(layer "B.Cu")
		(net 185)
	)
	(segment
		(start 146.55 51.75)
		(end 146.55 54.85)
		(width 0.125)
		(layer "B.Cu")
		(net 185)
	)
	(segment
		(start 147.1 55.4)
		(end 148 55.4)
		(width 0.125)
		(layer "B.Cu")
		(net 185)
	)
	(segment
		(start 150.9 99.1)
		(end 143.55 106.45)
		(width 0.125)
		(layer "B.Cu")
		(net 185)
	)
	(segment
		(start 146 51.2)
		(end 146.55 51.75)
		(width 0.125)
		(layer "B.Cu")
		(net 185)
	)
	(segment
		(start 142.8 52)
		(end 144.2 52)
		(width 0.125)
		(layer "B.Cu")
		(net 185)
	)
	(segment
		(start 148 55.4)
		(end 150.9 58.3)
		(width 0.125)
		(layer "B.Cu")
		(net 185)
	)
	(segment
		(start 145 51.2)
		(end 146 51.2)
		(width 0.125)
		(layer "B.Cu")
		(net 185)
	)
	(segment
		(start 143.55 106.45)
		(end 143.55 123.05)
		(width 0.125)
		(layer "B.Cu")
		(net 185)
	)
	(segment
		(start 143.55 123.05)
		(end 124.6 142)
		(width 0.125)
		(layer "B.Cu")
		(net 185)
	)
	(segment
		(start 120.4 139.351001)
		(end 118.651001 139.351001)
		(width 0.2)
		(layer "F.Cu")
		(net 186)
	)
	(segment
		(start 119.1 131.8)
		(end 120.019999 131.8)
		(width 0.2)
		(layer "F.Cu")
		(net 186)
	)
	(segment
		(start 118.4 132.5)
		(end 119.1 131.8)
		(width 0.2)
		(layer "F.Cu")
		(net 186)
	)
	(segment
		(start 118.4 139.1)
		(end 118.4 132.5)
		(width 0.2)
		(layer "F.Cu")
		(net 186)
	)
	(segment
		(start 118.651001 139.351001)
		(end 118.4 139.1)
		(width 0.2)
		(layer "F.Cu")
		(net 186)
	)
	(segment
		(start 149.302 94)
		(end 149.302 95.33)
		(width 0.3)
		(layer "F.Cu")
		(net 187)
	)
	(segment
		(start 149.302 94)
		(end 148.632 94)
		(width 0.15)
		(layer "F.Cu")
		(net 187)
	)
	(segment
		(start 146.301 93.499)
		(end 146.025 93.499001)
		(width 0.15)
		(layer "F.Cu")
		(net 187)
	)
	(segment
		(start 146.652 94)
		(end 146.652 93.85)
		(width 0.15)
		(layer "F.Cu")
		(net 187)
	)
	(segment
		(start 146.652 93.85)
		(end 146.301 93.499)
		(width 0.15)
		(layer "F.Cu")
		(net 187)
	)
	(segment
		(start 149.302 95.33)
		(end 148.632 96)
		(width 0.3)
		(layer "F.Cu")
		(net 187)
	)
	(segment
		(start 149.302 94)
		(end 148.632001 94)
		(width 0.3)
		(layer "F.Cu")
		(net 187)
	)
	(segment
		(start 138.2 94.599999)
		(end 139.6 94.6)
		(width 0.125)
		(layer "F.Cu")
		(net 187)
	)
	(segment
		(start 148.632001 94)
		(end 148.632 93.999999)
		(width 0.3)
		(layer "F.Cu")
		(net 187)
	)
	(via
		(at 149.302 94)
		(size 0.55)
		(drill 0.15)
		(layers "F.Cu" "B.Cu")
		(net 187)
	)
	(via
		(at 146.652 94)
		(size 0.55)
		(drill 0.15)
		(layers "F.Cu" "B.Cu")
		(net 187)
	)
	(via
		(at 139.6 94.6)
		(size 0.45)
		(drill 0.1)
		(layers "F.Cu" "B.Cu")
		(net 187)
	)
	(segment
		(start 146.652 94)
		(end 149.302 94)
		(width 0.3)
		(layer "B.Cu")
		(net 187)
	)
	(segment
		(start 139.6 94.6)
		(end 146.052 94.6)
		(width 0.3)
		(layer "B.Cu")
		(net 187)
	)
	(segment
		(start 146.052 94.6)
		(end 146.652 94)
		(width 0.3)
		(layer "B.Cu")
		(net 187)
	)
	(segment
		(start 142.175001 63.7)
		(end 142.125001 63.75)
		(width 0.2)
		(layer "F.Cu")
		(net 197)
	)
	(segment
		(start 142.125001 63.75)
		(end 141.6 63.75)
		(width 0.2)
		(layer "F.Cu")
		(net 197)
	)
	(segment
		(start 143.32 64)
		(end 143.295 64)
		(width 0.2)
		(layer "F.Cu")
		(net 197)
	)
	(segment
		(start 142.995 63.7)
		(end 142.175001 63.7)
		(width 0.2)
		(layer "F.Cu")
		(net 197)
	)
	(segment
		(start 143.295 64)
		(end 142.995 63.7)
		(width 0.2)
		(layer "F.Cu")
		(net 197)
	)
	(segment
		(start 142.175001 63.3)
		(end 142.125001 63.25)
		(width 0.2)
		(layer "F.Cu")
		(net 198)
	)
	(segment
		(start 142.125001 63.25)
		(end 141.6 63.25)
		(width 0.2)
		(layer "F.Cu")
		(net 198)
	)
	(segment
		(start 142.995 63.3)
		(end 142.175001 63.3)
		(width 0.2)
		(layer "F.Cu")
		(net 198)
	)
	(segment
		(start 143.295 63)
		(end 142.995 63.3)
		(width 0.2)
		(layer "F.Cu")
		(net 198)
	)
	(segment
		(start 143.32 63)
		(end 143.295 63)
		(width 0.2)
		(layer "F.Cu")
		(net 198)
	)
	(zone
		(net 118)
		(net_name "/Power/Ideal-diode-1/VIN")
		(layer "F.Cu")
		(hatch edge 0.5)
		(priority 5)
		(connect_pads yes
			(clearance 0.15)
		)
		(min_thickness 0.25)
		(filled_areas_thickness no)
		(fill yes
			(thermal_gap 0.5)
			(thermal_bridge_width 0.5)
		)
		(polygon
			(pts
				(xy 143.5 118) (xy 143.5 109) (xy 140 109) (xy 140 118)
			)
		)
	)
	(zone
		(net 187)
		(net_name "/USB-PD/12V_CONV")
		(layer "F.Cu")
		(hatch edge 0.5)
		(priority 16)
		(connect_pads yes
			(clearance 0.15)
		)
		(min_thickness 0.25)
		(filled_areas_thickness no)
		(fill yes
			(thermal_gap 0.5)
			(thermal_bridge_width 0.5)
		)
		(polygon
			(pts
				(xy 132.5 100) (xy 132.5 101.5) (xy 134 101.5) (xy 134 102.75) (xy 135 103.75) (xy 135 104.75) (xy 138.965 104.75)
				(xy 139.15 104.565) (xy 139.15 93.5) (xy 132 93.5) (xy 132 99.5)
			)
		)
	)
	(zone
		(net 66)
		(net_name "GND")
		(layer "F.Cu")
		(hatch edge 0.5)
		(priority 27)
		(connect_pads yes
			(clearance 0.15)
		)
		(min_thickness 0.25)
		(filled_areas_thickness no)
		(fill yes
			(thermal_gap 0.5)
			(thermal_bridge_width 0.5)
		)
		(polygon
			(pts
				(xy 158 123) (xy 148 123) (xy 148 98) (xy 158 98)
			)
		)
	)
	(zone
		(net 66)
		(net_name "GND")
		(layer "F.Cu")
		(hatch edge 0.5)
		(priority 12)
		(connect_pads yes
			(clearance 0.15)
		)
		(min_thickness 0.25)
		(filled_areas_thickness no)
		(fill yes
			(thermal_gap 0.5)
			(thermal_bridge_width 0.5)
		)
		(polygon
			(pts
				(xy 119 137.6) (xy 123.6 137.6) (xy 123.6 135.2) (xy 119 135.2)
			)
		)
	)
	(zone
		(net 116)
		(net_name "/Power/Ideal-diode-2/VIN")
		(layer "F.Cu")
		(hatch edge 0.5)
		(priority 6)
		(connect_pads yes
			(clearance 0.15)
		)
		(min_thickness 0.25)
		(filled_areas_thickness no)
		(fill yes
			(thermal_gap 0.5)
			(thermal_bridge_width 0.5)
		)
		(polygon
			(pts
				(xy 143.5 133.5) (xy 140 133.5) (xy 140 143) (xy 143.5 143)
			)
		)
	)
	(zone
		(net 66)
		(net_name "GND")
		(layer "F.Cu")
		(hatch edge 0.5)
		(priority 19)
		(connect_pads yes
			(clearance 0.15)
		)
		(min_thickness 0.25)
		(filled_areas_thickness no)
		(fill yes
			(thermal_gap 0.5)
			(thermal_bridge_width 0.5)
		)
		(polygon
			(pts
				(xy 137 86.5) (xy 133.25 86.5) (xy 133.25 89.75) (xy 133.65 89.75) (xy 133.7 89.75) (xy 139 89.75)
				(xy 139 91) (xy 140.25 91) (xy 140.25 91.398999) (xy 145.253 91.398999) (xy 145.253 92.918999) (xy 142.9 92.918999)
				(xy 142.9 93.5) (xy 139.301001 93.5) (xy 139.001001 93.25) (xy 138.5 93.25) (xy 131.75 93.25) (xy 131.5 93.5)
				(xy 131.5 99.5) (xy 130 99.5) (xy 130 76.5) (xy 132.5 74) (xy 137 74)
			)
		)
	)
	(zone
		(net 119)
		(net_name "/Power/VCC_PD")
		(layer "F.Cu")
		(hatch edge 0.5)
		(priority 15)
		(connect_pads yes
			(clearance 0.15)
		)
		(min_thickness 0.25)
		(filled_areas_thickness no)
		(fill yes
			(thermal_gap 0.5)
			(thermal_bridge_width 0.5)
		)
		(polygon
			(pts
				(xy 134 104.5) (xy 134 101.5) (xy 132.5 101.5) (xy 132.5 100) (xy 130.5 100) (xy 130.5 104.5)
			)
		)
	)
	(zone
		(net 168)
		(net_name "/Power/VCC_DC_CONN_1")
		(layer "F.Cu")
		(hatch edge 0.5)
		(priority 25)
		(connect_pads yes
			(clearance 0.15)
		)
		(min_thickness 0.25)
		(filled_areas_thickness no)
		(fill yes
			(thermal_gap 0.5)
			(thermal_bridge_width 0.5)
		)
		(polygon
			(pts
				(xy 148 123.5) (xy 146.5 123.5) (xy 146.5 125.5) (xy 144.5 125.5) (xy 144.5 117.5) (xy 143.5 116.5)
				(xy 143.5 115) (xy 143.5 111.5) (xy 145.25 111.5) (xy 145.25 108.5) (xy 148 108.5)
			)
		)
	)
	(zone
		(net 186)
		(net_name "/Power/3V3_CONV")
		(layer "F.Cu")
		(hatch edge 0.5)
		(priority 13)
		(connect_pads yes
			(clearance 0.15)
		)
		(min_thickness 0.25)
		(filled_areas_thickness no)
		(fill yes
			(thermal_gap 0.5)
			(thermal_bridge_width 0.5)
		)
		(polygon
			(pts
				(xy 116.8 138.6) (xy 123.4 138.6) (xy 124 138) (xy 127.764999 138) (xy 128 138.235001) (xy 128 140.55)
				(xy 127.25 141.3) (xy 116.8 141.3)
			)
		)
	)
	(zone
		(net 134)
		(net_name "+3V3")
		(layer "F.Cu")
		(hatch edge 0.5)
		(priority 14)
		(connect_pads yes
			(clearance 0.15)
		)
		(min_thickness 0.25)
		(filled_areas_thickness no)
		(fill yes
			(thermal_gap 0.5)
			(thermal_bridge_width 0.5)
		)
		(polygon
			(pts
				(xy 106 113) (xy 106 108.5) (xy 103 108.5) (xy 103 113)
			)
		)
	)
	(zone
		(net 113)
		(net_name "VBUS")
		(layer "F.Cu")
		(hatch edge 0.5)
		(priority 4)
		(connect_pads yes
			(clearance 0.15)
		)
		(min_thickness 0.25)
		(filled_areas_thickness no)
		(fill yes
			(thermal_gap 0.5)
			(thermal_bridge_width 0.5)
		)
		(polygon
			(pts
				(xy 141.31 37.751) (xy 141.31 44.2) (xy 149.2 44.2) (xy 150.6 45.6) (xy 152.6 45.6) (xy 152.6 42.2)
				(xy 152.325001 41.925001) (xy 147.113 41.925001) (xy 147 41.812001) (xy 147 37.8) (xy 146.2 37.8)
				(xy 145.35 38.65) (xy 145.35 41.2) (xy 142.7 41.2) (xy 142.7 37.827528)
			)
		)
	)
	(zone
		(net 66)
		(net_name "GND")
		(layer "F.Cu")
		(hatch edge 0.5)
		(priority 22)
		(connect_pads yes
			(clearance 0.15)
		)
		(min_thickness 0.25)
		(filled_areas_thickness no)
		(fill yes
			(thermal_gap 0.5)
			(thermal_bridge_width 0.5)
		)
		(polygon
			(pts
				(xy 154.8 42) (xy 157.4 42) (xy 157.4 34.4) (xy 154.8 34.4)
			)
		)
	)
	(zone
		(net 87)
		(net_name "+12V")
		(layer "F.Cu")
		(hatch edge 0.5)
		(priority 2)
		(connect_pads yes
			(clearance 0.15)
		)
		(min_thickness 0.25)
		(filled_areas_thickness no)
		(fill yes
			(thermal_gap 0.5)
			(thermal_bridge_width 0.5)
		)
		(polygon
			(pts
				(xy 133.6 114.5) (xy 140 114.5) (xy 140 117) (xy 137 117) (xy 137 139) (xy 140.5 139) (xy 140.5 142)
				(xy 133 142) (xy 132.5 141.5) (xy 132.5 133.6) (xy 125.6 133.6) (xy 125.6 131.8) (xy 126 131.4)
				(xy 132.5 131.4) (xy 132.5 125.5) (xy 129.25 122.25) (xy 116.4 122.25) (xy 116.4 118.8) (xy 120.4 118.8)
				(xy 120.9 119.3) (xy 127.55 119.3) (xy 127.55 104.95) (xy 133.6 104.95)
			)
		)
	)
	(zone
		(net 87)
		(net_name "+12V")
		(layer "F.Cu")
		(hatch edge 0.5)
		(priority 1)
		(connect_pads yes
			(clearance 0.15)
		)
		(min_thickness 0.25)
		(filled_areas_thickness no)
		(fill yes
			(thermal_gap 0.5)
			(thermal_bridge_width 0.5)
		)
		(polygon
			(pts
				(xy 109 118.85) (xy 113.1 118.85) (xy 113.1 121.35) (xy 109.8 121.35) (xy 109 120.55)
			)
		)
	)
	(zone
		(net 169)
		(net_name "/Power/VCC_DC_CONN_2")
		(layer "F.Cu")
		(hatch edge 0.5)
		(priority 3)
		(connect_pads yes
			(clearance 0.15)
		)
		(min_thickness 0.25)
		(filled_areas_thickness no)
		(fill yes
			(thermal_gap 0.5)
			(thermal_bridge_width 0.5)
		)
		(polygon
			(pts
				(xy 143.5 136.5) (xy 145.75 136.5) (xy 146.5 136.5) (xy 146.5 123.75) (xy 157.7 123.75) (xy 157.7 144.5)
				(xy 147 144.5) (xy 146 143.5) (xy 146 141) (xy 145 140) (xy 143.5 140)
			)
		)
	)
	(zone
		(net 143)
		(net_name "/USB-PD/12V_SW")
		(layer "F.Cu")
		(hatch edge 0.5)
		(priority 20)
		(connect_pads yes
			(clearance 0.15)
		)
		(min_thickness 0.25)
		(filled_areas_thickness no)
		(fill yes
			(thermal_gap 0.5)
			(thermal_bridge_width 0.5)
		)
		(polygon
			(pts
				(xy 141.3 93.7) (xy 141.3 104.7) (xy 144.1 104.7) (xy 144.1 96.9) (xy 142.9 95.7) (xy 142.9 93.7)
			)
		)
	)
	(zone
		(net 66)
		(net_name "GND")
		(layer "F.Cu")
		(hatch edge 0.5)
		(priority 10)
		(connect_pads yes
			(clearance 0.15)
		)
		(min_thickness 0.25)
		(filled_areas_thickness no)
		(fill yes
			(thermal_gap 0.5)
			(thermal_bridge_width 0.5)
		)
		(polygon
			(pts
				(xy 124.4 131) (xy 124.4 130.4) (xy 126 128.8) (xy 132 128.8) (xy 132 127.4) (xy 123 127.4) (xy 123 131)
			)
		)
	)
	(zone
		(net 134)
		(net_name "+3V3")
		(layer "F.Cu")
		(hatch edge 0.5)
		(priority 17)
		(connect_pads yes
			(clearance 0.15)
		)
		(min_thickness 0.25)
		(filled_areas_thickness no)
		(fill yes
			(thermal_gap 0.5)
			(thermal_bridge_width 0.5)
		)
		(polygon
			(pts
				(xy 118 138.5) (xy 112.5 138.5) (xy 112.5 135) (xy 118 135) (xy 118 138.5) (xy 118 138.3)
			)
		)
	)
	(zone
		(net 134)
		(net_name "+3V3")
		(layer "F.Cu")
		(hatch edge 0.5)
		(priority 7)
		(connect_pads yes
			(clearance 0.15)
		)
		(min_thickness 0.25)
		(filled_areas_thickness no)
		(fill yes
			(thermal_gap 0.5)
			(thermal_bridge_width 0.5)
		)
		(polygon
			(pts
				(xy 108.9 111.8) (xy 112.8 111.8) (xy 112.8 113) (xy 113.6 113.8) (xy 113.6 114.4) (xy 109.9 114.4)
				(xy 108.9 113.4)
			)
		)
	)
	(zone
		(net 66)
		(net_name "GND")
		(layer "F.Cu")
		(hatch edge 0.5)
		(priority 18)
		(connect_pads yes
			(clearance 0.15)
		)
		(min_thickness 0.25)
		(filled_areas_thickness no)
		(fill yes
			(thermal_gap 0.5)
			(thermal_bridge_width 0.5)
		)
		(polygon
			(pts
				(xy 123 107) (xy 127.25 107) (xy 127.25 119) (xy 123 119)
			)
		)
	)
	(zone
		(net 168)
		(net_name "/Power/VCC_DC_CONN_1")
		(layer "F.Cu")
		(hatch edge 0.5)
		(priority 22)
		(connect_pads yes
			(clearance 0.15)
		)
		(min_thickness 0.25)
		(filled_areas_thickness no)
		(fill yes
			(thermal_gap 0.5)
			(thermal_bridge_width 0.5)
		)
		(polygon
			(pts
				(xy 152.1 42) (xy 154.7 42) (xy 154.7 34.4) (xy 152.1 34.4)
			)
		)
	)
	(zone
		(net 115)
		(net_name "/USB-PD/VCC")
		(layer "F.Cu")
		(hatch edge 0.5)
		(priority 23)
		(connect_pads yes
			(clearance 0.15)
		)
		(min_thickness 0.25)
		(filled_areas_thickness no)
		(fill yes
			(thermal_gap 0.5)
			(thermal_bridge_width 0.5)
		)
		(polygon
			(pts
				(xy 158.25 65.15) (xy 154 69.4) (xy 154 76.9) (xy 151.4 79.5) (xy 144.25 79.5) (xy 144.25 86.25)
				(xy 143.75 86.75) (xy 140.75 86.75) (xy 140.75 89.75) (xy 141 89.999998) (xy 143.853 89.999998)
				(xy 143.853 91.398999) (xy 140.25 91.398999) (xy 140.25 91) (xy 139 91) (xy 139 89.5) (xy 133.5 89.5)
				(xy 133.5 87) (xy 138.25 87) (xy 138.25 74) (xy 144.25 74) (xy 149 74) (xy 150 73) (xy 150 65.8)
				(xy 155.7 60.1) (xy 155.7 46.1) (xy 152.9 46.1) (xy 152.9 43.4) (xy 158.25 43.4)
			)
		)
	)
	(zone
		(net 66)
		(net_name "GND")
		(layer "F.Cu")
		(hatch edge 0.5)
		(priority 21)
		(connect_pads yes
			(clearance 0.15)
		)
		(min_thickness 0.25)
		(filled_areas_thickness no)
		(fill yes
			(thermal_gap 0.5)
			(thermal_bridge_width 0.5)
		)
		(polygon
			(pts
				(xy 141.3 37.925) (xy 140.7 37.925) (xy 140.7 39.263) (xy 140.711 39.274) (xy 140.511 39.474) (xy 138.711 39.474)
				(xy 138.711 41.874) (xy 141.3 41.874001)
			)
		)
	)
	(zone
		(net 66)
		(net_name "GND")
		(layer "F.Cu")
		(hatch edge 0.5)
		(priority 21)
		(connect_pads yes
			(clearance 0.15)
		)
		(min_thickness 0.25)
		(filled_areas_thickness no)
		(fill yes
			(thermal_gap 0.5)
			(thermal_bridge_width 0.5)
		)
		(polygon
			(pts
				(xy 147.113 37.975999) (xy 147.713 37.976) (xy 147.713 39.314) (xy 147.702 39.324999) (xy 147.802 39.425)
				(xy 149.702 39.425) (xy 149.702001 41.625) (xy 147.113 41.625001)
			)
		)
	)
	(zone
		(net 86)
		(net_name "/Power/3V3_SW")
		(layer "F.Cu")
		(hatch edge 0.5)
		(priority 9)
		(connect_pads yes
			(clearance 0.15)
		)
		(min_thickness 0.25)
		(filled_areas_thickness no)
		(fill yes
			(thermal_gap 0.5)
			(thermal_bridge_width 0.5)
		)
		(polygon
			(pts
				(xy 123.8 137) (xy 128 137) (xy 128 134) (xy 127.2 134) (xy 127.1 134.1) (xy 127.1 134.8) (xy 126.7 135.2)
				(xy 125.2 135.2) (xy 124.8 134.8) (xy 124 134.8) (xy 123.8 135)
			)
		)
	)
	(zone
		(net 66)
		(net_name "GND")
		(layer "F.Cu")
		(hatch edge 0.5)
		(priority 11)
		(connect_pads yes
			(clearance 0.15)
		)
		(min_thickness 0.25)
		(filled_areas_thickness no)
		(fill yes
			(thermal_gap 0.5)
			(thermal_bridge_width 0.5)
		)
		(polygon
			(pts
				(xy 122.6 134) (xy 124.8 134) (xy 124.8 132) (xy 122.6 132)
			)
		)
	)
	(zone
		(net 66)
		(net_name "GND")
		(layers "F.Cu" "B.Cu")
		(hatch edge 0.5)
		(priority 8)
		(connect_pads yes
			(clearance 0.15)
		)
		(min_thickness 0.25)
		(filled_areas_thickness no)
		(fill yes
			(thermal_gap 0.5)
			(thermal_bridge_width 0.5)
		)
		(polygon
			(pts
				(xy 103.6 164) (xy 103.6 33) (xy 157.6 33) (xy 157.6 163.4) (xy 96 163.4) (xy 96 167) (xy 162.4 167)
				(xy 162.5 29) (xy 97 29) (xy 96 30) (xy 96 164)
			)
		)
	)
	(zone
		(net 66)
		(net_name "GND")
		(layer "B.Cu")
		(hatch edge 0.5)
		(priority 29)
		(connect_pads yes
			(clearance 0.15)
		)
		(min_thickness 0.25)
		(filled_areas_thickness no)
		(fill yes
			(thermal_gap 0.5)
			(thermal_bridge_width 0.5)
		)
		(polygon
			(pts
				(xy 124.2 137.6) (xy 124.2 134.6) (xy 124.8 134) (xy 124.8 130.4) (xy 132 130.4) (xy 132 127.4)
				(xy 120.4 127.4) (xy 119 128.8) (xy 119 137.6)
			)
		)
	)
	(zone
		(net 66)
		(net_name "GND")
		(layer "B.Cu")
		(hatch edge 0.5)
		(priority 28)
		(connect_pads
			(clearance 0.15)
		)
		(min_thickness 0.25)
		(filled_areas_thickness no)
		(fill yes
			(thermal_gap 0.5)
			(thermal_bridge_width 0.5)
		)
		(polygon
			(pts
				(xy 129.6 84) (xy 129.6 96) (xy 143.6 96) (xy 145.6 98) (xy 150.3 98) (xy 150.3 80) (xy 133.6 80)
			)
		)
	)
	(zone
		(net 168)
		(net_name "/Power/VCC_DC_CONN_1")
		(layer "B.Cu")
		(hatch edge 0.5)
		(priority 26)
		(connect_pads yes
			(clearance 0.15)
		)
		(min_thickness 0.25)
		(filled_areas_thickness no)
		(fill yes
			(thermal_gap 0.5)
			(thermal_bridge_width 0.5)
		)
		(polygon
			(pts
				(xy 154.8 34.4) (xy 154.8 39.8) (xy 157.8 42.8) (xy 157.5 115.15) (xy 145.1 115.15) (xy 145.1 106.7)
				(xy 151.4 100.4) (xy 151.4 62.4) (xy 154.6 59.2) (xy 154.6 48.6) (xy 152 46) (xy 152 34.4)
			)
		)
	)
	(zone
		(net 134)
		(net_name "+3V3")
		(layer "B.Cu")
		(hatch edge 0.5)
		(priority 24)
		(connect_pads yes
			(clearance 0.15)
		)
		(min_thickness 0.25)
		(filled_areas_thickness no)
		(fill yes
			(thermal_gap 0.5)
			(thermal_bridge_width 0.5)
		)
		(polygon
			(pts
				(xy 103.15 108.5) (xy 106 108.5) (xy 106 113) (xy 116.5 123.5) (xy 116.5 138.5) (xy 112.5 138.5)
				(xy 112.5 128) (xy 103.15 118.65)
			)
		)
	)
	(zone
		(net 66)
		(net_name "GND")
		(layers "In1.Cu" "In2.Cu")
		(hatch edge 0.5)
		(connect_pads yes
			(clearance 0.125)
		)
		(min_thickness 0.125)
		(filled_areas_thickness no)
		(fill yes
			(thermal_gap 0.2)
			(thermal_bridge_width 0.5)
			(smoothing fillet)
			(radius 0.2)
		)
		(polygon
			(pts
				(xy 95.849 27.849999) (xy 95.849 169.150001) (xy 172.899 169.150001) (xy 172.899001 27.849999)
			)
		)
	)
)
